(kicad_pcb
	(version 20241229)
	(generator "pcbnew")
	(generator_version "9.0")
	(general
		(thickness 1.258)
		(legacy_teardrops no)
	)
	(paper "A4")
	(title_block
		(date "2024-05-27")
		(rev "1.1.2")
	)
	(layers
		(0 "F.Cu" signal)
		(4 "In1.Cu" power)
		(6 "In2.Cu" power)
		(8 "In3.Cu" signal)
		(10 "In4.Cu" signal)
		(2 "B.Cu" signal)
		(9 "F.Adhes" user "F.Adhesive")
		(11 "B.Adhes" user "B.Adhesive")
		(13 "F.Paste" user)
		(15 "B.Paste" user)
		(5 "F.SilkS" user "F.Silkscreen")
		(7 "B.SilkS" user "B.Silkscreen")
		(1 "F.Mask" user)
		(3 "B.Mask" user)
		(17 "Dwgs.User" user "User.Drawings")
		(19 "Cmts.User" user "User.Comments")
		(21 "Eco1.User" user "User.Eco1")
		(23 "Eco2.User" user "User.Eco2")
		(25 "Edge.Cuts" user)
		(27 "Margin" user)
		(31 "F.CrtYd" user "F.Courtyard")
		(29 "B.CrtYd" user "B.Courtyard")
		(35 "F.Fab" user)
		(33 "B.Fab" user)
	)
	(setup
		(stackup
			(layer "F.SilkS"
				(type "Top Silk Screen")
			)
			(layer "F.Paste"
				(type "Top Solder Paste")
			)
			(layer "F.Mask"
				(type "Top Solder Mask")
				(thickness 0.01)
			)
			(layer "F.Cu"
				(type "copper")
				(thickness 0.018)
			)
			(layer "dielectric 1"
				(type "prepreg")
				(thickness 0.11)
				(material "FR4")
				(epsilon_r 4.3)
				(loss_tangent 0.02)
			)
			(layer "In1.Cu"
				(type "copper")
				(thickness 0.018)
			)
			(layer "dielectric 2"
				(type "core")
				(thickness 0.4)
				(material "FR4")
				(epsilon_r 4.3)
				(loss_tangent 0.02)
			)
			(layer "In2.Cu"
				(type "copper")
				(thickness 0.018)
			)
			(layer "dielectric 3"
				(type "prepreg")
				(thickness 0.11)
				(material "FR4")
				(epsilon_r 4.3)
				(loss_tangent 0.02)
			)
			(layer "In3.Cu"
				(type "copper")
				(thickness 0.018)
			)
			(layer "dielectric 4"
				(type "core")
				(thickness 0.4)
				(material "FR4")
				(epsilon_r 4.3)
				(loss_tangent 0.02)
			)
			(layer "In4.Cu"
				(type "copper")
				(thickness 0.018)
			)
			(layer "dielectric 5"
				(type "prepreg")
				(thickness 0.11)
				(material "FR4")
				(epsilon_r 4.3)
				(loss_tangent 0.02)
			)
			(layer "B.Cu"
				(type "copper")
				(thickness 0.018)
			)
			(layer "B.Mask"
				(type "Bottom Solder Mask")
				(thickness 0.01)
			)
			(layer "B.Paste"
				(type "Bottom Solder Paste")
			)
			(layer "B.SilkS"
				(type "Bottom Silk Screen")
			)
			(copper_finish "None")
			(dielectric_constraints no)
		)
		(pad_to_mask_clearance 0.05)
		(allow_soldermask_bridges_in_footprints no)
		(tenting front back)
		(pcbplotparams
			(layerselection 0x00000000_00000000_55555555_5755f5ff)
			(plot_on_all_layers_selection 0x00000000_00000000_00000000_00000000)
			(disableapertmacros no)
			(usegerberextensions no)
			(usegerberattributes yes)
			(usegerberadvancedattributes yes)
			(creategerberjobfile yes)
			(dashed_line_dash_ratio 12.000000)
			(dashed_line_gap_ratio 3.000000)
			(svgprecision 6)
			(plotframeref no)
			(mode 1)
			(useauxorigin no)
			(hpglpennumber 1)
			(hpglpenspeed 20)
			(hpglpendiameter 15.000000)
			(pdf_front_fp_property_popups yes)
			(pdf_back_fp_property_popups yes)
			(pdf_metadata yes)
			(pdf_single_document no)
			(dxfpolygonmode yes)
			(dxfimperialunits yes)
			(dxfusepcbnewfont yes)
			(psnegative no)
			(psa4output no)
			(plot_black_and_white yes)
			(sketchpadsonfab no)
			(plotpadnumbers no)
			(hidednponfab no)
			(sketchdnponfab yes)
			(crossoutdnponfab yes)
			(subtractmaskfromsilk no)
			(outputformat 1)
			(mirror no)
			(drillshape 0)
			(scaleselection 1)
			(outputdirectory "./fab")
		)
	)
	(net 0 "")
	(net 1 "GND")
	(net 2 "VDDQ")
	(net 3 "RESET_N")
	(net 4 "Net-(D1-Pad1)")
	(net 5 "Net-(D2-Pad1)")
	(net 6 "Net-(D3-Pad1)")
	(net 7 "Net-(D4-Pad1)")
	(net 8 "Net-(IC1-P0)")
	(net 9 "Net-(IC1-P1)")
	(net 10 "Net-(IC1-P2)")
	(net 11 "Net-(IC1-P3)")
	(net 12 "SDA")
	(net 13 "SCL")
	(net 14 "Net-(IC1-P4)")
	(net 15 "Net-(IC1-P5)")
	(net 16 "unconnected-(IC1-P6-Pad11)")
	(net 17 "CS_N")
	(net 18 "VDD")
	(net 19 "VPP")
	(net 20 "DQ3")
	(net 21 "DQ2")
	(net 22 "CA1")
	(net 23 "DQ1")
	(net 24 "CA0")
	(net 25 "DQ0")
	(net 26 "DQS_P")
	(net 27 "DQS_N")
	(net 28 "DQ7")
	(net 29 "DQ6")
	(net 30 "DQ5")
	(net 31 "DQ4")
	(net 32 "CA10")
	(net 33 "CA11")
	(net 34 "CA12")
	(net 35 "CA13")
	(net 36 "LBDQS")
	(net 37 "TDQS_P")
	(net 38 "LBDQ")
	(net 39 "TDQS_N")
	(net 40 "CA6")
	(net 41 "CA7")
	(net 42 "CLK_P")
	(net 43 "CA8")
	(net 44 "CLK_N")
	(net 45 "CA9")
	(net 46 "CA2")
	(net 47 "CA3")
	(net 48 "CA4")
	(net 49 "CA5")
	(net 50 "1V8_SYS")
	(net 51 "1V1_SYS")
	(net 52 "/EEPROM/VDD_LED")
	(net 53 "ALERT_N")
	(net 54 "TEN")
	(net 55 "OTD_CA_A")
	(net 56 "CAI")
	(net 57 "MIR")
	(net 58 "/DDR5/R_ODT_CA_A")
	(net 59 "/DDR5/R_ALERT_N")
	(net 60 "/DDR5/R_RESET_N")
	(net 61 "/DDR5/ZQ")
	(net 62 "/DDR5/R_CAI")
	(net 63 "/DDR5/R_MIR")
	(net 64 "/DDR5/R_TEN")
	(net 65 "/DDR5/R_LBDQ")
	(net 66 "/DDR5/R_LBDQS")
	(net 67 "unconnected-(IC1-P7-Pad12)")
	(net 68 "unconnected-(IC1-~{INT}-Pad13)")
	(net 69 "Net-(U2-SW)")
	(net 70 "unconnected-(J1-Pad51)")
	(net 71 "unconnected-(J1-Pad52)")
	(net 72 "unconnected-(J1-Pad53)")
	(net 73 "unconnected-(J1-Pad54)")
	(net 74 "unconnected-(J1-Pad55)")
	(net 75 "unconnected-(J1-Pad56)")
	(net 76 "unconnected-(J1-Pad57)")
	(net 77 "unconnected-(J1-Pad58)")
	(net 78 "unconnected-(J1-Pad59)")
	(net 79 "unconnected-(J1-Pad60)")
	(net 80 "unconnected-(J1-Pad61)")
	(net 81 "unconnected-(J1-Pad62)")
	(net 82 "unconnected-(J1-Pad63)")
	(net 83 "unconnected-(J1-Pad64)")
	(net 84 "unconnected-(J1-Pad65)")
	(net 85 "unconnected-(J1-Pad66)")
	(net 86 "unconnected-(J1-Pad67)")
	(net 87 "unconnected-(J1-Pad68)")
	(net 88 "unconnected-(J1-Pad69)")
	(net 89 "unconnected-(J1-Pad70)")
	(net 90 "unconnected-(J1-Pad71)")
	(net 91 "unconnected-(J1-Pad72)")
	(net 92 "unconnected-(J1-Pad73)")
	(net 93 "unconnected-(J1-Pad74)")
	(net 94 "unconnected-(J1-Pad75)")
	(net 95 "unconnected-(J1-Pad76)")
	(net 96 "unconnected-(J1-Pad77)")
	(net 97 "unconnected-(J1-Pad78)")
	(net 98 "unconnected-(J1-Pad79)")
	(net 99 "unconnected-(J1-Pad80)")
	(net 100 "unconnected-(J1-Pad81)")
	(net 101 "unconnected-(J1-Pad82)")
	(net 102 "unconnected-(J1-Pad83)")
	(net 103 "unconnected-(J1-Pad84)")
	(net 104 "unconnected-(J1-Pad85)")
	(net 105 "unconnected-(J1-Pad86)")
	(net 106 "unconnected-(J1-Pad87)")
	(net 107 "unconnected-(J1-Pad88)")
	(net 108 "unconnected-(J1-Pad89)")
	(net 109 "unconnected-(J1-Pad90)")
	(net 110 "unconnected-(J1-Pad91)")
	(net 111 "unconnected-(J1-Pad92)")
	(net 112 "unconnected-(J1-Pad94)")
	(net 113 "unconnected-(J1-Pad96)")
	(net 114 "unconnected-(J1-Pad98)")
	(net 115 "unconnected-(J1-Pad100)")
	(net 116 "unconnected-(J1-Pad102)")
	(net 117 "unconnected-(J1-Pad104)")
	(net 118 "unconnected-(J1-Pad106)")
	(net 119 "unconnected-(J1-Pad108)")
	(net 120 "unconnected-(J1-Pad109)")
	(net 121 "unconnected-(J1-Pad110)")
	(net 122 "unconnected-(J1-Pad111)")
	(net 123 "unconnected-(J1-Pad112)")
	(net 124 "unconnected-(J1-Pad113)")
	(net 125 "unconnected-(J1-Pad114)")
	(net 126 "unconnected-(J1-Pad115)")
	(net 127 "unconnected-(J1-Pad117)")
	(net 128 "unconnected-(J1-Pad119)")
	(net 129 "unconnected-(J1-Pad121)")
	(net 130 "unconnected-(J1-Pad123)")
	(net 131 "unconnected-(J1-Pad125)")
	(net 132 "unconnected-(J1-Pad126)")
	(net 133 "unconnected-(J1-Pad128)")
	(net 134 "unconnected-(J1-Pad130)")
	(net 135 "unconnected-(J1-Pad131)")
	(net 136 "unconnected-(J1-Pad132)")
	(net 137 "unconnected-(J1-Pad133)")
	(net 138 "unconnected-(J1-Pad134)")
	(net 139 "unconnected-(J1-Pad135)")
	(net 140 "unconnected-(J1-Pad136)")
	(net 141 "unconnected-(J1-Pad137)")
	(net 142 "unconnected-(J1-Pad138)")
	(net 143 "unconnected-(J1-Pad139)")
	(net 144 "unconnected-(J1-Pad140)")
	(net 145 "unconnected-(J1-Pad141)")
	(net 146 "unconnected-(J1-Pad142)")
	(net 147 "unconnected-(J1-Pad143)")
	(net 148 "unconnected-(J1-Pad144)")
	(net 149 "unconnected-(J1-Pad145)")
	(net 150 "unconnected-(J1-Pad146)")
	(net 151 "unconnected-(J1-Pad147)")
	(net 152 "unconnected-(J1-Pad148)")
	(net 153 "unconnected-(J1-Pad149)")
	(net 154 "unconnected-(J1-Pad150)")
	(net 155 "unconnected-(J1-Pad151)")
	(net 156 "unconnected-(J1-Pad152)")
	(net 157 "unconnected-(J1-Pad153)")
	(net 158 "unconnected-(J1-Pad155)")
	(net 159 "unconnected-(J1-Pad157)")
	(net 160 "unconnected-(J1-Pad159)")
	(net 161 "unconnected-(J1-Pad170)")
	(net 162 "unconnected-(J1-Pad172)")
	(net 163 "unconnected-(J1-Pad174)")
	(net 164 "unconnected-(J1-Pad176)")
	(net 165 "unconnected-(J1-Pad188)")
	(net 166 "unconnected-(J1-Pad190)")
	(net 167 "unconnected-(J1-Pad202)")
	(net 168 "unconnected-(J1-Pad204)")
	(net 169 "unconnected-(J1-Pad208)")
	(net 170 "unconnected-(J1-Pad212)")
	(net 171 "unconnected-(J1-Pad213)")
	(net 172 "unconnected-(J1-Pad214)")
	(net 173 "unconnected-(J1-Pad215)")
	(net 174 "unconnected-(J1-Pad216)")
	(net 175 "unconnected-(J1-Pad217)")
	(net 176 "unconnected-(J1-Pad218)")
	(net 177 "unconnected-(J1-Pad219)")
	(net 178 "unconnected-(J1-Pad220)")
	(net 179 "unconnected-(J1-Pad221)")
	(net 180 "unconnected-(J1-Pad222)")
	(net 181 "unconnected-(J1-Pad223)")
	(net 182 "unconnected-(J1-Pad224)")
	(net 183 "unconnected-(J1-Pad225)")
	(net 184 "unconnected-(J1-Pad226)")
	(net 185 "unconnected-(J1-Pad227)")
	(net 186 "unconnected-(J1-Pad228)")
	(net 187 "unconnected-(J1-Pad229)")
	(net 188 "unconnected-(J1-Pad230)")
	(net 189 "unconnected-(J1-Pad231)")
	(net 190 "unconnected-(J1-Pad232)")
	(net 191 "unconnected-(J1-Pad233)")
	(net 192 "unconnected-(J1-Pad234)")
	(net 193 "unconnected-(J1-Pad235)")
	(net 194 "unconnected-(J1-Pad236)")
	(net 195 "unconnected-(J1-Pad237)")
	(net 196 "unconnected-(J1-Pad238)")
	(net 197 "unconnected-(J1-Pad239)")
	(net 198 "unconnected-(J1-Pad240)")
	(net 199 "unconnected-(J1-Pad241)")
	(net 200 "unconnected-(J1-Pad242)")
	(net 201 "unconnected-(J1-Pad243)")
	(net 202 "unconnected-(J1-Pad244)")
	(net 203 "unconnected-(J1-Pad245)")
	(net 204 "unconnected-(J1-Pad246)")
	(net 205 "unconnected-(J1-Pad247)")
	(net 206 "unconnected-(J1-Pad248)")
	(net 207 "unconnected-(J1-Pad249)")
	(net 208 "unconnected-(J1-Pad250)")
	(net 209 "unconnected-(J1-Pad251)")
	(net 210 "unconnected-(J1-Pad252)")
	(net 211 "unconnected-(J1-Pad253)")
	(net 212 "unconnected-(J1-Pad254)")
	(net 213 "unconnected-(J1-Pad255)")
	(net 214 "unconnected-(J1-Pad256)")
	(net 215 "unconnected-(J1-Pad257)")
	(net 216 "unconnected-(J1-Pad258)")
	(net 217 "unconnected-(J1-Pad259)")
	(net 218 "unconnected-(J1-Pad260)")
	(net 219 "unconnected-(U1-DNU-PadA1)")
	(net 220 "unconnected-(U1-DNU-PadA11)")
	(net 221 "unconnected-(U1-DNU-PadN1)")
	(net 222 "unconnected-(U1-DNU-PadN11)")
	(net 223 "unconnected-(U2-NC-Pad3)")
	(net 224 "unconnected-(U2-NC-Pad5)")
	(footprint "antmicro-footprints:antmicro-logo_scaled_20mm"
		(layer "F.Cu")
		(at 112.225 74.9)
		(property "Reference" "N1"
			(at 0.05 -5.5 0)
			(layer "F.SilkS")
			(hide yes)
			(effects
				(font
					(size 0.7 0.7)
					(thickness 0.15)
				)
				(justify left bottom)
			)
		)
		(property "Value" "antmicro_logo"
			(at -0.101 5.099 0)
			(layer "F.SilkS")
			(hide yes)
			(effects
				(font
					(size 0.7 0.7)
					(thickness 0.15)
				)
				(justify left bottom)
			)
		)
		(property "Author" "Antmicro"
			(at 0 0 0)
			(layer "F.Fab")
			(hide yes)
			(effects
				(font
					(size 1 1)
					(thickness 0.15)
				)
			)
		)
		(property "License" "Apache-2.0"
			(at 0 0 0)
			(layer "F.Fab")
			(hide yes)
			(effects
				(font
					(size 1 1)
					(thickness 0.15)
				)
			)
		)
		(property "MPN" ""
			(at 0 0 0)
			(layer "F.Fab")
			(hide yes)
			(effects
				(font
					(size 1 1)
					(thickness 0.15)
				)
			)
		)
		(property "Manufacturer" ""
			(at 0 0 0)
			(layer "F.Fab")
			(hide yes)
			(effects
				(font
					(size 1 1)
					(thickness 0.15)
				)
			)
		)
		(sheetfile "ddr5-testbed.kicad_sch")
		(attr allow_soldermask_bridges)
		(fp_poly
			(pts
				(xy 5.212 0.944) (xy 4.834 0.944) (xy 4.834 -1.292) (xy 5.212 -1.292) (xy 5.212 0.944)
			)
			(stroke
				(width 0.00186)
				(type solid)
			)
			(fill yes)
			(layer "F.Cu")
		)
		(fp_poly
			(pts
				(xy 8.164 -1.321) (xy 8.193 -1.317) (xy 8.204 -1.31) (xy 8.204 -1.308) (xy 8.2 -1.285) (xy 8.188 -1.24)
				(xy 8.171 -1.181) (xy 8.163 -1.156) (xy 8.142 -1.092) (xy 8.126 -1.053) (xy 8.112 -1.034) (xy 8.097 -1.031)
				(xy 8.094 -1.032) (xy 7.996 -1.053) (xy 7.886 -1.06) (xy 7.778 -1.053) (xy 7.683 -1.032) (xy 7.665 -1.026)
				(xy 7.622 -1.009) (xy 7.622 0.944) (xy 7.244 0.944) (xy 7.244 -1.178) (xy 7.358 -1.219) (xy 7.457 -1.253)
				(xy 7.548 -1.277) (xy 7.639 -1.295) (xy 7.738 -1.307) (xy 7.856 -1.315) (xy 7.94 -1.319) (xy 8.042 -1.322)
				(xy 8.115 -1.322) (xy 8.164 -1.321)
			)
			(stroke
				(width 0.00186)
				(type solid)
			)
			(fill yes)
			(layer "F.Cu")
		)
		(fp_poly
			(pts
				(xy 0.795 -1.891) (xy 0.798 -1.849) (xy 0.8 -1.786) (xy 0.802 -1.705) (xy 0.803 -1.612) (xy 0.803 -1.599)
				(xy 0.803 -1.292) (xy 1.181 -1.292) (xy 1.181 -1.04) (xy 0.803 -1.04) (xy 0.803 0.498) (xy 0.838 0.566)
				(xy 0.885 0.631) (xy 0.944 0.671) (xy 1.021 0.688) (xy 1.082 0.689) (xy 1.181 0.685) (xy 1.181 0.806)
				(xy 1.178 0.88) (xy 1.17 0.926) (xy 1.161 0.939) (xy 1.138 0.945) (xy 1.09 0.95) (xy 1.028 0.954)
				(xy 0.984 0.956) (xy 0.897 0.957) (xy 0.832 0.953) (xy 0.778 0.942) (xy 0.743 0.931) (xy 0.647 0.886)
				(xy 0.571 0.823) (xy 0.508 0.737) (xy 0.488 0.701) (xy 0.433 0.593) (xy 0.428 -0.223) (xy 0.424 -1.04)
				(xy 0.173 -1.04) (xy 0.173 -1.292) (xy 0.425 -1.292) (xy 0.425 -1.795) (xy 0.603 -1.85) (xy 0.673 -1.872)
				(xy 0.733 -1.89) (xy 0.774 -1.902) (xy 0.792 -1.906) (xy 0.795 -1.891)
			)
			(stroke
				(width 0.00186)
				(type solid)
			)
			(fill yes)
			(layer "F.Cu")
		)
		(fp_poly
			(pts
				(xy -0.82 -1.315) (xy -0.737 -1.312) (xy -0.672 -1.308) (xy -0.621 -1.301) (xy -0.577 -1.291) (xy -0.56 -1.286)
				(xy -0.417 -1.232) (xy -0.302 -1.164) (xy -0.212 -1.082) (xy -0.154 -0.996) (xy -0.135 -0.961) (xy -0.119 -0.927)
				(xy -0.105 -0.893) (xy -0.094 -0.855) (xy -0.085 -0.811) (xy -0.078 -0.758) (xy -0.073 -0.693) (xy -0.069 -0.612)
				(xy -0.067 -0.515) (xy -0.065 -0.397) (xy -0.064 -0.256) (xy -0.064 -0.088) (xy -0.063 0.105) (xy -0.063 0.944)
				(xy -0.441 0.944) (xy -0.441 0.113) (xy -0.442 -0.083) (xy -0.442 -0.25) (xy -0.443 -0.391) (xy -0.445 -0.508)
				(xy -0.448 -0.604) (xy -0.452 -0.682) (xy -0.457 -0.744) (xy -0.465 -0.794) (xy -0.474 -0.833) (xy -0.486 -0.864)
				(xy -0.501 -0.89) (xy -0.518 -0.913) (xy -0.538 -0.937) (xy -0.539 -0.939) (xy -0.604 -0.997) (xy -0.684 -1.039)
				(xy -0.784 -1.066) (xy -0.822 -1.072) (xy -0.927 -1.078) (xy -1.044 -1.073) (xy -1.158 -1.056) (xy -1.24 -1.034)
				(xy -1.3 -1.013) (xy -1.304 -0.034) (xy -1.308 0.944) (xy -1.686 0.944) (xy -1.686 -1.178) (xy -1.54 -1.225)
				(xy -1.44 -1.257) (xy -1.354 -1.28) (xy -1.276 -1.297) (xy -1.195 -1.307) (xy -1.105 -1.313) (xy -0.995 -1.315)
				(xy -0.93 -1.315) (xy -0.82 -1.315)
			)
			(stroke
				(width 0.00186)
				(type solid)
			)
			(fill yes)
			(layer "F.Cu")
		)
		(fp_poly
			(pts
				(xy 3.757 -1.312) (xy 3.91 -1.278) (xy 4.043 -1.223) (xy 4.153 -1.146) (xy 4.24 -1.047) (xy 4.282 -0.977)
				(xy 4.299 -0.943) (xy 4.313 -0.91) (xy 4.325 -0.876) (xy 4.335 -0.837) (xy 4.343 -0.791) (xy 4.349 -0.734)
				(xy 4.353 -0.665) (xy 4.357 -0.581) (xy 4.359 -0.478) (xy 4.361 -0.354) (xy 4.361 -0.206) (xy 4.362 -0.031)
				(xy 4.362 0.111) (xy 4.362 0.944) (xy 3.985 0.944) (xy 3.98 0.074) (xy 3.976 -0.796) (xy 3.93 -0.879)
				(xy 3.867 -0.961) (xy 3.786 -1.022) (xy 3.691 -1.062) (xy 3.586 -1.079) (xy 3.476 -1.074) (xy 3.366 -1.045)
				(xy 3.26 -0.994) (xy 3.185 -0.938) (xy 3.118 -0.88) (xy 3.118 0.944) (xy 2.74 0.944) (xy 2.74 0.092)
				(xy 2.739 -0.122) (xy 2.739 -0.305) (xy 2.737 -0.459) (xy 2.735 -0.585) (xy 2.732 -0.683) (xy 2.729 -0.755)
				(xy 2.725 -0.802) (xy 2.722 -0.821) (xy 2.679 -0.91) (xy 2.613 -0.981) (xy 2.523 -1.034) (xy 2.413 -1.067)
				(xy 2.284 -1.079) (xy 2.154 -1.073) (xy 2.082 -1.064) (xy 2.031 -1.056) (xy 1.989 -1.046) (xy 1.944 -1.031)
				(xy 1.917 -1.021) (xy 1.874 -1.005) (xy 1.874 0.944) (xy 1.511 0.944) (xy 1.511 -1.18) (xy 1.661 -1.228)
				(xy 1.83 -1.276) (xy 1.988 -1.306) (xy 2.148 -1.319) (xy 2.314 -1.319) (xy 2.448 -1.311) (xy 2.557 -1.297)
				(xy 2.649 -1.272) (xy 2.732 -1.237) (xy 2.811 -1.189) (xy 2.843 -1.165) (xy 2.947 -1.087) (xy 3.012 -1.14)
				(xy 3.14 -1.224) (xy 3.283 -1.283) (xy 3.443 -1.315) (xy 3.582 -1.323) (xy 3.757 -1.312)
			)
			(stroke
				(width 0.00186)
				(type solid)
			)
			(fill yes)
			(layer "F.Cu")
		)
		(fp_poly
			(pts
				(xy 9.278 -1.313) (xy 9.419 -1.281) (xy 9.543 -1.225) (xy 9.656 -1.146) (xy 9.708 -1.097) (xy 9.808 -0.975)
				(xy 9.887 -0.831) (xy 9.945 -0.666) (xy 9.984 -0.476) (xy 9.998 -0.354) (xy 10.005 -0.134) (xy 9.992 0.072)
				(xy 9.96 0.262) (xy 9.908 0.434) (xy 9.837 0.585) (xy 9.749 0.714) (xy 9.643 0.819) (xy 9.578 0.867)
				(xy 9.475 0.918) (xy 9.352 0.956) (xy 9.219 0.98) (xy 9.087 0.986) (xy 8.966 0.975) (xy 8.81 0.933)
				(xy 8.673 0.864) (xy 8.553 0.771) (xy 8.452 0.653) (xy 8.371 0.511) (xy 8.31 0.346) (xy 8.277 0.202)
				(xy 8.249 -0.011) (xy 8.243 -0.182) (xy 8.619 -0.182) (xy 8.626 -0.007) (xy 8.647 0.163) (xy 8.682 0.318)
				(xy 8.73 0.449) (xy 8.792 0.552) (xy 8.87 0.633) (xy 8.961 0.69) (xy 9.06 0.721) (xy 9.164 0.724)
				(xy 9.268 0.699) (xy 9.303 0.683) (xy 9.391 0.625) (xy 9.465 0.546) (xy 9.524 0.443) (xy 9.569 0.315)
				(xy 9.601 0.162) (xy 9.62 0) (xy 9.628 -0.198) (xy 9.62 -0.382) (xy 9.597 -0.55) (xy 9.558 -0.698)
				(xy 9.505 -0.825) (xy 9.439 -0.927) (xy 9.397 -0.971) (xy 9.307 -1.035) (xy 9.21 -1.071) (xy 9.109 -1.079)
				(xy 9.009 -1.062) (xy 8.915 -1.019) (xy 8.831 -0.953) (xy 8.76 -0.863) (xy 8.733 -0.813) (xy 8.684 -0.68)
				(xy 8.648 -0.526) (xy 8.627 -0.358) (xy 8.619 -0.182) (xy 8.243 -0.182) (xy 8.242 -0.218) (xy 8.255 -0.417)
				(xy 8.288 -0.602) (xy 8.339 -0.772) (xy 8.41 -0.923) (xy 8.498 -1.051) (xy 8.524 -1.081) (xy 8.637 -1.182)
				(xy 8.765 -1.255) (xy 8.908 -1.302) (xy 9.068 -1.322) (xy 9.117 -1.323) (xy 9.278 -1.313)
			)
			(stroke
				(width 0.00186)
				(type solid)
			)
			(fill yes)
			(layer "F.Cu")
		)
		(fp_poly
			(pts
				(xy 6.48 -1.32) (xy 6.584 -1.31) (xy 6.642 -1.3) (xy 6.701 -1.282) (xy 6.765 -1.259) (xy 6.825 -1.233)
				(xy 6.873 -1.209) (xy 6.9 -1.189) (xy 6.902 -1.186) (xy 6.901 -1.166) (xy 6.889 -1.128) (xy 6.872 -1.079)
				(xy 6.852 -1.03) (xy 6.833 -0.989) (xy 6.818 -0.966) (xy 6.815 -0.963) (xy 6.795 -0.969) (xy 6.757 -0.985)
				(xy 6.717 -1.002) (xy 6.597 -1.044) (xy 6.478 -1.06) (xy 6.365 -1.05) (xy 6.267 -1.016) (xy 6.184 -0.957)
				(xy 6.109 -0.87) (xy 6.042 -0.76) (xy 5.988 -0.629) (xy 5.964 -0.554) (xy 5.946 -0.461) (xy 5.934 -0.347)
				(xy 5.929 -0.22) (xy 5.931 -0.091) (xy 5.938 0.032) (xy 5.953 0.138) (xy 5.965 0.191) (xy 6.018 0.347)
				(xy 6.085 0.476) (xy 6.166 0.576) (xy 6.262 0.649) (xy 6.269 0.653) (xy 6.318 0.678) (xy 6.36 0.692)
				(xy 6.409 0.698) (xy 6.476 0.7) (xy 6.48 0.7) (xy 6.551 0.697) (xy 6.613 0.686) (xy 6.676 0.665)
				(xy 6.75 0.631) (xy 6.805 0.602) (xy 6.811 0.606) (xy 6.823 0.627) (xy 6.842 0.667) (xy 6.868 0.73)
				(xy 6.904 0.819) (xy 6.907 0.827) (xy 6.898 0.844) (xy 6.866 0.868) (xy 6.818 0.895) (xy 6.759 0.922)
				(xy 6.697 0.945) (xy 6.68 0.95) (xy 6.596 0.968) (xy 6.494 0.98) (xy 6.388 0.984) (xy 6.292 0.98)
				(xy 6.251 0.975) (xy 6.192 0.96) (xy 6.121 0.935) (xy 6.055 0.906) (xy 5.924 0.825) (xy 5.811 0.718)
				(xy 5.717 0.586) (xy 5.641 0.431) (xy 5.585 0.252) (xy 5.566 0.164) (xy 5.552 0.061) (xy 5.545 -0.061)
				(xy 5.544 -0.193) (xy 5.549 -0.327) (xy 5.56 -0.453) (xy 5.576 -0.563) (xy 5.589 -0.623) (xy 5.65 -0.797)
				(xy 5.731 -0.949) (xy 5.831 -1.077) (xy 5.948 -1.181) (xy 6.081 -1.259) (xy 6.187 -1.298) (xy 6.27 -1.314)
				(xy 6.372 -1.322) (xy 6.48 -1.32)
			)
			(stroke
				(width 0.00186)
				(type solid)
			)
			(fill yes)
			(layer "F.Cu")
		)
		(fp_poly
			(pts
				(xy -2.763 -1.313) (xy -2.663 -1.294) (xy -2.55 -1.259) (xy -2.459 -1.216) (xy -2.38 -1.16) (xy -2.341 -1.124)
				(xy -2.284 -1.053) (xy -2.232 -0.961) (xy -2.192 -0.861) (xy -2.174 -0.79) (xy -2.17 -0.754) (xy -2.167 -0.69)
				(xy -2.164 -0.599) (xy -2.162 -0.485) (xy -2.16 -0.35) (xy -2.159 -0.196) (xy -2.158 -0.027) (xy -2.158 0.064)
				(xy -2.158 0.833) (xy -2.232 0.865) (xy -2.364 0.913) (xy -2.517 0.949) (xy -2.682 0.974) (xy -2.85 0.986)
				(xy -3.011 0.983) (xy -3.097 0.975) (xy -3.264 0.942) (xy -3.407 0.889) (xy -3.525 0.817) (xy -3.618 0.725)
				(xy -3.686 0.616) (xy -3.729 0.487) (xy -3.746 0.341) (xy -3.746 0.268) (xy -3.744 0.254) (xy -3.383 0.254)
				(xy -3.38 0.384) (xy -3.352 0.497) (xy -3.298 0.591) (xy -3.221 0.665) (xy -3.12 0.719) (xy -3.072 0.735)
				(xy -3.011 0.745) (xy -2.928 0.75) (xy -2.835 0.75) (xy -2.74 0.744) (xy -2.655 0.734) (xy -2.589 0.72)
				(xy -2.579 0.716) (xy -2.504 0.689) (xy -2.504 -0.302) (xy -2.595 -0.291) (xy -2.653 -0.282) (xy -2.728 -0.267)
				(xy -2.806 -0.25) (xy -2.831 -0.244) (xy -2.992 -0.194) (xy -3.125 -0.133) (xy -3.229 -0.06) (xy -3.306 0.026)
				(xy -3.357 0.125) (xy -3.381 0.238) (xy -3.383 0.254) (xy -3.744 0.254) (xy -3.725 0.126) (xy -3.678 0)
				(xy -3.602 -0.112) (xy -3.559 -0.158) (xy -3.465 -0.233) (xy -3.343 -0.303) (xy -3.198 -0.365) (xy -3.034 -0.417)
				(xy -2.856 -0.46) (xy -2.666 -0.49) (xy -2.663 -0.49) (xy -2.5 -0.51) (xy -2.51 -0.644) (xy -2.528 -0.77)
				(xy -2.564 -0.871) (xy -2.62 -0.949) (xy -2.697 -1.007) (xy -2.797 -1.045) (xy -2.845 -1.056) (xy -2.975 -1.067)
				(xy -3.12 -1.056) (xy -3.272 -1.024) (xy -3.426 -0.972) (xy -3.439 -0.967) (xy -3.488 -0.947) (xy -3.523 -0.936)
				(xy -3.537 -0.934) (xy -3.545 -0.95) (xy -3.56 -0.987) (xy -3.579 -1.035) (xy -3.598 -1.086) (xy -3.613 -1.129)
				(xy -3.622 -1.155) (xy -3.623 -1.159) (xy -3.609 -1.169) (xy -3.575 -1.188) (xy -3.537 -1.206) (xy -3.395 -1.257)
				(xy -3.239 -1.294) (xy -3.075 -1.316) (xy -2.914 -1.323) (xy -2.763 -1.313)
			)
			(stroke
				(width 0.00186)
				(type solid)
			)
			(fill yes)
			(layer "F.Cu")
		)
		(fp_poly
			(pts
				(xy -7.153 -3.366) (xy -7.087 -3.351) (xy -7.086 -3.351) (xy -7.066 -3.34) (xy -7.021 -3.315) (xy -6.953 -3.277)
				(xy -6.865 -3.227) (xy -6.759 -3.167) (xy -6.639 -3.099) (xy -6.505 -3.022) (xy -6.361 -2.94) (xy -6.209 -2.853)
				(xy -6.052 -2.762) (xy -5.891 -2.67) (xy -5.729 -2.577) (xy -5.569 -2.485) (xy -5.413 -2.395) (xy -5.264 -2.309)
				(xy -5.123 -2.227) (xy -4.994 -2.152) (xy -4.878 -2.085) (xy -4.778 -2.027) (xy -4.697 -1.979) (xy -4.636 -1.943)
				(xy -4.599 -1.921) (xy -4.595 -1.918) (xy -4.528 -1.863) (xy -4.476 -1.798) (xy -4.434 -1.725) (xy -4.429 -0.224)
				(xy -4.429 0.063) (xy -4.428 0.323) (xy -4.429 0.553) (xy -4.429 0.755) (xy -4.43 0.928) (xy -4.432 1.071)
				(xy -4.434 1.184) (xy -4.436 1.266) (xy -4.439 1.318) (xy -4.441 1.337) (xy -4.448 1.36) (xy -4.454 1.382)
				(xy -4.463 1.403) (xy -4.476 1.423) (xy -4.494 1.445) (xy -4.519 1.47) (xy -4.552 1.497) (xy -4.596 1.529)
				(xy -4.652 1.567) (xy -4.721 1.611) (xy -4.805 1.663) (xy -4.906 1.723) (xy -5.025 1.794) (xy -5.165 1.875)
				(xy -5.326 1.969) (xy -5.511 2.076) (xy -5.72 2.197) (xy -5.813 2.251) (xy -7.079 2.982) (xy -7.197 2.988)
				(xy -7.315 2.994) (xy -7.78 2.727) (xy -8.064 2.563) (xy -8.323 2.415) (xy -8.557 2.28) (xy -8.767 2.159)
				(xy -8.955 2.051) (xy -9.122 1.954) (xy -9.27 1.868) (xy -9.399 1.792) (xy -9.51 1.726) (xy -9.606 1.669)
				(xy -9.688 1.619) (xy -9.756 1.576) (xy -9.812 1.539) (xy -9.857 1.507) (xy -9.893 1.481) (xy -9.92 1.458)
				(xy -9.94 1.437) (xy -9.955 1.42) (xy -9.965 1.403) (xy -9.972 1.387) (xy -9.977 1.371) (xy -9.981 1.354)
				(xy -9.985 1.337) (xy -9.988 1.309) (xy -9.991 1.25) (xy -9.993 1.161) (xy -9.995 1.041) (xy -9.996 0.891)
				(xy -9.997 0.712) (xy -9.998 0.503) (xy -9.998 0.266) (xy -9.997 0) (xy -9.997 -0.189) (xy -9.024 -0.189)
				(xy -9.024 0.015) (xy -9.024 0.191) (xy -9.023 0.34) (xy -9.022 0.464) (xy -9.021 0.567) (xy -9.018 0.65)
				(xy -9.014 0.717) (xy -9.01 0.768) (xy -9.003 0.808) (xy -8.995 0.837) (xy -8.986 0.859) (xy -8.974 0.876)
				(xy -8.961 0.891) (xy -8.945 0.905) (xy -8.943 0.906) (xy -8.922 0.921) (xy -8.877 0.949) (xy -8.81 0.989)
				(xy -8.725 1.039) (xy -8.625 1.098) (xy -8.512 1.164) (xy -8.389 1.235) (xy -8.26 1.31) (xy -8.128 1.386)
				(xy -7.995 1.463) (xy -7.864 1.538) (xy -7.739 1.609) (xy -7.622 1.676) (xy -7.517 1.735) (xy -7.425 1.787)
				(xy -7.351 1.828) (xy -7.297 1.857) (xy -7.266 1.872) (xy -7.261 1.874) (xy -7.222 1.885) (xy -7.195 1.886)
				(xy -7.163 1.875) (xy -7.144 1.867) (xy -7.117 1.854) (xy -7.067 1.827) (xy -6.997 1.788) (xy -6.909 1.738)
				(xy -6.805 1.679) (xy -6.691 1.614) (xy -6.567 1.543) (xy -6.438 1.469) (xy -6.306 1.392) (xy -6.174 1.316)
				(xy -6.045 1.241) (xy -5.922 1.17) (xy -5.809 1.103) (xy -5.708 1.044) (xy -5.622 0.992) (xy -5.553 0.952)
				(xy -5.507 0.923) (xy -5.484 0.907) (xy -5.483 0.907) (xy -5.467 0.892) (xy -5.453 0.878) (xy -5.441 0.861)
				(xy -5.431 0.839) (xy -5.423 0.81) (xy -5.417 0.772) (xy -5.412 0.721) (xy -5.408 0.656) (xy -5.406 0.574)
				(xy -5.404 0.473) (xy -5.403 0.35) (xy -5.402 0.203) (xy -5.402 0.03) (xy -5.402 -0.172) (xy -5.402 -0.189)
				(xy -5.402 -0.395) (xy -5.402 -0.572) (xy -5.403 -0.721) (xy -5.404 -0.847) (xy -5.406 -0.95) (xy -5.408 -1.034)
				(xy -5.412 -1.101) (xy -5.418 -1.153) (xy -5.425 -1.193) (xy -5.434 -1.223) (xy -5.445 -1.245) (xy -5.458 -1.262)
				(xy -5.473 -1.276) (xy -5.491 -1.29) (xy -5.499 -1.295) (xy -5.522 -1.31) (xy -5.57 -1.339) (xy -5.64 -1.381)
				(xy -5.729 -1.433) (xy -5.835 -1.496) (xy -5.956 -1.566) (xy -6.088 -1.643) (xy -6.229 -1.725) (xy -6.348 -1.793)
				(xy -6.519 -1.891) (xy -6.664 -1.974) (xy -6.786 -2.044) (xy -6.888 -2.101) (xy -6.971 -2.147) (xy -7.038 -2.183)
				(xy -7.091 -2.21) (xy -7.132 -2.229) (xy -7.163 -2.242) (xy -7.187 -2.249) (xy -7.205 -2.252) (xy -7.211 -2.252)
				(xy -7.228 -2.251) (xy -7.249 -2.246) (xy -7.276 -2.236) (xy -7.312 -2.219) (xy -7.359 -2.196) (xy -7.419 -2.165)
				(xy -7.495 -2.123) (xy -7.587 -2.072) (xy -7.699 -2.008) (xy -7.832 -1.932) (xy -7.99 -1.842) (xy -8.1 -1.778)
				(xy -8.248 -1.693) (xy -8.388 -1.611) (xy -8.519 -1.535) (xy -8.637 -1.466) (xy -8.739 -1.406) (xy -8.825 -1.355)
				(xy -8.89 -1.316) (xy -8.933 -1.29) (xy -8.951 -1.278) (xy -8.966 -1.265) (xy -8.978 -1.251) (xy -8.989 -1.234)
				(xy -8.998 -1.212) (xy -9.005 -1.182) (xy -9.011 -1.141) (xy -9.015 -1.087) (xy -9.018 -1.019) (xy -9.021 -0.933)
				(xy -9.022 -0.827) (xy -9.023 -0.699) (xy -9.024 -0.546) (xy -9.024 -0.366) (xy -9.024 -0.189) (xy -9.997 -0.189)
				(xy -9.997 -0.224) (xy -9.996 -0.479) (xy -9.996 -0.705) (xy -9.995 -0.903) (xy -9.994 -1.075) (xy -9.993 -1.223)
				(xy -9.992 -1.35) (xy -9.99 -1.456) (xy -9.987 -1.545) (xy -9.984 -1.617) (xy -9.98 -1.675) (xy -9.974 -1.721)
				(xy -9.968 -1.757) (xy -9.961 -1.784) (xy -9.952 -1.805) (xy -9.941 -1.821) (xy -9.929 -1.834) (xy -9.915 -1.847)
				(xy -9.9 -1.86) (xy -9.893 -1.866) (xy -9.873 -1.88) (xy -9.828 -1.909) (xy -9.759 -1.951) (xy -9.669 -2.005)
				(xy -9.56 -2.07) (xy -9.433 -2.145) (xy -9.291 -2.228) (xy -9.136 -2.319) (xy -8.969 -2.416) (xy -8.793 -2.518)
				(xy -8.61 -2.624) (xy -8.59 -2.635) (xy -8.377 -2.759) (xy -8.189 -2.867) (xy -8.024 -2.962) (xy -7.882 -3.044)
				(xy -7.759 -3.114) (xy -7.656 -3.173) (xy -7.568 -3.221) (xy -7.496 -3.261) (xy -7.437 -3.293) (xy -7.389 -3.317)
				(xy -7.351 -3.336) (xy -7.321 -3.349) (xy -7.296 -3.357) (xy -7.276 -3.363) (xy -7.259 -3.366) (xy -7.242 -3.367)
				(xy -7.237 -3.368) (xy -7.153 -3.366)
			)
			(stroke
				(width 0.00186)
				(type solid)
			)
			(fill yes)
			(layer "F.Cu")
		)
		(fp_poly
			(pts
				(xy -7.128 -1.48) (xy -7.114 -1.475) (xy -7.042 -1.428) (xy -6.989 -1.361) (xy -6.96 -1.281) (xy -6.957 -1.196)
				(xy -6.961 -1.175) (xy -6.992 -1.094) (xy -7.046 -1.034) (xy -7.101 -1.001) (xy -7.166 -0.969) (xy -7.166 -0.599)
				(xy -6.891 -0.599) (xy -6.778 -0.711) (xy -6.665 -0.824) (xy -6.673 -0.905) (xy -6.673 -0.906) (xy -6.566 -0.906)
				(xy -6.549 -0.87) (xy -6.512 -0.853) (xy -6.467 -0.856) (xy -6.435 -0.876) (xy -6.412 -0.913) (xy -6.42 -0.95)
				(xy -6.441 -0.977) (xy -6.471 -1.002) (xy -6.496 -1.005) (xy -6.53 -0.986) (xy -6.532 -0.984) (xy -6.56 -0.949)
				(xy -6.566 -0.906) (xy -6.673 -0.906) (xy -6.676 -0.957) (xy -6.669 -0.992) (xy -6.648 -1.025) (xy -6.639 -1.036)
				(xy -6.582 -1.084) (xy -6.519 -1.106) (xy -6.456 -1.105) (xy -6.397 -1.084) (xy -6.349 -1.044) (xy -6.316 -0.99)
				(xy -6.304 -0.925) (xy -6.315 -0.859) (xy -6.351 -0.797) (xy -6.408 -0.757) (xy -6.484 -0.741) (xy -6.497 -0.741)
				(xy -6.529 -0.74) (xy -6.557 -0.734) (xy -6.585 -0.719) (xy -6.619 -0.693) (xy -6.667 -0.651) (xy -6.705 -0.615)
				(xy -6.84 -0.489) (xy -7.166 -0.489) (xy -7.166 -0.237) (xy -6.568 -0.237) (xy -6.545 -0.282) (xy -6.502 -0.333)
				(xy -6.443 -0.364) (xy -6.377 -0.373) (xy -6.311 -0.36) (xy -6.255 -0.322) (xy -6.249 -0.317) (xy -6.209 -0.253)
				(xy -6.195 -0.188) (xy -6.205 -0.126) (xy -6.234 -0.072) (xy -6.28 -0.03) (xy -6.337 -0.006) (xy -6.402 -0.002)
				(xy -6.472 -0.025) (xy -6.486 -0.033) (xy -6.523 -0.061) (xy -6.545 -0.091) (xy -6.547 -0.096) (xy -6.552 -0.106)
				(xy -6.561 -0.114) (xy -6.58 -0.12) (xy -6.613 -0.123) (xy -6.664 -0.125) (xy -6.737 -0.126) (xy -6.836 -0.126)
				(xy -6.861 -0.126) (xy -7.166 -0.126) (xy -7.166 0.11) (xy -6.842 0.11) (xy -6.581 0.373) (xy -6.507 0.366)
				(xy -6.428 0.372) (xy -6.367 0.402) (xy -6.325 0.457) (xy -6.314 0.486) (xy -6.304 0.561) (xy -6.322 0.626)
				(xy -6.361 0.678) (xy -6.422 0.72) (xy -6.487 0.736) (xy -6.55 0.727) (xy -6.605 0.697) (xy -6.648 0.648)
				(xy -6.671 0.583) (xy -6.672 0.536) (xy -6.564 0.536) (xy -6.559 0.575) (xy -6.544 0.597) (xy -6.508 0.625)
				(xy -6.474 0.623) (xy -6.441 0.598) (xy -6.414 0.56) (xy -6.417 0.525) (xy -6.44 0.497) (xy -6.48 0.476)
				(xy -6.518 0.48) (xy -6.549 0.502) (xy -6.564 0.536) (xy -6.672 0.536) (xy -6.673 0.52) (xy -6.664 0.445)
				(xy -6.891 0.22) (xy -7.166 0.22) (xy -7.166 0.593) (xy -7.101 0.622) (xy -7.033 0.668) (xy -6.986 0.732)
				(xy -6.96 0.805) (xy -6.956 0.883) (xy -6.973 0.959) (xy -7.013 1.026) (xy -7.074 1.079) (xy -7.088 1.087)
				(xy -7.171 1.112) (xy -7.258 1.112) (xy -7.34 1.087) (xy -7.341 1.086) (xy -7.406 1.036) (xy -7.448 0.97)
				(xy -7.469 0.895) (xy -7.468 0.858) (xy -7.361 0.858) (xy -7.355 0.905) (xy -7.331 0.942) (xy -7.31 0.962)
				(xy -7.252 0.999) (xy -7.195 1.005) (xy -7.137 0.979) (xy -7.116 0.962) (xy -7.08 0.923) (xy -7.066 0.883)
				(xy -7.065 0.858) (xy -7.079 0.801) (xy -7.116 0.751) (xy -7.167 0.718) (xy -7.213 0.708) (xy -7.27 0.722)
				(xy -7.319 0.76) (xy -7.352 0.812) (xy -7.361 0.858) (xy -7.468 0.858) (xy -7.468 0.817) (xy -7.445 0.742)
				(xy -7.401 0.677) (xy -7.336 0.628) (xy -7.325 0.622) (xy -7.26 0.593) (xy -7.26 0.22) (xy -7.535 0.22)
				(xy -7.762 0.445) (xy -7.753 0.52) (xy -7.757 0.595) (xy -7.785 0.658) (xy -7.83 0.703) (xy -7.887 0.73)
				(xy -7.951 0.735) (xy -8.015 0.715) (xy -8.065 0.678) (xy -8.109 0.617) (xy -8.123 0.551) (xy -8.12 0.532)
				(xy -8.012 0.532) (xy -8.009 0.566) (xy -7.985 0.598) (xy -7.946 0.625) (xy -7.912 0.623) (xy -7.883 0.599)
				(xy -7.863 0.558) (xy -7.868 0.517) (xy -7.896 0.486) (xy -7.915 0.478) (xy -7.961 0.48) (xy -7.985 0.496)
				(xy -8.012 0.532) (xy -8.12 0.532) (xy -8.112 0.486) (xy -8.079 0.422) (xy -8.025 0.381) (xy -7.953 0.365)
				(xy -7.919 0.366) (xy -7.845 0.373) (xy -7.584 0.11) (xy -7.26 0.11) (xy -7.26 -0.126) (xy -7.566 -0.126)
				(xy -7.672 -0.126) (xy -7.75 -0.126) (xy -7.805 -0.124) (xy -7.841 -0.121) (xy -7.863 -0.116) (xy -7.875 -0.108)
				(xy -7.881 -0.098) (xy -7.883 -0.094) (xy -7.908 -0.058) (xy -7.954 -0.026) (xy -8.009 -0.005) (xy -8.045 -0.001)
				(xy -8.117 -0.014) (xy -8.174 -0.049) (xy -8.213 -0.102) (xy -8.23 -0.164) (xy -8.228 -0.186) (xy -8.124 -0.186)
				(xy -8.12 -0.163) (xy -8.104 -0.143) (xy -8.063 -0.115) (xy -8.021 -0.117) (xy -7.994 -0.135) (xy -7.971 -0.176)
				(xy -7.976 -0.202) (xy -6.455 -0.202) (xy -6.449 -0.158) (xy -6.432 -0.135) (xy -6.392 -0.113) (xy -6.35 -0.121)
				(xy -6.322 -0.143) (xy -6.303 -0.169) (xy -6.304 -0.193) (xy -6.316 -0.218) (xy -6.35 -0.254) (xy -6.39 -0.265)
				(xy -6.429 -0.247) (xy -6.432 -0.244) (xy -6.455 -0.202) (xy -7.976 -0.202) (xy -7.979 -0.218) (xy -7.999 -0.244)
				(xy -8.04 -0.265) (xy -8.078 -0.255) (xy -8.11 -0.218) (xy -8.124 -0.186) (xy -8.228 -0.186) (xy -8.224 -0.232)
				(xy -8.192 -0.297) (xy -8.177 -0.317) (xy -8.121 -0.358) (xy -8.055 -0.374) (xy -7.988 -0.365) (xy -7.927 -0.333)
				(xy -7.885 -0.284) (xy -7.857 -0.237) (xy -7.26 -0.237) (xy -7.26 -0.489) (xy -7.586 -0.489) (xy -7.721 -0.615)
				(xy -7.779 -0.669) (xy -7.821 -0.704) (xy -7.852 -0.726) (xy -7.879 -0.737) (xy -7.908 -0.74) (xy -7.934 -0.741)
				(xy -8.011 -0.752) (xy -8.068 -0.787) (xy -8.105 -0.846) (xy -8.112 -0.866) (xy -8.119 -0.923) (xy -8.016 -0.923)
				(xy -8.003 -0.887) (xy -7.969 -0.862) (xy -7.928 -0.852) (xy -7.888 -0.861) (xy -7.878 -0.87) (xy -7.86 -0.907)
				(xy -7.866 -0.949) (xy -7.894 -0.984) (xy -7.924 -1.002) (xy -7.941 -1.008) (xy -7.964 -0.997) (xy -7.991 -0.969)
				(xy -8.011 -0.939) (xy -8.016 -0.923) (xy -8.119 -0.923) (xy -8.121 -0.94) (xy -8.105 -1.004) (xy -8.069 -1.055)
				(xy -8.018 -1.091) (xy -7.958 -1.108) (xy -7.894 -1.104) (xy -7.831 -1.076) (xy -7.787 -1.036) (xy -7.762 -1.001)
				(xy -7.751 -0.968) (xy -7.751 -0.923) (xy -7.753 -0.905) (xy -7.762 -0.824) (xy -7.648 -0.711) (xy -7.535 -0.599)
				(xy -7.26 -0.599) (xy -7.26 -0.971) (xy -7.323 -0.998) (xy -7.396 -1.046) (xy -7.446 -1.114) (xy -7.465 -1.166)
				(xy -7.472 -1.24) (xy -7.365 -1.24) (xy -7.359 -1.204) (xy -7.347 -1.177) (xy -7.307 -1.123) (xy -7.254 -1.093)
				(xy -7.194 -1.09) (xy -7.134 -1.116) (xy -7.127 -1.121) (xy -7.081 -1.171) (xy -7.065 -1.225) (xy -7.078 -1.283)
				(xy -7.116 -1.342) (xy -7.166 -1.375) (xy -7.222 -1.384) (xy -7.278 -1.368) (xy -7.326 -1.326) (xy -7.354 -1.278)
				(xy -7.365 -1.24) (xy -7.472 -1.24) (xy -7.474 -1.25) (xy -7.455 -1.328) (xy -7.416 -1.396) (xy -7.358 -1.449)
				(xy -7.288 -1.484) (xy -7.21 -1.495) (xy -7.128 -1.48)
			)
			(stroke
				(width 0.00186)
				(type solid)
			)
			(fill yes)
			(layer "F.Cu")
		)
		(fp_poly
			(pts
				(xy 5.212 0.944) (xy 4.834 0.944) (xy 4.834 -1.292) (xy 5.212 -1.292) (xy 5.212 0.944)
			)
			(stroke
				(width 0.00186)
				(type solid)
			)
			(fill yes)
			(layer "F.Mask")
		)
		(fp_poly
			(pts
				(xy 8.164 -1.321) (xy 8.193 -1.317) (xy 8.204 -1.31) (xy 8.204 -1.308) (xy 8.2 -1.285) (xy 8.188 -1.24)
				(xy 8.171 -1.181) (xy 8.163 -1.156) (xy 8.142 -1.092) (xy 8.126 -1.053) (xy 8.112 -1.034) (xy 8.097 -1.031)
				(xy 8.094 -1.032) (xy 7.996 -1.053) (xy 7.886 -1.06) (xy 7.778 -1.053) (xy 7.683 -1.032) (xy 7.665 -1.026)
				(xy 7.622 -1.009) (xy 7.622 0.944) (xy 7.244 0.944) (xy 7.244 -1.178) (xy 7.358 -1.219) (xy 7.457 -1.253)
				(xy 7.548 -1.277) (xy 7.639 -1.295) (xy 7.738 -1.307) (xy 7.856 -1.315) (xy 7.94 -1.319) (xy 8.042 -1.322)
				(xy 8.115 -1.322) (xy 8.164 -1.321)
			)
			(stroke
				(width 0.00186)
				(type solid)
			)
			(fill yes)
			(layer "F.Mask")
		)
		(fp_poly
			(pts
				(xy 0.795 -1.891) (xy 0.798 -1.849) (xy 0.8 -1.786) (xy 0.802 -1.705) (xy 0.803 -1.612) (xy 0.803 -1.599)
				(xy 0.803 -1.292) (xy 1.181 -1.292) (xy 1.181 -1.04) (xy 0.803 -1.04) (xy 0.803 0.498) (xy 0.838 0.566)
				(xy 0.885 0.631) (xy 0.944 0.671) (xy 1.021 0.688) (xy 1.082 0.689) (xy 1.181 0.685) (xy 1.181 0.806)
				(xy 1.178 0.88) (xy 1.17 0.926) (xy 1.161 0.939) (xy 1.138 0.945) (xy 1.09 0.95) (xy 1.028 0.954)
				(xy 0.984 0.956) (xy 0.897 0.957) (xy 0.832 0.953) (xy 0.778 0.942) (xy 0.743 0.931) (xy 0.647 0.886)
				(xy 0.571 0.823) (xy 0.508 0.737) (xy 0.488 0.701) (xy 0.433 0.593) (xy 0.428 -0.223) (xy 0.424 -1.04)
				(xy 0.173 -1.04) (xy 0.173 -1.292) (xy 0.425 -1.292) (xy 0.425 -1.795) (xy 0.603 -1.85) (xy 0.673 -1.872)
				(xy 0.733 -1.89) (xy 0.774 -1.902) (xy 0.792 -1.906) (xy 0.795 -1.891)
			)
			(stroke
				(width 0.00186)
				(type solid)
			)
			(fill yes)
			(layer "F.Mask")
		)
		(fp_poly
			(pts
				(xy -0.82 -1.315) (xy -0.737 -1.312) (xy -0.672 -1.308) (xy -0.621 -1.301) (xy -0.577 -1.291) (xy -0.56 -1.286)
				(xy -0.417 -1.232) (xy -0.302 -1.164) (xy -0.212 -1.082) (xy -0.154 -0.996) (xy -0.135 -0.961) (xy -0.119 -0.927)
				(xy -0.105 -0.893) (xy -0.094 -0.855) (xy -0.085 -0.811) (xy -0.078 -0.758) (xy -0.073 -0.693) (xy -0.069 -0.612)
				(xy -0.067 -0.515) (xy -0.065 -0.397) (xy -0.064 -0.256) (xy -0.064 -0.088) (xy -0.063 0.105) (xy -0.063 0.944)
				(xy -0.441 0.944) (xy -0.441 0.113) (xy -0.442 -0.083) (xy -0.442 -0.25) (xy -0.443 -0.391) (xy -0.445 -0.508)
				(xy -0.448 -0.604) (xy -0.452 -0.682) (xy -0.457 -0.744) (xy -0.465 -0.794) (xy -0.474 -0.833) (xy -0.486 -0.864)
				(xy -0.501 -0.89) (xy -0.518 -0.913) (xy -0.538 -0.937) (xy -0.539 -0.939) (xy -0.604 -0.997) (xy -0.684 -1.039)
				(xy -0.784 -1.066) (xy -0.822 -1.072) (xy -0.927 -1.078) (xy -1.044 -1.073) (xy -1.158 -1.056) (xy -1.24 -1.034)
				(xy -1.3 -1.013) (xy -1.304 -0.034) (xy -1.308 0.944) (xy -1.686 0.944) (xy -1.686 -1.178) (xy -1.54 -1.225)
				(xy -1.44 -1.257) (xy -1.354 -1.28) (xy -1.276 -1.297) (xy -1.195 -1.307) (xy -1.105 -1.313) (xy -0.995 -1.315)
				(xy -0.93 -1.315) (xy -0.82 -1.315)
			)
			(stroke
				(width 0.00186)
				(type solid)
			)
			(fill yes)
			(layer "F.Mask")
		)
		(fp_poly
			(pts
				(xy 3.757 -1.312) (xy 3.91 -1.278) (xy 4.043 -1.223) (xy 4.153 -1.146) (xy 4.24 -1.047) (xy 4.282 -0.977)
				(xy 4.299 -0.943) (xy 4.313 -0.91) (xy 4.325 -0.876) (xy 4.335 -0.837) (xy 4.343 -0.791) (xy 4.349 -0.734)
				(xy 4.353 -0.665) (xy 4.357 -0.581) (xy 4.359 -0.478) (xy 4.361 -0.354) (xy 4.361 -0.206) (xy 4.362 -0.031)
				(xy 4.362 0.111) (xy 4.362 0.944) (xy 3.985 0.944) (xy 3.98 0.074) (xy 3.976 -0.796) (xy 3.93 -0.879)
				(xy 3.867 -0.961) (xy 3.786 -1.022) (xy 3.691 -1.062) (xy 3.586 -1.079) (xy 3.476 -1.074) (xy 3.366 -1.045)
				(xy 3.26 -0.994) (xy 3.185 -0.938) (xy 3.118 -0.88) (xy 3.118 0.944) (xy 2.74 0.944) (xy 2.74 0.092)
				(xy 2.739 -0.122) (xy 2.739 -0.305) (xy 2.737 -0.459) (xy 2.735 -0.585) (xy 2.732 -0.683) (xy 2.729 -0.755)
				(xy 2.725 -0.802) (xy 2.722 -0.821) (xy 2.679 -0.91) (xy 2.613 -0.981) (xy 2.523 -1.034) (xy 2.413 -1.067)
				(xy 2.284 -1.079) (xy 2.154 -1.073) (xy 2.082 -1.064) (xy 2.031 -1.056) (xy 1.989 -1.046) (xy 1.944 -1.031)
				(xy 1.917 -1.021) (xy 1.874 -1.005) (xy 1.874 0.944) (xy 1.511 0.944) (xy 1.511 -1.18) (xy 1.661 -1.228)
				(xy 1.83 -1.276) (xy 1.988 -1.306) (xy 2.148 -1.319) (xy 2.314 -1.319) (xy 2.448 -1.311) (xy 2.557 -1.297)
				(xy 2.649 -1.272) (xy 2.732 -1.237) (xy 2.811 -1.189) (xy 2.843 -1.165) (xy 2.947 -1.087) (xy 3.012 -1.14)
				(xy 3.14 -1.224) (xy 3.283 -1.283) (xy 3.443 -1.315) (xy 3.582 -1.323) (xy 3.757 -1.312)
			)
			(stroke
				(width 0.00186)
				(type solid)
			)
			(fill yes)
			(layer "F.Mask")
		)
		(fp_poly
			(pts
				(xy 9.278 -1.313) (xy 9.419 -1.281) (xy 9.543 -1.225) (xy 9.656 -1.146) (xy 9.708 -1.097) (xy 9.808 -0.975)
				(xy 9.887 -0.831) (xy 9.945 -0.666) (xy 9.984 -0.476) (xy 9.998 -0.354) (xy 10.005 -0.134) (xy 9.992 0.072)
				(xy 9.96 0.262) (xy 9.908 0.434) (xy 9.837 0.585) (xy 9.749 0.714) (xy 9.643 0.819) (xy 9.578 0.867)
				(xy 9.475 0.918) (xy 9.352 0.956) (xy 9.219 0.98) (xy 9.087 0.986) (xy 8.966 0.975) (xy 8.81 0.933)
				(xy 8.673 0.864) (xy 8.553 0.771) (xy 8.452 0.653) (xy 8.371 0.511) (xy 8.31 0.346) (xy 8.277 0.202)
				(xy 8.249 -0.011) (xy 8.243 -0.182) (xy 8.619 -0.182) (xy 8.626 -0.007) (xy 8.647 0.163) (xy 8.682 0.318)
				(xy 8.73 0.449) (xy 8.792 0.552) (xy 8.87 0.633) (xy 8.961 0.69) (xy 9.06 0.721) (xy 9.164 0.724)
				(xy 9.268 0.699) (xy 9.303 0.683) (xy 9.391 0.625) (xy 9.465 0.546) (xy 9.524 0.443) (xy 9.569 0.315)
				(xy 9.601 0.162) (xy 9.62 0) (xy 9.628 -0.198) (xy 9.62 -0.382) (xy 9.597 -0.55) (xy 9.558 -0.698)
				(xy 9.505 -0.825) (xy 9.439 -0.927) (xy 9.397 -0.971) (xy 9.307 -1.035) (xy 9.21 -1.071) (xy 9.109 -1.079)
				(xy 9.009 -1.062) (xy 8.915 -1.019) (xy 8.831 -0.953) (xy 8.76 -0.863) (xy 8.733 -0.813) (xy 8.684 -0.68)
				(xy 8.648 -0.526) (xy 8.627 -0.358) (xy 8.619 -0.182) (xy 8.243 -0.182) (xy 8.242 -0.218) (xy 8.255 -0.417)
				(xy 8.288 -0.602) (xy 8.339 -0.772) (xy 8.41 -0.923) (xy 8.498 -1.051) (xy 8.524 -1.081) (xy 8.637 -1.182)
				(xy 8.765 -1.255) (xy 8.908 -1.302) (xy 9.068 -1.322) (xy 9.117 -1.323) (xy 9.278 -1.313)
			)
			(stroke
				(width 0.00186)
				(type solid)
			)
			(fill yes)
			(layer "F.Mask")
		)
		(fp_poly
			(pts
				(xy 6.48 -1.32) (xy 6.584 -1.31) (xy 6.642 -1.3) (xy 6.701 -1.282) (xy 6.765 -1.259) (xy 6.825 -1.233)
				(xy 6.873 -1.209) (xy 6.9 -1.189) (xy 6.902 -1.186) (xy 6.901 -1.166) (xy 6.889 -1.128) (xy 6.872 -1.079)
				(xy 6.852 -1.03) (xy 6.833 -0.989) (xy 6.818 -0.966) (xy 6.815 -0.963) (xy 6.795 -0.969) (xy 6.757 -0.985)
				(xy 6.717 -1.002) (xy 6.597 -1.044) (xy 6.478 -1.06) (xy 6.365 -1.05) (xy 6.267 -1.016) (xy 6.184 -0.957)
				(xy 6.109 -0.87) (xy 6.042 -0.76) (xy 5.988 -0.629) (xy 5.964 -0.554) (xy 5.946 -0.461) (xy 5.934 -0.347)
				(xy 5.929 -0.22) (xy 5.931 -0.091) (xy 5.938 0.032) (xy 5.953 0.138) (xy 5.965 0.191) (xy 6.018 0.347)
				(xy 6.085 0.476) (xy 6.166 0.576) (xy 6.262 0.649) (xy 6.269 0.653) (xy 6.318 0.678) (xy 6.36 0.692)
				(xy 6.409 0.698) (xy 6.476 0.7) (xy 6.48 0.7) (xy 6.551 0.697) (xy 6.613 0.686) (xy 6.676 0.665)
				(xy 6.75 0.631) (xy 6.805 0.602) (xy 6.811 0.606) (xy 6.823 0.627) (xy 6.842 0.667) (xy 6.868 0.73)
				(xy 6.904 0.819) (xy 6.907 0.827) (xy 6.898 0.844) (xy 6.866 0.868) (xy 6.818 0.895) (xy 6.759 0.922)
				(xy 6.697 0.945) (xy 6.68 0.95) (xy 6.596 0.968) (xy 6.494 0.98) (xy 6.388 0.984) (xy 6.292 0.98)
				(xy 6.251 0.975) (xy 6.192 0.96) (xy 6.121 0.935) (xy 6.055 0.906) (xy 5.924 0.825) (xy 5.811 0.718)
				(xy 5.717 0.586) (xy 5.641 0.431) (xy 5.585 0.252) (xy 5.566 0.164) (xy 5.552 0.061) (xy 5.545 -0.061)
				(xy 5.544 -0.193) (xy 5.549 -0.327) (xy 5.56 -0.453) (xy 5.576 -0.563) (xy 5.589 -0.623) (xy 5.65 -0.797)
				(xy 5.731 -0.949) (xy 5.831 -1.077) (xy 5.948 -1.181) (xy 6.081 -1.259) (xy 6.187 -1.298) (xy 6.27 -1.314)
				(xy 6.372 -1.322) (xy 6.48 -1.32)
			)
			(stroke
				(width 0.00186)
				(type solid)
			)
			(fill yes)
			(layer "F.Mask")
		)
		(fp_poly
			(pts
				(xy -2.763 -1.313) (xy -2.663 -1.294) (xy -2.55 -1.259) (xy -2.459 -1.216) (xy -2.38 -1.16) (xy -2.341 -1.124)
				(xy -2.284 -1.053) (xy -2.232 -0.961) (xy -2.192 -0.861) (xy -2.174 -0.79) (xy -2.17 -0.754) (xy -2.167 -0.69)
				(xy -2.164 -0.599) (xy -2.162 -0.485) (xy -2.16 -0.35) (xy -2.159 -0.196) (xy -2.158 -0.027) (xy -2.158 0.064)
				(xy -2.158 0.833) (xy -2.232 0.865) (xy -2.364 0.913) (xy -2.517 0.949) (xy -2.682 0.974) (xy -2.85 0.986)
				(xy -3.011 0.983) (xy -3.097 0.975) (xy -3.264 0.942) (xy -3.407 0.889) (xy -3.525 0.817) (xy -3.618 0.725)
				(xy -3.686 0.616) (xy -3.729 0.487) (xy -3.746 0.341) (xy -3.746 0.268) (xy -3.744 0.254) (xy -3.383 0.254)
				(xy -3.38 0.384) (xy -3.352 0.497) (xy -3.298 0.591) (xy -3.221 0.665) (xy -3.12 0.719) (xy -3.072 0.735)
				(xy -3.011 0.745) (xy -2.928 0.75) (xy -2.835 0.75) (xy -2.74 0.744) (xy -2.655 0.734) (xy -2.589 0.72)
				(xy -2.579 0.716) (xy -2.504 0.689) (xy -2.504 -0.302) (xy -2.595 -0.291) (xy -2.653 -0.282) (xy -2.728 -0.267)
				(xy -2.806 -0.25) (xy -2.831 -0.244) (xy -2.992 -0.194) (xy -3.125 -0.133) (xy -3.229 -0.06) (xy -3.306 0.026)
				(xy -3.357 0.125) (xy -3.381 0.238) (xy -3.383 0.254) (xy -3.744 0.254) (xy -3.725 0.126) (xy -3.678 0)
				(xy -3.602 -0.112) (xy -3.559 -0.158) (xy -3.465 -0.233) (xy -3.343 -0.303) (xy -3.198 -0.365) (xy -3.034 -0.417)
				(xy -2.856 -0.46) (xy -2.666 -0.49) (xy -2.663 -0.49) (xy -2.5 -0.51) (xy -2.51 -0.644) (xy -2.528 -0.77)
				(xy -2.564 -0.871) (xy -2.62 -0.949) (xy -2.697 -1.007) (xy -2.797 -1.045) (xy -2.845 -1.056) (xy -2.975 -1.067)
				(xy -3.12 -1.056) (xy -3.272 -1.024) (xy -3.426 -0.972) (xy -3.439 -0.967) (xy -3.488 -0.947) (xy -3.523 -0.936)
				(xy -3.537 -0.934) (xy -3.545 -0.95) (xy -3.56 -0.987) (xy -3.579 -1.035) (xy -3.598 -1.086) (xy -3.613 -1.129)
				(xy -3.622 -1.155) (xy -3.623 -1.159) (xy -3.609 -1.169) (xy -3.575 -1.188) (xy -3.537 -1.206) (xy -3.395 -1.257)
				(xy -3.239 -1.294) (xy -3.075 -1.316) (xy -2.914 -1.323) (xy -2.763 -1.313)
			)
			(stroke
				(width 0.00186)
				(type solid)
			)
			(fill yes)
			(layer "F.Mask")
		)
		(fp_poly
			(pts
				(xy -7.153 -3.366) (xy -7.087 -3.351) (xy -7.086 -3.351) (xy -7.066 -3.34) (xy -7.021 -3.315) (xy -6.953 -3.277)
				(xy -6.865 -3.227) (xy -6.759 -3.167) (xy -6.639 -3.099) (xy -6.505 -3.022) (xy -6.361 -2.94) (xy -6.209 -2.853)
				(xy -6.052 -2.762) (xy -5.891 -2.67) (xy -5.729 -2.577) (xy -5.569 -2.485) (xy -5.413 -2.395) (xy -5.264 -2.309)
				(xy -5.123 -2.227) (xy -4.994 -2.152) (xy -4.878 -2.085) (xy -4.778 -2.027) (xy -4.697 -1.979) (xy -4.636 -1.943)
				(xy -4.599 -1.921) (xy -4.595 -1.918) (xy -4.528 -1.863) (xy -4.476 -1.798) (xy -4.434 -1.725) (xy -4.429 -0.224)
				(xy -4.429 0.063) (xy -4.428 0.323) (xy -4.429 0.553) (xy -4.429 0.755) (xy -4.43 0.928) (xy -4.432 1.071)
				(xy -4.434 1.184) (xy -4.436 1.266) (xy -4.439 1.318) (xy -4.441 1.337) (xy -4.448 1.36) (xy -4.454 1.382)
				(xy -4.463 1.403) (xy -4.476 1.423) (xy -4.494 1.445) (xy -4.519 1.47) (xy -4.552 1.497) (xy -4.596 1.529)
				(xy -4.652 1.567) (xy -4.721 1.611) (xy -4.805 1.663) (xy -4.906 1.723) (xy -5.025 1.794) (xy -5.165 1.875)
				(xy -5.326 1.969) (xy -5.511 2.076) (xy -5.72 2.197) (xy -5.813 2.251) (xy -7.079 2.982) (xy -7.197 2.988)
				(xy -7.315 2.994) (xy -7.78 2.727) (xy -8.064 2.563) (xy -8.323 2.415) (xy -8.557 2.28) (xy -8.767 2.159)
				(xy -8.955 2.051) (xy -9.122 1.954) (xy -9.27 1.868) (xy -9.399 1.792) (xy -9.51 1.726) (xy -9.606 1.669)
				(xy -9.688 1.619) (xy -9.756 1.576) (xy -9.812 1.539) (xy -9.857 1.507) (xy -9.893 1.481) (xy -9.92 1.458)
				(xy -9.94 1.437) (xy -9.955 1.42) (xy -9.965 1.403) (xy -9.972 1.387) (xy -9.977 1.371) (xy -9.981 1.354)
				(xy -9.985 1.337) (xy -9.988 1.309) (xy -9.991 1.25) (xy -9.993 1.161) (xy -9.995 1.041) (xy -9.996 0.891)
				(xy -9.997 0.712) (xy -9.998 0.503) (xy -9.998 0.266) (xy -9.997 0) (xy -9.997 -0.189) (xy -9.024 -0.189)
				(xy -9.024 0.015) (xy -9.024 0.191) (xy -9.023 0.34) (xy -9.022 0.464) (xy -9.021 0.567) (xy -9.018 0.65)
				(xy -9.014 0.717) (xy -9.01 0.768) (xy -9.003 0.808) (xy -8.995 0.837) (xy -8.986 0.859) (xy -8.974 0.876)
				(xy -8.961 0.891) (xy -8.945 0.905) (xy -8.943 0.906) (xy -8.922 0.921) (xy -8.877 0.949) (xy -8.81 0.989)
				(xy -8.725 1.039) (xy -8.625 1.098) (xy -8.512 1.164) (xy -8.389 1.235) (xy -8.26 1.31) (xy -8.128 1.386)
				(xy -7.995 1.463) (xy -7.864 1.538) (xy -7.739 1.609) (xy -7.622 1.676) (xy -7.517 1.735) (xy -7.425 1.787)
				(xy -7.351 1.828) (xy -7.297 1.857) (xy -7.266 1.872) (xy -7.261 1.874) (xy -7.222 1.885) (xy -7.195 1.886)
				(xy -7.163 1.875) (xy -7.144 1.867) (xy -7.117 1.854) (xy -7.067 1.827) (xy -6.997 1.788) (xy -6.909 1.738)
				(xy -6.805 1.679) (xy -6.691 1.614) (xy -6.567 1.543) (xy -6.438 1.469) (xy -6.306 1.392) (xy -6.174 1.316)
				(xy -6.045 1.241) (xy -5.922 1.17) (xy -5.809 1.103) (xy -5.708 1.044) (xy -5.622 0.992) (xy -5.553 0.952)
				(xy -5.507 0.923) (xy -5.484 0.907) (xy -5.483 0.907) (xy -5.467 0.892) (xy -5.453 0.878) (xy -5.441 0.861)
				(xy -5.431 0.839) (xy -5.423 0.81) (xy -5.417 0.772) (xy -5.412 0.721) (xy -5.408 0.656) (xy -5.406 0.574)
				(xy -5.404 0.473) (xy -5.403 0.35) (xy -5.402 0.203) (xy -5.402 0.03) (xy -5.402 -0.172) (xy -5.402 -0.189)
				(xy -5.402 -0.395) (xy -5.402 -0.572) (xy -5.403 -0.721) (xy -5.404 -0.847) (xy -5.406 -0.95) (xy -5.408 -1.034)
				(xy -5.412 -1.101) (xy -5.418 -1.153) (xy -5.425 -1.193) (xy -5.434 -1.223) (xy -5.445 -1.245) (xy -5.458 -1.262)
				(xy -5.473 -1.276) (xy -5.491 -1.29) (xy -5.499 -1.295) (xy -5.522 -1.31) (xy -5.57 -1.339) (xy -5.64 -1.381)
				(xy -5.729 -1.433) (xy -5.835 -1.496) (xy -5.956 -1.566) (xy -6.088 -1.643) (xy -6.229 -1.725) (xy -6.348 -1.793)
				(xy -6.519 -1.891) (xy -6.664 -1.974) (xy -6.786 -2.044) (xy -6.888 -2.101) (xy -6.971 -2.147) (xy -7.038 -2.183)
				(xy -7.091 -2.21) (xy -7.132 -2.229) (xy -7.163 -2.242) (xy -7.187 -2.249) (xy -7.205 -2.252) (xy -7.211 -2.252)
				(xy -7.228 -2.251) (xy -7.249 -2.246) (xy -7.276 -2.236) (xy -7.312 -2.219) (xy -7.359 -2.196) (xy -7.419 -2.165)
				(xy -7.495 -2.123) (xy -7.587 -2.072) (xy -7.699 -2.008) (xy -7.832 -1.932) (xy -7.99 -1.842) (xy -8.1 -1.778)
				(xy -8.248 -1.693) (xy -8.388 -1.611) (xy -8.519 -1.535) (xy -8.637 -1.466) (xy -8.739 -1.406) (xy -8.825 -1.355)
				(xy -8.89 -1.316) (xy -8.933 -1.29) (xy -8.951 -1.278) (xy -8.966 -1.265) (xy -8.978 -1.251) (xy -8.989 -1.234)
				(xy -8.998 -1.212) (xy -9.005 -1.182) (xy -9.011 -1.141) (xy -9.015 -1.087) (xy -9.018 -1.019) (xy -9.021 -0.933)
				(xy -9.022 -0.827) (xy -9.023 -0.699) (xy -9.024 -0.546) (xy -9.024 -0.366) (xy -9.024 -0.189) (xy -9.997 -0.189)
				(xy -9.997 -0.224) (xy -9.996 -0.479) (xy -9.996 -0.705) (xy -9.995 -0.903) (xy -9.994 -1.075) (xy -9.993 -1.223)
				(xy -9.992 -1.35) (xy -9.99 -1.456) (xy -9.987 -1.545) (xy -9.984 -1.617) (xy -9.98 -1.675) (xy -9.974 -1.721)
				(xy -9.968 -1.757) (xy -9.961 -1.784) (xy -9.952 -1.805) (xy -9.941 -1.821) (xy -9.929 -1.834) (xy -9.915 -1.847)
				(xy -9.9 -1.86) (xy -9.893 -1.866) (xy -9.873 -1.88) (xy -9.828 -1.909) (xy -9.759 -1.951) (xy -9.669 -2.005)
				(xy -9.56 -2.07) (xy -9.433 -2.145) (xy -9.291 -2.228) (xy -9.136 -2.319) (xy -8.969 -2.416) (xy -8.793 -2.518)
				(xy -8.61 -2.624) (xy -8.59 -2.635) (xy -8.377 -2.759) (xy -8.189 -2.867) (xy -8.024 -2.962) (xy -7.882 -3.044)
				(xy -7.759 -3.114) (xy -7.656 -3.173) (xy -7.568 -3.221) (xy -7.496 -3.261) (xy -7.437 -3.293) (xy -7.389 -3.317)
				(xy -7.351 -3.336) (xy -7.321 -3.349) (xy -7.296 -3.357) (xy -7.276 -3.363) (xy -7.259 -3.366) (xy -7.242 -3.367)
				(xy -7.237 -3.368) (xy -7.153 -3.366)
			)
			(stroke
				(width 0.00186)
				(type solid)
			)
			(fill yes)
			(layer "F.Mask")
		)
		(fp_poly
			(pts
				(xy -7.128 -1.48) (xy -7.114 -1.475) (xy -7.042 -1.428) (xy -6.989 -1.361) (xy -6.96 -1.281) (xy -6.957 -1.196)
				(xy -6.961 -1.175) (xy -6.992 -1.094) (xy -7.046 -1.034) (xy -7.101 -1.001) (xy -7.166 -0.969) (xy -7.166 -0.599)
				(xy -6.891 -0.599) (xy -6.778 -0.711) (xy -6.665 -0.824) (xy -6.673 -0.905) (xy -6.673 -0.906) (xy -6.566 -0.906)
				(xy -6.549 -0.87) (xy -6.512 -0.853) (xy -6.467 -0.856) (xy -6.435 -0.876) (xy -6.412 -0.913) (xy -6.42 -0.95)
				(xy -6.441 -0.977) (xy -6.471 -1.002) (xy -6.496 -1.005) (xy -6.53 -0.986) (xy -6.532 -0.984) (xy -6.56 -0.949)
				(xy -6.566 -0.906) (xy -6.673 -0.906) (xy -6.676 -0.957) (xy -6.669 -0.992) (xy -6.648 -1.025) (xy -6.639 -1.036)
				(xy -6.582 -1.084) (xy -6.519 -1.106) (xy -6.456 -1.105) (xy -6.397 -1.084) (xy -6.349 -1.044) (xy -6.316 -0.99)
				(xy -6.304 -0.925) (xy -6.315 -0.859) (xy -6.351 -0.797) (xy -6.408 -0.757) (xy -6.484 -0.741) (xy -6.497 -0.741)
				(xy -6.529 -0.74) (xy -6.557 -0.734) (xy -6.585 -0.719) (xy -6.619 -0.693) (xy -6.667 -0.651) (xy -6.705 -0.615)
				(xy -6.84 -0.489) (xy -7.166 -0.489) (xy -7.166 -0.237) (xy -6.568 -0.237) (xy -6.545 -0.282) (xy -6.502 -0.333)
				(xy -6.443 -0.364) (xy -6.377 -0.373) (xy -6.311 -0.36) (xy -6.255 -0.322) (xy -6.249 -0.317) (xy -6.209 -0.253)
				(xy -6.195 -0.188) (xy -6.205 -0.126) (xy -6.234 -0.072) (xy -6.28 -0.03) (xy -6.337 -0.006) (xy -6.402 -0.002)
				(xy -6.472 -0.025) (xy -6.486 -0.033) (xy -6.523 -0.061) (xy -6.545 -0.091) (xy -6.547 -0.096) (xy -6.552 -0.106)
				(xy -6.561 -0.114) (xy -6.58 -0.12) (xy -6.613 -0.123) (xy -6.664 -0.125) (xy -6.737 -0.126) (xy -6.836 -0.126)
				(xy -6.861 -0.126) (xy -7.166 -0.126) (xy -7.166 0.11) (xy -6.842 0.11) (xy -6.581 0.373) (xy -6.507 0.366)
				(xy -6.428 0.372) (xy -6.367 0.402) (xy -6.325 0.457) (xy -6.314 0.486) (xy -6.304 0.561) (xy -6.322 0.626)
				(xy -6.361 0.678) (xy -6.422 0.72) (xy -6.487 0.736) (xy -6.55 0.727) (xy -6.605 0.697) (xy -6.648 0.648)
				(xy -6.671 0.583) (xy -6.672 0.536) (xy -6.564 0.536) (xy -6.559 0.575) (xy -6.544 0.597) (xy -6.508 0.625)
				(xy -6.474 0.623) (xy -6.441 0.598) (xy -6.414 0.56) (xy -6.417 0.525) (xy -6.44 0.497) (xy -6.48 0.476)
				(xy -6.518 0.48) (xy -6.549 0.502) (xy -6.564 0.536) (xy -6.672 0.536) (xy -6.673 0.52) (xy -6.664 0.445)
				(xy -6.891 0.22) (xy -7.166 0.22) (xy -7.166 0.593) (xy -7.101 0.622) (xy -7.033 0.668) (xy -6.986 0.732)
				(xy -6.96 0.805) (xy -6.956 0.883) (xy -6.973 0.959) (xy -7.013 1.026) (xy -7.074 1.079) (xy -7.088 1.087)
				(xy -7.171 1.112) (xy -7.258 1.112) (xy -7.34 1.087) (xy -7.341 1.086) (xy -7.406 1.036) (xy -7.448 0.97)
				(xy -7.469 0.895) (xy -7.468 0.858) (xy -7.361 0.858) (xy -7.355 0.905) (xy -7.331 0.942) (xy -7.31 0.962)
				(xy -7.252 0.999) (xy -7.195 1.005) (xy -7.137 0.979) (xy -7.116 0.962) (xy -7.08 0.923) (xy -7.066 0.883)
				(xy -7.065 0.858) (xy -7.079 0.801) (xy -7.116 0.751) (xy -7.167 0.718) (xy -7.213 0.708) (xy -7.27 0.722)
				(xy -7.319 0.76) (xy -7.352 0.812) (xy -7.361 0.858) (xy -7.468 0.858) (xy -7.468 0.817) (xy -7.445 0.742)
				(xy -7.401 0.677) (xy -7.336 0.628) (xy -7.325 0.622) (xy -7.26 0.593) (xy -7.26 0.22) (xy -7.535 0.22)
				(xy -7.762 0.445) (xy -7.753 0.52) (xy -7.757 0.595) (xy -7.785 0.658) (xy -7.83 0.703) (xy -7.887 0.73)
				(xy -7.951 0.735) (xy -8.015 0.715) (xy -8.065 0.678) (xy -8.109 0.617) (xy -8.123 0.551) (xy -8.12 0.532)
				(xy -8.012 0.532) (xy -8.009 0.566) (xy -7.985 0.598) (xy -7.946 0.625) (xy -7.912 0.623) (xy -7.883 0.599)
				(xy -7.863 0.558) (xy -7.868 0.517) (xy -7.896 0.486) (xy -7.915 0.478) (xy -7.961 0.48) (xy -7.985 0.496)
				(xy -8.012 0.532) (xy -8.12 0.532) (xy -8.112 0.486) (xy -8.079 0.422) (xy -8.025 0.381) (xy -7.953 0.365)
				(xy -7.919 0.366) (xy -7.845 0.373) (xy -7.584 0.11) (xy -7.26 0.11) (xy -7.26 -0.126) (xy -7.566 -0.126)
				(xy -7.672 -0.126) (xy -7.75 -0.126) (xy -7.805 -0.124) (xy -7.841 -0.121) (xy -7.863 -0.116) (xy -7.875 -0.108)
				(xy -7.881 -0.098) (xy -7.883 -0.094) (xy -7.908 -0.058) (xy -7.954 -0.026) (xy -8.009 -0.005) (xy -8.045 -0.001)
				(xy -8.117 -0.014) (xy -8.174 -0.049) (xy -8.213 -0.102) (xy -8.23 -0.164) (xy -8.228 -0.186) (xy -8.124 -0.186)
				(xy -8.12 -0.163) (xy -8.104 -0.143) (xy -8.063 -0.115) (xy -8.021 -0.117) (xy -7.994 -0.135) (xy -7.971 -0.176)
				(xy -7.976 -0.202) (xy -6.455 -0.202) (xy -6.449 -0.158) (xy -6.432 -0.135) (xy -6.392 -0.113) (xy -6.35 -0.121)
				(xy -6.322 -0.143) (xy -6.303 -0.169) (xy -6.304 -0.193) (xy -6.316 -0.218) (xy -6.35 -0.254) (xy -6.39 -0.265)
				(xy -6.429 -0.247) (xy -6.432 -0.244) (xy -6.455 -0.202) (xy -7.976 -0.202) (xy -7.979 -0.218) (xy -7.999 -0.244)
				(xy -8.04 -0.265) (xy -8.078 -0.255) (xy -8.11 -0.218) (xy -8.124 -0.186) (xy -8.228 -0.186) (xy -8.224 -0.232)
				(xy -8.192 -0.297) (xy -8.177 -0.317) (xy -8.121 -0.358) (xy -8.055 -0.374) (xy -7.988 -0.365) (xy -7.927 -0.333)
				(xy -7.885 -0.284) (xy -7.857 -0.237) (xy -7.26 -0.237) (xy -7.26 -0.489) (xy -7.586 -0.489) (xy -7.721 -0.615)
				(xy -7.779 -0.669) (xy -7.821 -0.704) (xy -7.852 -0.726) (xy -7.879 -0.737) (xy -7.908 -0.74) (xy -7.934 -0.741)
				(xy -8.011 -0.752) (xy -8.068 -0.787) (xy -8.105 -0.846) (xy -8.112 -0.866) (xy -8.119 -0.923) (xy -8.016 -0.923)
				(xy -8.003 -0.887) (xy -7.969 -0.862) (xy -7.928 -0.852) (xy -7.888 -0.861) (xy -7.878 -0.87) (xy -7.86 -0.907)
				(xy -7.866 -0.949) (xy -7.894 -0.984) (xy -7.924 -1.002) (xy -7.941 -1.008) (xy -7.964 -0.997) (xy -7.991 -0.969)
				(xy -8.011 -0.939) (xy -8.016 -0.923) (xy -8.119 -0.923) (xy -8.121 -0.94) (xy -8.105 -1.004) (xy -8.069 -1.055)
				(xy -8.018 -1.091) (xy -7.958 -1.108) (xy -7.894 -1.104) (xy -7.831 -1.076) (xy -7.787 -1.036) (xy -7.762 -1.001)
				(xy -7.751 -0.968) (xy -7.751 -0.923) (xy -7.753 -0.905) (xy -7.762 -0.824) (xy -7.648 -0.711) (xy -7.535 -0.599)
				(xy -7.26 -0.599) (xy -7.26 -0.971) (xy -7.323 -0.998) (xy -7.396 -1.046) (xy -7.446 -1.114) (xy -7.465 -1.166)
				(xy -7.472 -1.24) (xy -7.365 -1.24) (xy -7.359 -1.204) (xy -7.347 -1.177) (xy -7.307 -1.123) (xy -7.254 -1.093)
				(xy -7.194 -1.09) (xy -7.134 -1.116) (xy -7.127 -1.121) (xy -7.081 -1.171) (xy -7.065 -1.225) (xy -7.078 -1.283)
				(xy -7.116 -1.342) (xy -7.166 -1.375) (xy -7.222 -1.384) (xy -7.278 -1.368) (xy -7.326 -1.326) (xy -7.354 -1.278)
				(xy -7.365 -1.24) (xy -7.472 -1.24) (xy -7.474 -1.25) (xy -7.455 -1.328) (xy -7.416 -1.396) (xy -7.358 -1.449)
				(xy -7.288 -1.484) (xy -7.21 -1.495) (xy -7.128 -1.48)
			)
			(stroke
				(width 0.00186)
				(type solid)
			)
			(fill yes)
			(layer "F.Mask")
		)
	)
	(footprint "antmicro-footprints:oshw-logo"
		(layer "F.Cu")
		(at 161.775 74.25)
		(descr "OSHW Logo")
		(tags "OSHW Logo")
		(property "Reference" "N2"
			(at 0 -4.4 0)
			(layer "F.SilkS")
			(hide yes)
			(effects
				(font
					(size 0.7 0.7)
					(thickness 0.15)
				)
				(justify left bottom)
			)
		)
		(property "Value" "oshw_logo"
			(at 0 -3.4 0)
			(layer "F.Fab")
			(hide yes)
			(effects
				(font
					(size 0.7 0.7)
					(thickness 0.15)
				)
				(justify left bottom)
			)
		)
		(property "Author" "Antmicro"
			(at 0 0 0)
			(layer "F.Fab")
			(hide yes)
			(effects
				(font
					(size 1 1)
					(thickness 0.15)
				)
			)
		)
		(property "License" "Apache-2.0"
			(at 0 0 0)
			(layer "F.Fab")
			(hide yes)
			(effects
				(font
					(size 1 1)
					(thickness 0.15)
				)
			)
		)
		(property "MPN" ""
			(at 0 0 0)
			(layer "F.Fab")
			(hide yes)
			(effects
				(font
					(size 1 1)
					(thickness 0.15)
				)
			)
		)
		(property "Manufacturer" ""
			(at 0 0 0)
			(layer "F.Fab")
			(hide yes)
			(effects
				(font
					(size 1 1)
					(thickness 0.15)
				)
			)
		)
		(sheetfile "ddr5-testbed.kicad_sch")
		(attr exclude_from_pos_files allow_soldermask_bridges)
		(fp_poly
			(pts
				(xy -0.843 2.558) (xy -0.815 2.564) (xy -0.794 2.572) (xy -0.773 2.581) (xy -0.759 2.589) (xy -0.738 2.603)
				(xy -0.783 2.658) (xy -0.8 2.677) (xy -0.814 2.694) (xy -0.825 2.706) (xy -0.831 2.712) (xy -0.832 2.712)
				(xy -0.837 2.71) (xy -0.847 2.703) (xy -0.849 2.702) (xy -0.874 2.69) (xy -0.904 2.684) (xy -0.935 2.685)
				(xy -0.942 2.686) (xy -0.975 2.698) (xy -1.001 2.717) (xy -1.02 2.741) (xy -1.034 2.766) (xy -1.039 3.197)
				(xy -1.164 3.2) (xy -1.164 2.565) (xy -1.037 2.565) (xy -1.037 2.626) (xy -1.009 2.604) (xy -0.972 2.579)
				(xy -0.931 2.563) (xy -0.887 2.556) (xy -0.843 2.558)
			)
			(stroke
				(width 0.01)
				(type solid)
			)
			(fill yes)
			(layer "F.Cu")
		)
		(fp_poly
			(pts
				(xy 1.889 1.554) (xy 1.907 1.559) (xy 1.927 1.566) (xy 1.948 1.574) (xy 1.966 1.583) (xy 1.979 1.592)
				(xy 1.984 1.597) (xy 1.982 1.604) (xy 1.974 1.616) (xy 1.962 1.633) (xy 1.946 1.652) (xy 1.945 1.654)
				(xy 1.929 1.673) (xy 1.915 1.689) (xy 1.906 1.7) (xy 1.901 1.706) (xy 1.896 1.705) (xy 1.885 1.7)
				(xy 1.873 1.695) (xy 1.84 1.683) (xy 1.808 1.68) (xy 1.776 1.685) (xy 1.747 1.698) (xy 1.723 1.717)
				(xy 1.704 1.742) (xy 1.696 1.763) (xy 1.695 1.772) (xy 1.694 1.79) (xy 1.693 1.817) (xy 1.692 1.85)
				(xy 1.692 1.89) (xy 1.691 1.934) (xy 1.691 1.983) (xy 1.691 2.194) (xy 1.559 2.194) (xy 1.559 1.559)
				(xy 1.691 1.559) (xy 1.691 1.626) (xy 1.71 1.607) (xy 1.739 1.585) (xy 1.775 1.568) (xy 1.814 1.556)
				(xy 1.855 1.552) (xy 1.889 1.554)
			)
			(stroke
				(width 0.01)
				(type solid)
			)
			(fill yes)
			(layer "F.Cu")
		)
		(fp_poly
			(pts
				(xy -0.837 1.56) (xy -0.797 1.576) (xy -0.761 1.6) (xy -0.73 1.63) (xy -0.706 1.667) (xy -0.69 1.709)
				(xy -0.687 1.721) (xy -0.685 1.734) (xy -0.684 1.757) (xy -0.683 1.79) (xy -0.682 1.833) (xy -0.681 1.884)
				(xy -0.681 1.945) (xy -0.681 1.971) (xy -0.681 2.194) (xy -0.808 2.194) (xy -0.809 1.984) (xy -0.811 1.774)
				(xy -0.826 1.744) (xy -0.845 1.716) (xy -0.868 1.697) (xy -0.897 1.686) (xy -0.925 1.682) (xy -0.947 1.682)
				(xy -0.967 1.684) (xy -0.979 1.686) (xy -1.001 1.698) (xy -1.023 1.716) (xy -1.041 1.738) (xy -1.049 1.752)
				(xy -1.052 1.758) (xy -1.054 1.765) (xy -1.056 1.773) (xy -1.057 1.783) (xy -1.058 1.797) (xy -1.059 1.815)
				(xy -1.06 1.839) (xy -1.06 1.869) (xy -1.061 1.907) (xy -1.061 1.953) (xy -1.061 1.985) (xy -1.063 2.194)
				(xy -1.189 2.194) (xy -1.189 1.559) (xy -1.062 1.559) (xy -1.062 1.625) (xy -1.033 1.602) (xy -1.001 1.579)
				(xy -0.969 1.564) (xy -0.934 1.555) (xy -0.927 1.554) (xy -0.881 1.553) (xy -0.837 1.56)
			)
			(stroke
				(width 0.01)
				(type solid)
			)
			(fill yes)
			(layer "F.Cu")
		)
		(fp_poly
			(pts
				(xy 1.042 1.769) (xy 1.043 1.979) (xy 1.059 2.009) (xy 1.077 2.036) (xy 1.1 2.056) (xy 1.129 2.067)
				(xy 1.159 2.071) (xy 1.193 2.07) (xy 1.221 2.063) (xy 1.245 2.047) (xy 1.258 2.034) (xy 1.266 2.025)
				(xy 1.273 2.016) (xy 1.278 2.008) (xy 1.282 1.997) (xy 1.286 1.985) (xy 1.288 1.969) (xy 1.29 1.948)
				(xy 1.291 1.922) (xy 1.292 1.89) (xy 1.293 1.85) (xy 1.293 1.801) (xy 1.294 1.766) (xy 1.295 1.559)
				(xy 1.422 1.559) (xy 1.422 2.194) (xy 1.295 2.194) (xy 1.295 2.161) (xy 1.295 2.144) (xy 1.293 2.132)
				(xy 1.292 2.128) (xy 1.287 2.131) (xy 1.278 2.14) (xy 1.271 2.147) (xy 1.256 2.159) (xy 1.236 2.171)
				(xy 1.219 2.181) (xy 1.202 2.188) (xy 1.186 2.193) (xy 1.17 2.196) (xy 1.148 2.197) (xy 1.135 2.198)
				(xy 1.107 2.198) (xy 1.087 2.197) (xy 1.07 2.194) (xy 1.059 2.19) (xy 1.036 2.181) (xy 1.019 2.172)
				(xy 1.003 2.161) (xy 0.985 2.146) (xy 0.981 2.141) (xy 0.952 2.107) (xy 0.931 2.068) (xy 0.92 2.033)
				(xy 0.918 2.019) (xy 0.917 1.996) (xy 0.916 1.963) (xy 0.915 1.92) (xy 0.914 1.869) (xy 0.914 1.808)
				(xy 0.914 1.782) (xy 0.914 1.559) (xy 1.04 1.559) (xy 1.042 1.769)
			)
			(stroke
				(width 0.01)
				(type solid)
			)
			(fill yes)
			(layer "F.Cu")
		)
		(fp_poly
			(pts
				(xy 1.753 2.563) (xy 1.768 2.568) (xy 1.787 2.577) (xy 1.804 2.586) (xy 1.818 2.595) (xy 1.826 2.602)
				(xy 1.827 2.606) (xy 1.824 2.611) (xy 1.815 2.621) (xy 1.803 2.636) (xy 1.789 2.654) (xy 1.775 2.671)
				(xy 1.761 2.688) (xy 1.749 2.701) (xy 1.742 2.71) (xy 1.739 2.712) (xy 1.735 2.71) (xy 1.724 2.704)
				(xy 1.713 2.698) (xy 1.697 2.69) (xy 1.682 2.686) (xy 1.664 2.685) (xy 1.653 2.685) (xy 1.618 2.688)
				(xy 1.59 2.699) (xy 1.566 2.718) (xy 1.561 2.723) (xy 1.554 2.732) (xy 1.548 2.74) (xy 1.544 2.748)
				(xy 1.54 2.758) (xy 1.537 2.769) (xy 1.534 2.785) (xy 1.533 2.804) (xy 1.532 2.829) (xy 1.531 2.861)
				(xy 1.53 2.899) (xy 1.53 2.947) (xy 1.53 2.988) (xy 1.528 3.2) (xy 1.468 3.2) (xy 1.444 3.2) (xy 1.425 3.199)
				(xy 1.411 3.198) (xy 1.405 3.197) (xy 1.404 3.191) (xy 1.404 3.176) (xy 1.403 3.153) (xy 1.403 3.122)
				(xy 1.402 3.085) (xy 1.402 3.042) (xy 1.402 2.993) (xy 1.402 2.941) (xy 1.402 2.886) (xy 1.402 2.565)
				(xy 1.529 2.565) (xy 1.529 2.595) (xy 1.529 2.611) (xy 1.53 2.623) (xy 1.532 2.626) (xy 1.537 2.623)
				(xy 1.547 2.615) (xy 1.554 2.608) (xy 1.588 2.584) (xy 1.627 2.567) (xy 1.669 2.558) (xy 1.712 2.556)
				(xy 1.753 2.563)
			)
			(stroke
				(width 0.01)
				(type solid)
			)
			(fill yes)
			(layer "F.Cu")
		)
		(fp_poly
			(pts
				(xy 2.316 1.557) (xy 2.365 1.57) (xy 2.41 1.593) (xy 2.453 1.625) (xy 2.46 1.631) (xy 2.491 1.661)
				(xy 2.466 1.684) (xy 2.448 1.699) (xy 2.43 1.715) (xy 2.419 1.725) (xy 2.397 1.743) (xy 2.376 1.724)
				(xy 2.345 1.701) (xy 2.312 1.687) (xy 2.274 1.681) (xy 2.265 1.681) (xy 2.226 1.684) (xy 2.195 1.693)
				(xy 2.167 1.708) (xy 2.159 1.715) (xy 2.136 1.741) (xy 2.118 1.776) (xy 2.107 1.817) (xy 2.103 1.866)
				(xy 2.103 1.876) (xy 2.106 1.926) (xy 2.116 1.97) (xy 2.132 2.006) (xy 2.155 2.034) (xy 2.184 2.055)
				(xy 2.219 2.067) (xy 2.259 2.072) (xy 2.274 2.071) (xy 2.309 2.066) (xy 2.339 2.056) (xy 2.366 2.038)
				(xy 2.377 2.028) (xy 2.386 2.02) (xy 2.393 2.016) (xy 2.4 2.015) (xy 2.409 2.018) (xy 2.42 2.027)
				(xy 2.436 2.041) (xy 2.456 2.059) (xy 2.491 2.092) (xy 2.476 2.108) (xy 2.449 2.132) (xy 2.416 2.155)
				(xy 2.38 2.174) (xy 2.35 2.186) (xy 2.327 2.193) (xy 2.306 2.197) (xy 2.283 2.199) (xy 2.259 2.199)
				(xy 2.233 2.198) (xy 2.209 2.196) (xy 2.189 2.193) (xy 2.182 2.191) (xy 2.133 2.173) (xy 2.089 2.146)
				(xy 2.053 2.112) (xy 2.023 2.071) (xy 2.012 2.051) (xy 2 2.023) (xy 1.991 1.999) (xy 1.984 1.975)
				(xy 1.981 1.948) (xy 1.979 1.917) (xy 1.978 1.879) (xy 1.978 1.877) (xy 1.979 1.838) (xy 1.98 1.806)
				(xy 1.984 1.78) (xy 1.99 1.756) (xy 1.999 1.731) (xy 2.011 1.704) (xy 2.012 1.701) (xy 2.039 1.657)
				(xy 2.072 1.62) (xy 2.111 1.591) (xy 2.156 1.57) (xy 2.207 1.557) (xy 2.263 1.552) (xy 2.316 1.557)
			)
			(stroke
				(width 0.01)
				(type solid)
			)
			(fill yes)
			(layer "F.Cu")
		)
		(fp_poly
			(pts
				(xy -1.494 1.56) (xy -1.447 1.576) (xy -1.405 1.6) (xy -1.368 1.633) (xy -1.341 1.668) (xy -1.326 1.692)
				(xy -1.316 1.716) (xy -1.308 1.743) (xy -1.302 1.774) (xy -1.299 1.811) (xy -1.297 1.845) (xy -1.294 1.925)
				(xy -1.692 1.925) (xy -1.692 1.942) (xy -1.687 1.977) (xy -1.673 2.011) (xy -1.65 2.039) (xy -1.626 2.059)
				(xy -1.601 2.071) (xy -1.572 2.078) (xy -1.537 2.079) (xy -1.497 2.074) (xy -1.458 2.06) (xy -1.422 2.036)
				(xy -1.421 2.036) (xy -1.402 2.021) (xy -1.359 2.057) (xy -1.342 2.072) (xy -1.327 2.085) (xy -1.317 2.094)
				(xy -1.314 2.098) (xy -1.316 2.103) (xy -1.324 2.113) (xy -1.338 2.126) (xy -1.354 2.139) (xy -1.372 2.152)
				(xy -1.389 2.163) (xy -1.399 2.168) (xy -1.421 2.178) (xy -1.445 2.187) (xy -1.461 2.191) (xy -1.488 2.196)
				(xy -1.522 2.199) (xy -1.557 2.199) (xy -1.591 2.196) (xy -1.62 2.192) (xy -1.629 2.19) (xy -1.677 2.171)
				(xy -1.718 2.146) (xy -1.752 2.114) (xy -1.779 2.074) (xy -1.8 2.026) (xy -1.802 2.02) (xy -1.81 1.989)
				(xy -1.815 1.951) (xy -1.818 1.908) (xy -1.819 1.865) (xy -1.818 1.823) (xy -1.816 1.804) (xy -1.692 1.804)
				(xy -1.692 1.818) (xy -1.428 1.818) (xy -1.428 1.801) (xy -1.432 1.775) (xy -1.442 1.748) (xy -1.457 1.722)
				(xy -1.469 1.707) (xy -1.495 1.688) (xy -1.526 1.676) (xy -1.56 1.672) (xy -1.593 1.676) (xy -1.619 1.685)
				(xy -1.646 1.704) (xy -1.668 1.73) (xy -1.683 1.76) (xy -1.691 1.792) (xy -1.692 1.804) (xy -1.816 1.804)
				(xy -1.814 1.786) (xy -1.812 1.777) (xy -1.797 1.724) (xy -1.775 1.676) (xy -1.747 1.636) (xy -1.713 1.603)
				(xy -1.673 1.578) (xy -1.629 1.561) (xy -1.597 1.554) (xy -1.544 1.552) (xy -1.494 1.56)
			)
			(stroke
				(width 0.01)
				(type solid)
			)
			(fill yes)
			(layer "F.Cu")
		)
		(fp_poly
			(pts
				(xy 2.835 1.557) (xy 2.883 1.57) (xy 2.926 1.592) (xy 2.964 1.621) (xy 2.996 1.657) (xy 3.021 1.699)
				(xy 3.038 1.747) (xy 3.04 1.757) (xy 3.043 1.776) (xy 3.045 1.802) (xy 3.047 1.832) (xy 3.047 1.858)
				(xy 3.047 1.925) (xy 2.65 1.925) (xy 2.653 1.951) (xy 2.663 1.991) (xy 2.68 2.024) (xy 2.703 2.049)
				(xy 2.733 2.067) (xy 2.77 2.077) (xy 2.801 2.079) (xy 2.845 2.075) (xy 2.883 2.063) (xy 2.916 2.042)
				(xy 2.92 2.039) (xy 2.929 2.031) (xy 2.935 2.026) (xy 2.941 2.025) (xy 2.949 2.027) (xy 2.959 2.034)
				(xy 2.974 2.047) (xy 2.994 2.064) (xy 3.01 2.078) (xy 3.023 2.088) (xy 3.03 2.095) (xy 3.032 2.096)
				(xy 3.03 2.1) (xy 3.022 2.11) (xy 3.01 2.122) (xy 3.009 2.123) (xy 2.98 2.147) (xy 2.945 2.169)
				(xy 2.906 2.185) (xy 2.887 2.191) (xy 2.861 2.196) (xy 2.828 2.198) (xy 2.793 2.198) (xy 2.759 2.197)
				(xy 2.729 2.193) (xy 2.721 2.191) (xy 2.675 2.175) (xy 2.634 2.15) (xy 2.599 2.118) (xy 2.569 2.077)
				(xy 2.547 2.029) (xy 2.536 1.996) (xy 2.532 1.973) (xy 2.529 1.942) (xy 2.527 1.906) (xy 2.527 1.869)
				(xy 2.528 1.832) (xy 2.529 1.818) (xy 2.65 1.818) (xy 2.922 1.818) (xy 2.918 1.799) (xy 2.908 1.758)
				(xy 2.891 1.725) (xy 2.869 1.7) (xy 2.84 1.683) (xy 2.826 1.678) (xy 2.788 1.672) (xy 2.753 1.675)
				(xy 2.722 1.687) (xy 2.695 1.706) (xy 2.674 1.734) (xy 2.659 1.768) (xy 2.654 1.794) (xy 2.65 1.818)
				(xy 2.529 1.818) (xy 2.53 1.798) (xy 2.534 1.769) (xy 2.536 1.76) (xy 2.554 1.707) (xy 2.578 1.662)
				(xy 2.609 1.624) (xy 2.645 1.593) (xy 2.687 1.571) (xy 2.734 1.557) (xy 2.783 1.553) (xy 2.835 1.557)
			)
			(stroke
				(width 0.01)
				(type solid)
			)
			(fill yes)
			(layer "F.Cu")
		)
		(fp_poly
			(pts
				(xy -2.733 1.557) (xy -2.685 1.57) (xy -2.642 1.592) (xy -2.604 1.622) (xy -2.581 1.649) (xy -2.562 1.676)
				(xy -2.548 1.706) (xy -2.537 1.739) (xy -2.53 1.777) (xy -2.527 1.821) (xy -2.526 1.873) (xy -2.527 1.907)
				(xy -2.529 1.956) (xy -2.534 1.997) (xy -2.542 2.031) (xy -2.553 2.06) (xy -2.567 2.086) (xy -2.587 2.111)
				(xy -2.603 2.129) (xy -2.637 2.158) (xy -2.673 2.178) (xy -2.714 2.192) (xy -2.76 2.198) (xy -2.789 2.199)
				(xy -2.813 2.198) (xy -2.835 2.196) (xy -2.852 2.194) (xy -2.857 2.194) (xy -2.898 2.179) (xy -2.937 2.155)
				(xy -2.97 2.126) (xy -2.993 2.101) (xy -3.011 2.077) (xy -3.024 2.051) (xy -3.034 2.022) (xy -3.041 1.988)
				(xy -3.045 1.947) (xy -3.047 1.91) (xy -3.047 1.882) (xy -2.919 1.882) (xy -2.919 1.968) (xy -2.903 2.001)
				(xy -2.885 2.031) (xy -2.863 2.051) (xy -2.837 2.064) (xy -2.804 2.07) (xy -2.779 2.07) (xy -2.755 2.069)
				(xy -2.737 2.065) (xy -2.722 2.058) (xy -2.717 2.055) (xy -2.697 2.041) (xy -2.681 2.025) (xy -2.67 2.004)
				(xy -2.662 1.978) (xy -2.657 1.945) (xy -2.654 1.903) (xy -2.654 1.899) (xy -2.653 1.848) (xy -2.656 1.806)
				(xy -2.662 1.772) (xy -2.673 1.744) (xy -2.687 1.722) (xy -2.707 1.705) (xy -2.723 1.695) (xy -2.755 1.684)
				(xy -2.788 1.68) (xy -2.821 1.684) (xy -2.851 1.695) (xy -2.877 1.713) (xy -2.892 1.729) (xy -2.901 1.745)
				(xy -2.908 1.76) (xy -2.913 1.778) (xy -2.916 1.8) (xy -2.918 1.828) (xy -2.919 1.864) (xy -2.919 1.882)
				(xy -3.047 1.882) (xy -3.048 1.844) (xy -3.043 1.786) (xy -3.034 1.736) (xy -3.021 1.695) (xy -3.004 1.664)
				(xy -2.972 1.624) (xy -2.935 1.594) (xy -2.893 1.571) (xy -2.846 1.558) (xy -2.794 1.553) (xy -2.787 1.553)
				(xy -2.733 1.557)
			)
			(stroke
				(width 0.01)
				(type solid)
			)
			(fill yes)
			(layer "F.Cu")
		)
		(fp_poly
			(pts
				(xy 2.148 2.561) (xy 2.193 2.574) (xy 2.235 2.595) (xy 2.273 2.623) (xy 2.304 2.657) (xy 2.326 2.691)
				(xy 2.338 2.718) (xy 2.346 2.745) (xy 2.352 2.774) (xy 2.355 2.808) (xy 2.357 2.85) (xy 2.357 2.858)
				(xy 2.357 2.931) (xy 1.96 2.931) (xy 1.963 2.955) (xy 1.973 2.993) (xy 1.991 3.026) (xy 2.015 3.053)
				(xy 2.039 3.069) (xy 2.057 3.076) (xy 2.08 3.08) (xy 2.103 3.082) (xy 2.144 3.081) (xy 2.18 3.071)
				(xy 2.214 3.054) (xy 2.227 3.045) (xy 2.24 3.035) (xy 2.25 3.029) (xy 2.253 3.027) (xy 2.258 3.03)
				(xy 2.269 3.039) (xy 2.284 3.05) (xy 2.3 3.064) (xy 2.315 3.078) (xy 2.329 3.09) (xy 2.338 3.099)
				(xy 2.341 3.103) (xy 2.337 3.11) (xy 2.327 3.121) (xy 2.312 3.134) (xy 2.294 3.148) (xy 2.276 3.161)
				(xy 2.259 3.171) (xy 2.252 3.175) (xy 2.204 3.192) (xy 2.152 3.202) (xy 2.098 3.204) (xy 2.046 3.198)
				(xy 2.032 3.195) (xy 1.984 3.178) (xy 1.943 3.154) (xy 1.909 3.123) (xy 1.881 3.084) (xy 1.859 3.037)
				(xy 1.847 3.003) (xy 1.841 2.972) (xy 1.838 2.934) (xy 1.836 2.893) (xy 1.837 2.851) (xy 1.839 2.824)
				(xy 1.96 2.824) (xy 2.23 2.824) (xy 2.23 2.813) (xy 2.225 2.783) (xy 2.214 2.753) (xy 2.196 2.725)
				(xy 2.175 2.702) (xy 2.151 2.686) (xy 2.128 2.68) (xy 2.101 2.677) (xy 2.072 2.678) (xy 2.051 2.683)
				(xy 2.023 2.696) (xy 2 2.717) (xy 1.981 2.746) (xy 1.968 2.779) (xy 1.963 2.8) (xy 1.96 2.824) (xy 1.839 2.824)
				(xy 1.839 2.811) (xy 1.844 2.776) (xy 1.848 2.76) (xy 1.866 2.708) (xy 1.889 2.663) (xy 1.919 2.627)
				(xy 1.954 2.598) (xy 1.996 2.575) (xy 2.007 2.571) (xy 2.054 2.559) (xy 2.101 2.556) (xy 2.148 2.561)
			)
			(stroke
				(width 0.01)
				(type solid)
			)
			(fill yes)
			(layer "F.Cu")
		)
		(fp_poly
			(pts
				(xy -0.229 3.2) (xy -0.354 3.197) (xy -0.355 3.165) (xy -0.357 3.133) (xy -0.374 3.148) (xy -0.411 3.175)
				(xy -0.453 3.193) (xy -0.497 3.203) (xy -0.542 3.204) (xy -0.585 3.195) (xy -0.586 3.195) (xy -0.621 3.181)
				(xy -0.651 3.16) (xy -0.673 3.141) (xy -0.689 3.123) (xy -0.702 3.106) (xy -0.712 3.086) (xy -0.72 3.064)
				(xy -0.726 3.038) (xy -0.73 3.007) (xy -0.732 2.968) (xy -0.733 2.922) (xy -0.733 2.88) (xy -0.602 2.88)
				(xy -0.602 2.915) (xy -0.602 2.942) (xy -0.601 2.962) (xy -0.6 2.977) (xy -0.598 2.988) (xy -0.596 2.998)
				(xy -0.592 3.007) (xy -0.591 3.01) (xy -0.574 3.039) (xy -0.552 3.059) (xy -0.525 3.071) (xy -0.492 3.076)
				(xy -0.472 3.076) (xy -0.442 3.072) (xy -0.418 3.063) (xy -0.398 3.048) (xy -0.382 3.029) (xy -0.371 3.004)
				(xy -0.363 2.972) (xy -0.358 2.933) (xy -0.356 2.885) (xy -0.356 2.88) (xy -0.358 2.828) (xy -0.363 2.785)
				(xy -0.373 2.75) (xy -0.387 2.724) (xy -0.406 2.704) (xy -0.43 2.692) (xy -0.46 2.686) (xy -0.483 2.685)
				(xy -0.517 2.687) (xy -0.544 2.696) (xy -0.565 2.711) (xy -0.583 2.734) (xy -0.591 2.751) (xy -0.595 2.76)
				(xy -0.598 2.769) (xy -0.6 2.779) (xy -0.601 2.793) (xy -0.602 2.811) (xy -0.602 2.836) (xy -0.602 2.869)
				(xy -0.602 2.88) (xy -0.733 2.88) (xy -0.733 2.827) (xy -0.732 2.783) (xy -0.729 2.746) (xy -0.725 2.716)
				(xy -0.719 2.691) (xy -0.71 2.67) (xy -0.699 2.651) (xy -0.685 2.633) (xy -0.668 2.616) (xy -0.668 2.615)
				(xy -0.632 2.587) (xy -0.592 2.567) (xy -0.55 2.557) (xy -0.506 2.556) (xy -0.463 2.564) (xy -0.421 2.582)
				(xy -0.411 2.587) (xy -0.394 2.598) (xy -0.377 2.61) (xy -0.373 2.614) (xy -0.356 2.627) (xy -0.356 2.306)
				(xy -0.229 2.306) (xy -0.229 3.2)
			)
			(stroke
				(width 0.01)
				(type solid)
			)
			(fill yes)
			(layer "F.Cu")
		)
		(fp_poly
			(pts
				(xy 0.605 1.558) (xy 0.651 1.574) (xy 0.694 1.598) (xy 0.728 1.627) (xy 0.75 1.652) (xy 0.768 1.678)
				(xy 0.781 1.707) (xy 0.791 1.739) (xy 0.797 1.777) (xy 0.801 1.822) (xy 0.802 1.876) (xy 0.802 1.877)
				(xy 0.801 1.929) (xy 0.798 1.973) (xy 0.792 2.009) (xy 0.784 2.04) (xy 0.774 2.062) (xy 0.748 2.103)
				(xy 0.715 2.139) (xy 0.675 2.167) (xy 0.632 2.187) (xy 0.626 2.189) (xy 0.599 2.195) (xy 0.567 2.198)
				(xy 0.532 2.199) (xy 0.499 2.197) (xy 0.471 2.193) (xy 0.466 2.192) (xy 0.428 2.177) (xy 0.391 2.155)
				(xy 0.359 2.129) (xy 0.354 2.123) (xy 0.332 2.098) (xy 0.316 2.073) (xy 0.303 2.047) (xy 0.294 2.017)
				(xy 0.287 1.983) (xy 0.284 1.943) (xy 0.282 1.894) (xy 0.282 1.877) (xy 0.409 1.877) (xy 0.41 1.918)
				(xy 0.412 1.95) (xy 0.416 1.976) (xy 0.423 1.997) (xy 0.432 2.015) (xy 0.445 2.03) (xy 0.451 2.037)
				(xy 0.471 2.054) (xy 0.491 2.064) (xy 0.514 2.07) (xy 0.543 2.072) (xy 0.569 2.07) (xy 0.59 2.065)
				(xy 0.601 2.06) (xy 0.625 2.047) (xy 0.642 2.031) (xy 0.656 2.009) (xy 0.661 1.998) (xy 0.665 1.989)
				(xy 0.668 1.98) (xy 0.67 1.969) (xy 0.671 1.954) (xy 0.672 1.935) (xy 0.673 1.909) (xy 0.673 1.877)
				(xy 0.673 1.842) (xy 0.672 1.817) (xy 0.671 1.798) (xy 0.67 1.784) (xy 0.668 1.773) (xy 0.665 1.764)
				(xy 0.661 1.755) (xy 0.647 1.73) (xy 0.632 1.712) (xy 0.612 1.698) (xy 0.601 1.693) (xy 0.569 1.683)
				(xy 0.535 1.681) (xy 0.501 1.686) (xy 0.471 1.7) (xy 0.447 1.719) (xy 0.434 1.736) (xy 0.424 1.753)
				(xy 0.417 1.774) (xy 0.412 1.8) (xy 0.41 1.833) (xy 0.409 1.873) (xy 0.409 1.877) (xy 0.282 1.877)
				(xy 0.283 1.824) (xy 0.286 1.78) (xy 0.292 1.742) (xy 0.301 1.711) (xy 0.313 1.683) (xy 0.33 1.657)
				(xy 0.35 1.633) (xy 0.351 1.632) (xy 0.385 1.601) (xy 0.42 1.578) (xy 0.46 1.563) (xy 0.505 1.554)
				(xy 0.555 1.551) (xy 0.605 1.558)
			)
			(stroke
				(width 0.01)
				(type solid)
			)
			(fill yes)
			(layer "F.Cu")
		)
		(fp_poly
			(pts
				(xy 0.004 1.556) (xy 0.054 1.566) (xy 0.102 1.582) (xy 0.146 1.605) (xy 0.154 1.61) (xy 0.193 1.636)
				(xy 0.178 1.655) (xy 0.166 1.668) (xy 0.152 1.686) (xy 0.138 1.7) (xy 0.114 1.727) (xy 0.07 1.705)
				(xy 0.032 1.688) (xy -0.007 1.677) (xy -0.044 1.672) (xy -0.079 1.672) (xy -0.11 1.678) (xy -0.136 1.69)
				(xy -0.154 1.707) (xy -0.162 1.724) (xy -0.164 1.745) (xy -0.164 1.761) (xy -0.159 1.772) (xy -0.15 1.782)
				(xy -0.149 1.783) (xy -0.139 1.791) (xy -0.128 1.797) (xy -0.114 1.802) (xy -0.095 1.805) (xy -0.07 1.808)
				(xy -0.037 1.811) (xy -0.02 1.813) (xy 0.027 1.817) (xy 0.065 1.823) (xy 0.096 1.832) (xy 0.122 1.842)
				(xy 0.14 1.854) (xy 0.166 1.879) (xy 0.186 1.91) (xy 0.2 1.947) (xy 0.206 1.987) (xy 0.206 2.018)
				(xy 0.198 2.06) (xy 0.181 2.097) (xy 0.155 2.129) (xy 0.122 2.156) (xy 0.08 2.177) (xy 0.042 2.189)
				(xy 0.005 2.196) (xy -0.038 2.199) (xy -0.083 2.198) (xy -0.125 2.194) (xy -0.153 2.189) (xy -0.177 2.181)
				(xy -0.204 2.171) (xy -0.229 2.16) (xy -0.232 2.159) (xy -0.251 2.148) (xy -0.272 2.136) (xy -0.292 2.122)
				(xy -0.309 2.109) (xy -0.323 2.098) (xy -0.33 2.09) (xy -0.331 2.088) (xy -0.327 2.084) (xy -0.318 2.073)
				(xy -0.304 2.059) (xy -0.288 2.043) (xy -0.246 2) (xy -0.221 2.021) (xy -0.184 2.047) (xy -0.145 2.065)
				(xy -0.102 2.075) (xy -0.053 2.079) (xy -0.049 2.079) (xy -0.023 2.079) (xy -0.004 2.078) (xy 0.011 2.074)
				(xy 0.025 2.069) (xy 0.029 2.068) (xy 0.054 2.052) (xy 0.071 2.033) (xy 0.079 2.01) (xy 0.078 1.986)
				(xy 0.074 1.975) (xy 0.068 1.964) (xy 0.06 1.956) (xy 0.048 1.949) (xy 0.031 1.944) (xy 0.007 1.939)
				(xy -0.024 1.935) (xy -0.052 1.932) (xy -0.089 1.929) (xy -0.119 1.925) (xy -0.142 1.921) (xy -0.16 1.917)
				(xy -0.176 1.912) (xy -0.192 1.906) (xy -0.201 1.901) (xy -0.235 1.879) (xy -0.262 1.85) (xy -0.28 1.816)
				(xy -0.29 1.776) (xy -0.292 1.75) (xy -0.291 1.727) (xy -0.289 1.705) (xy -0.286 1.689) (xy -0.286 1.688)
				(xy -0.273 1.659) (xy -0.253 1.63) (xy -0.229 1.604) (xy -0.221 1.599) (xy -0.185 1.577) (xy -0.143 1.562)
				(xy -0.096 1.554) (xy -0.047 1.552) (xy 0.004 1.556)
			)
			(stroke
				(width 0.01)
				(type solid)
			)
			(fill yes)
			(layer "F.Cu")
		)
		(fp_poly
			(pts
				(xy 1.038 2.556) (xy 1.091 2.563) (xy 1.137 2.576) (xy 1.177 2.595) (xy 1.209 2.62) (xy 1.234 2.65)
				(xy 1.242 2.665) (xy 1.247 2.677) (xy 1.251 2.691) (xy 1.255 2.708) (xy 1.258 2.727) (xy 1.26 2.751)
				(xy 1.262 2.78) (xy 1.263 2.815) (xy 1.263 2.858) (xy 1.264 2.908) (xy 1.263 2.967) (xy 1.263 2.989)
				(xy 1.262 3.197) (xy 1.135 3.197) (xy 1.133 3.171) (xy 1.132 3.144) (xy 1.119 3.159) (xy 1.096 3.179)
				(xy 1.065 3.193) (xy 1.026 3.202) (xy 0.98 3.204) (xy 0.976 3.204) (xy 0.955 3.204) (xy 0.937 3.203)
				(xy 0.925 3.202) (xy 0.924 3.201) (xy 0.879 3.189) (xy 0.839 3.17) (xy 0.806 3.144) (xy 0.781 3.113)
				(xy 0.763 3.077) (xy 0.753 3.037) (xy 0.753 3.005) (xy 0.873 3.005) (xy 0.874 3.023) (xy 0.878 3.035)
				(xy 0.887 3.047) (xy 0.89 3.05) (xy 0.903 3.063) (xy 0.917 3.072) (xy 0.935 3.078) (xy 0.957 3.081)
				(xy 0.986 3.082) (xy 1.013 3.082) (xy 1.043 3.081) (xy 1.065 3.079) (xy 1.08 3.077) (xy 1.091 3.073)
				(xy 1.096 3.071) (xy 1.112 3.058) (xy 1.123 3.039) (xy 1.13 3.012) (xy 1.132 2.977) (xy 1.132 2.975)
				(xy 1.132 2.931) (xy 1.035 2.931) (xy 0.999 2.931) (xy 0.973 2.931) (xy 0.953 2.932) (xy 0.939 2.934)
				(xy 0.928 2.936) (xy 0.919 2.939) (xy 0.916 2.94) (xy 0.893 2.954) (xy 0.88 2.971) (xy 0.874 2.994)
				(xy 0.873 3.005) (xy 0.753 3.005) (xy 0.753 2.994) (xy 0.761 2.951) (xy 0.768 2.931) (xy 0.776 2.915)
				(xy 0.786 2.901) (xy 0.802 2.884) (xy 0.804 2.882) (xy 0.82 2.867) (xy 0.835 2.854) (xy 0.85 2.845)
				(xy 0.867 2.838) (xy 0.887 2.833) (xy 0.912 2.829) (xy 0.943 2.827) (xy 0.982 2.826) (xy 1.015 2.825)
				(xy 1.133 2.823) (xy 1.132 2.771) (xy 1.131 2.746) (xy 1.129 2.73) (xy 1.127 2.719) (xy 1.123 2.711)
				(xy 1.117 2.705) (xy 1.098 2.691) (xy 1.07 2.682) (xy 1.032 2.677) (xy 1.006 2.677) (xy 0.972 2.678)
				(xy 0.945 2.682) (xy 0.924 2.688) (xy 0.907 2.699) (xy 0.9 2.706) (xy 0.882 2.723) (xy 0.834 2.686)
				(xy 0.816 2.672) (xy 0.801 2.66) (xy 0.79 2.652) (xy 0.787 2.648) (xy 0.791 2.639) (xy 0.801 2.626)
				(xy 0.816 2.612) (xy 0.832 2.6) (xy 0.864 2.581) (xy 0.902 2.568) (xy 0.946 2.559) (xy 0.98 2.556)
				(xy 1.038 2.556)
			)
			(stroke
				(width 0.01)
				(type solid)
			)
			(fill yes)
			(layer "F.Cu")
		)
		(fp_poly
			(pts
				(xy -1.521 2.559) (xy -1.485 2.562) (xy -1.454 2.568) (xy -1.427 2.577) (xy -1.401 2.589) (xy -1.371 2.61)
				(xy -1.345 2.639) (xy -1.325 2.67) (xy -1.321 2.679) (xy -1.309 2.71) (xy -1.309 3.197) (xy -1.433 3.2)
				(xy -1.433 3.172) (xy -1.434 3.157) (xy -1.435 3.147) (xy -1.436 3.144) (xy -1.44 3.147) (xy -1.449 3.156)
				(xy -1.453 3.161) (xy -1.472 3.178) (xy -1.496 3.19) (xy -1.526 3.198) (xy -1.563 3.202) (xy -1.578 3.203)
				(xy -1.603 3.203) (xy -1.627 3.203) (xy -1.647 3.201) (xy -1.656 3.2) (xy -1.686 3.191) (xy -1.717 3.176)
				(xy -1.746 3.159) (xy -1.765 3.143) (xy -1.79 3.111) (xy -1.807 3.075) (xy -1.816 3.037) (xy -1.817 2.998)
				(xy -1.817 2.997) (xy -1.697 2.997) (xy -1.696 3.02) (xy -1.687 3.042) (xy -1.67 3.06) (xy -1.668 3.062)
				(xy -1.654 3.07) (xy -1.64 3.076) (xy -1.624 3.08) (xy -1.602 3.081) (xy -1.574 3.082) (xy -1.558 3.082)
				(xy -1.529 3.081) (xy -1.508 3.08) (xy -1.494 3.078) (xy -1.483 3.075) (xy -1.474 3.07) (xy -1.458 3.058)
				(xy -1.447 3.041) (xy -1.44 3.017) (xy -1.435 2.985) (xy -1.435 2.977) (xy -1.432 2.931) (xy -1.533 2.931)
				(xy -1.568 2.931) (xy -1.595 2.931) (xy -1.615 2.932) (xy -1.63 2.934) (xy -1.641 2.936) (xy -1.65 2.938)
				(xy -1.655 2.941) (xy -1.676 2.955) (xy -1.69 2.974) (xy -1.697 2.997) (xy -1.817 2.997) (xy -1.811 2.96)
				(xy -1.797 2.924) (xy -1.775 2.892) (xy -1.747 2.864) (xy -1.715 2.845) (xy -1.7 2.838) (xy -1.685 2.833)
				(xy -1.668 2.83) (xy -1.648 2.827) (xy -1.623 2.825) (xy -1.591 2.824) (xy -1.551 2.824) (xy -1.54 2.824)
				(xy -1.432 2.824) (xy -1.434 2.776) (xy -1.436 2.747) (xy -1.441 2.726) (xy -1.448 2.711) (xy -1.46 2.699)
				(xy -1.474 2.689) (xy -1.483 2.685) (xy -1.492 2.682) (xy -1.505 2.68) (xy -1.524 2.68) (xy -1.55 2.679)
				(xy -1.56 2.679) (xy -1.594 2.68) (xy -1.62 2.682) (xy -1.639 2.686) (xy -1.654 2.692) (xy -1.666 2.701)
				(xy -1.675 2.711) (xy -1.686 2.724) (xy -1.735 2.686) (xy -1.754 2.672) (xy -1.769 2.659) (xy -1.78 2.65)
				(xy -1.784 2.646) (xy -1.78 2.64) (xy -1.77 2.629) (xy -1.756 2.616) (xy -1.74 2.604) (xy -1.724 2.592)
				(xy -1.711 2.584) (xy -1.71 2.583) (xy -1.688 2.574) (xy -1.668 2.566) (xy -1.647 2.562) (xy -1.623 2.559)
				(xy -1.593 2.558) (xy -1.565 2.558) (xy -1.521 2.559)
			)
			(stroke
				(width 0.01)
				(type solid)
			)
			(fill yes)
			(layer "F.Cu")
		)
		(fp_poly
			(pts
				(xy 0.035 2.777) (xy 0.047 2.822) (xy 0.059 2.864) (xy 0.069 2.903) (xy 0.078 2.936) (xy 0.086 2.963)
				(xy 0.092 2.984) (xy 0.095 2.996) (xy 0.096 2.999) (xy 0.098 2.999) (xy 0.103 2.991) (xy 0.109 2.975)
				(xy 0.118 2.95) (xy 0.129 2.917) (xy 0.143 2.874) (xy 0.152 2.849) (xy 0.165 2.807) (xy 0.179 2.766)
				(xy 0.192 2.726) (xy 0.204 2.689) (xy 0.214 2.658) (xy 0.221 2.634) (xy 0.224 2.627) (xy 0.244 2.565)
				(xy 0.338 2.565) (xy 0.406 2.774) (xy 0.42 2.819) (xy 0.434 2.861) (xy 0.446 2.899) (xy 0.457 2.932)
				(xy 0.466 2.96) (xy 0.473 2.981) (xy 0.477 2.993) (xy 0.478 2.997) (xy 0.48 2.998) (xy 0.482 2.996)
				(xy 0.485 2.99) (xy 0.49 2.978) (xy 0.495 2.96) (xy 0.502 2.936) (xy 0.511 2.905) (xy 0.523 2.865)
				(xy 0.536 2.817) (xy 0.543 2.789) (xy 0.556 2.744) (xy 0.568 2.701) (xy 0.578 2.663) (xy 0.587 2.629)
				(xy 0.595 2.602) (xy 0.601 2.582) (xy 0.605 2.57) (xy 0.606 2.567) (xy 0.611 2.566) (xy 0.625 2.566)
				(xy 0.645 2.566) (xy 0.669 2.566) (xy 0.673 2.566) (xy 0.739 2.567) (xy 0.656 2.827) (xy 0.64 2.878)
				(xy 0.624 2.928) (xy 0.609 2.976) (xy 0.595 3.02) (xy 0.582 3.06) (xy 0.571 3.094) (xy 0.563 3.121)
				(xy 0.557 3.139) (xy 0.556 3.143) (xy 0.538 3.2) (xy 0.425 3.197) (xy 0.358 2.975) (xy 0.341 2.917)
				(xy 0.327 2.87) (xy 0.315 2.831) (xy 0.305 2.801) (xy 0.297 2.78) (xy 0.292 2.766) (xy 0.289 2.761)
				(xy 0.288 2.761) (xy 0.286 2.768) (xy 0.281 2.783) (xy 0.274 2.806) (xy 0.265 2.836) (xy 0.254 2.871)
				(xy 0.242 2.911) (xy 0.23 2.953) (xy 0.223 2.976) (xy 0.21 3.02) (xy 0.197 3.062) (xy 0.186 3.099)
				(xy 0.177 3.132) (xy 0.169 3.158) (xy 0.163 3.177) (xy 0.16 3.189) (xy 0.159 3.191) (xy 0.157 3.195)
				(xy 0.151 3.198) (xy 0.141 3.199) (xy 0.124 3.2) (xy 0.101 3.2) (xy 0.073 3.199) (xy 0.055 3.198)
				(xy 0.045 3.196) (xy 0.043 3.194) (xy 0.041 3.188) (xy 0.036 3.173) (xy 0.029 3.15) (xy 0.019 3.121)
				(xy 0.008 3.084) (xy -0.006 3.043) (xy -0.02 2.996) (xy -0.036 2.946) (xy -0.053 2.893) (xy -0.057 2.883)
				(xy -0.074 2.83) (xy -0.09 2.779) (xy -0.105 2.732) (xy -0.119 2.689) (xy -0.131 2.652) (xy -0.141 2.621)
				(xy -0.148 2.596) (xy -0.154 2.58) (xy -0.156 2.572) (xy -0.156 2.569) (xy -0.151 2.567) (xy -0.14 2.566)
				(xy -0.123 2.565) (xy -0.096 2.565) (xy -0.091 2.565) (xy -0.023 2.565) (xy 0.035 2.777)
			)
			(stroke
				(width 0.01)
				(type solid)
			)
			(fill yes)
			(layer "F.Cu")
		)
		(fp_poly
			(pts
				(xy -2.065 1.559) (xy -2.024 1.576) (xy -1.986 1.601) (xy -1.973 1.612) (xy -1.957 1.63) (xy -1.943 1.649)
				(xy -1.932 1.668) (xy -1.924 1.69) (xy -1.918 1.716) (xy -1.914 1.747) (xy -1.911 1.785) (xy -1.91 1.831)
				(xy -1.91 1.877) (xy -1.91 1.93) (xy -1.912 1.974) (xy -1.914 2.011) (xy -1.919 2.041) (xy -1.925 2.067)
				(xy -1.934 2.088) (xy -1.945 2.107) (xy -1.959 2.125) (xy -1.972 2.139) (xy -1.993 2.157) (xy -2.018 2.173)
				(xy -2.031 2.18) (xy -2.047 2.188) (xy -2.06 2.192) (xy -2.074 2.195) (xy -2.091 2.196) (xy -2.114 2.197)
				(xy -2.122 2.197) (xy -2.147 2.196) (xy -2.165 2.195) (xy -2.179 2.193) (xy -2.191 2.189) (xy -2.205 2.183)
				(xy -2.21 2.18) (xy -2.231 2.169) (xy -2.251 2.156) (xy -2.265 2.146) (xy -2.286 2.127) (xy -2.286 2.627)
				(xy -2.266 2.608) (xy -2.248 2.595) (xy -2.227 2.582) (xy -2.217 2.577) (xy -2.173 2.562) (xy -2.129 2.556)
				(xy -2.086 2.559) (xy -2.045 2.57) (xy -2.007 2.589) (xy -1.974 2.616) (xy -1.946 2.648) (xy -1.926 2.687)
				(xy -1.919 2.707) (xy -1.917 2.715) (xy -1.915 2.724) (xy -1.914 2.737) (xy -1.913 2.753) (xy -1.912 2.774)
				(xy -1.911 2.8) (xy -1.911 2.833) (xy -1.911 2.874) (xy -1.911 2.923) (xy -1.911 2.967) (xy -1.911 3.2)
				(xy -2.035 3.197) (xy -2.038 2.984) (xy -2.038 2.932) (xy -2.039 2.889) (xy -2.039 2.854) (xy -2.04 2.826)
				(xy -2.041 2.805) (xy -2.042 2.788) (xy -2.043 2.776) (xy -2.045 2.767) (xy -2.046 2.76) (xy -2.049 2.755)
				(xy -2.051 2.75) (xy -2.072 2.721) (xy -2.098 2.701) (xy -2.128 2.688) (xy -2.161 2.683) (xy -2.195 2.687)
				(xy -2.22 2.697) (xy -2.24 2.71) (xy -2.259 2.729) (xy -2.274 2.75) (xy -2.278 2.757) (xy -2.28 2.765)
				(xy -2.281 2.781) (xy -2.283 2.806) (xy -2.284 2.839) (xy -2.285 2.881) (xy -2.286 2.933) (xy -2.286 2.984)
				(xy -2.289 3.197) (xy -2.413 3.2) (xy -2.413 1.877) (xy -2.286 1.877) (xy -2.285 1.926) (xy -2.281 1.966)
				(xy -2.274 1.998) (xy -2.262 2.024) (xy -2.247 2.043) (xy -2.228 2.058) (xy -2.215 2.064) (xy -2.194 2.07)
				(xy -2.168 2.072) (xy -2.141 2.071) (xy -2.117 2.066) (xy -2.106 2.063) (xy -2.079 2.044) (xy -2.058 2.019)
				(xy -2.05 2.001) (xy -2.045 1.984) (xy -2.042 1.959) (xy -2.04 1.929) (xy -2.038 1.895) (xy -2.038 1.861)
				(xy -2.039 1.829) (xy -2.041 1.8) (xy -2.044 1.777) (xy -2.045 1.772) (xy -2.057 1.738) (xy -2.073 1.712)
				(xy -2.094 1.695) (xy -2.122 1.684) (xy -2.156 1.681) (xy -2.159 1.681) (xy -2.192 1.683) (xy -2.22 1.691)
				(xy -2.243 1.705) (xy -2.26 1.725) (xy -2.273 1.753) (xy -2.281 1.788) (xy -2.285 1.832) (xy -2.286 1.877)
				(xy -2.413 1.877) (xy -2.413 1.559) (xy -2.286 1.559) (xy -2.286 1.62) (xy -2.26 1.6) (xy -2.225 1.577)
				(xy -2.19 1.563) (xy -2.154 1.554) (xy -2.109 1.552) (xy -2.065 1.559)
			)
			(stroke
				(width 0.01)
				(type solid)
			)
			(fill yes)
			(layer "F.Cu")
		)
		(fp_poly
			(pts
				(xy 0.063 -3.201) (xy 0.118 -3.201) (xy 0.164 -3.201) (xy 0.202 -3.2) (xy 0.233 -3.2) (xy 0.258 -3.2)
				(xy 0.277 -3.199) (xy 0.292 -3.198) (xy 0.302 -3.197) (xy 0.309 -3.196) (xy 0.314 -3.195) (xy 0.317 -3.193)
				(xy 0.319 -3.192) (xy 0.321 -3.189) (xy 0.324 -3.183) (xy 0.327 -3.174) (xy 0.33 -3.161) (xy 0.334 -3.144)
				(xy 0.339 -3.12) (xy 0.345 -3.091) (xy 0.352 -3.054) (xy 0.361 -3.01) (xy 0.371 -2.958) (xy 0.382 -2.897)
				(xy 0.385 -2.878) (xy 0.395 -2.824) (xy 0.405 -2.772) (xy 0.414 -2.724) (xy 0.423 -2.68) (xy 0.43 -2.642)
				(xy 0.437 -2.61) (xy 0.442 -2.586) (xy 0.446 -2.569) (xy 0.448 -2.562) (xy 0.456 -2.55) (xy 0.464 -2.544)
				(xy 0.476 -2.539) (xy 0.495 -2.53) (xy 0.521 -2.519) (xy 0.552 -2.506) (xy 0.587 -2.492) (xy 0.624 -2.477)
				(xy 0.664 -2.461) (xy 0.704 -2.445) (xy 0.743 -2.43) (xy 0.78 -2.415) (xy 0.814 -2.402) (xy 0.843 -2.391)
				(xy 0.868 -2.382) (xy 0.885 -2.376) (xy 0.895 -2.373) (xy 0.896 -2.373) (xy 0.911 -2.376) (xy 0.931 -2.386)
				(xy 0.948 -2.397) (xy 0.962 -2.406) (xy 0.983 -2.421) (xy 1.011 -2.44) (xy 1.043 -2.462) (xy 1.079 -2.487)
				(xy 1.118 -2.513) (xy 1.158 -2.541) (xy 1.198 -2.568) (xy 1.238 -2.595) (xy 1.275 -2.621) (xy 1.309 -2.644)
				(xy 1.338 -2.665) (xy 1.362 -2.681) (xy 1.377 -2.691) (xy 1.398 -2.705) (xy 1.418 -2.717) (xy 1.433 -2.725)
				(xy 1.442 -2.728) (xy 1.443 -2.728) (xy 1.448 -2.726) (xy 1.456 -2.72) (xy 1.468 -2.71) (xy 1.486 -2.694)
				(xy 1.508 -2.673) (xy 1.535 -2.647) (xy 1.568 -2.614) (xy 1.608 -2.575) (xy 1.654 -2.53) (xy 1.675 -2.509)
				(xy 1.721 -2.462) (xy 1.761 -2.422) (xy 1.794 -2.388) (xy 1.822 -2.36) (xy 1.844 -2.337) (xy 1.862 -2.318)
				(xy 1.875 -2.304) (xy 1.884 -2.293) (xy 1.89 -2.284) (xy 1.893 -2.279) (xy 1.894 -2.275) (xy 1.892 -2.269)
				(xy 1.886 -2.257) (xy 1.875 -2.239) (xy 1.86 -2.215) (xy 1.839 -2.183) (xy 1.814 -2.145) (xy 1.783 -2.1)
				(xy 1.747 -2.046) (xy 1.721 -2.009) (xy 1.69 -1.964) (xy 1.661 -1.921) (xy 1.634 -1.88) (xy 1.609 -1.844)
				(xy 1.588 -1.811) (xy 1.57 -1.785) (xy 1.557 -1.764) (xy 1.549 -1.75) (xy 1.546 -1.743) (xy 1.547 -1.735)
				(xy 1.552 -1.719) (xy 1.56 -1.696) (xy 1.571 -1.667) (xy 1.585 -1.634) (xy 1.6 -1.597) (xy 1.616 -1.557)
				(xy 1.633 -1.516) (xy 1.651 -1.476) (xy 1.668 -1.436) (xy 1.685 -1.398) (xy 1.701 -1.363) (xy 1.715 -1.333)
				(xy 1.727 -1.309) (xy 1.736 -1.291) (xy 1.742 -1.281) (xy 1.744 -1.279) (xy 1.751 -1.277) (xy 1.767 -1.273)
				(xy 1.791 -1.268) (xy 1.822 -1.261) (xy 1.86 -1.254) (xy 1.903 -1.245) (xy 1.951 -1.236) (xy 2.002 -1.226)
				(xy 2.049 -1.217) (xy 2.103 -1.207) (xy 2.154 -1.198) (xy 2.201 -1.188) (xy 2.244 -1.18) (xy 2.281 -1.173)
				(xy 2.311 -1.166) (xy 2.335 -1.161) (xy 2.35 -1.157) (xy 2.355 -1.156) (xy 2.367 -1.148) (xy 2.367 -0.834)
				(xy 2.367 -0.768) (xy 2.367 -0.712) (xy 2.367 -0.664) (xy 2.366 -0.625) (xy 2.366 -0.592) (xy 2.365 -0.566)
				(xy 2.364 -0.546) (xy 2.363 -0.531) (xy 2.361 -0.52) (xy 2.358 -0.512) (xy 2.355 -0.507) (xy 2.352 -0.504)
				(xy 2.348 -0.503) (xy 2.343 -0.501) (xy 2.34 -0.501) (xy 2.333 -0.499) (xy 2.317 -0.496) (xy 2.293 -0.492)
				(xy 2.261 -0.486) (xy 2.224 -0.479) (xy 2.181 -0.471) (xy 2.134 -0.462) (xy 2.084 -0.453) (xy 2.054 -0.448)
				(xy 2.002 -0.438) (xy 1.953 -0.429) (xy 1.907 -0.42) (xy 1.866 -0.412) (xy 1.831 -0.404) (xy 1.802 -0.398)
				(xy 1.78 -0.394) (xy 1.767 -0.391) (xy 1.764 -0.39) (xy 1.76 -0.387) (xy 1.757 -0.384) (xy 1.753 -0.379)
				(xy 1.748 -0.371) (xy 1.742 -0.36) (xy 1.735 -0.344) (xy 1.726 -0.324) (xy 1.715 -0.297) (xy 1.701 -0.264)
				(xy 1.685 -0.223) (xy 1.665 -0.174) (xy 1.653 -0.145) (xy 1.63 -0.086) (xy 1.61 -0.037) (xy 1.594 0.005)
				(xy 1.582 0.038) (xy 1.572 0.064) (xy 1.566 0.084) (xy 1.562 0.097) (xy 1.561 0.104) (xy 1.562 0.105)
				(xy 1.565 0.111) (xy 1.574 0.125) (xy 1.587 0.146) (xy 1.604 0.173) (xy 1.626 0.205) (xy 1.65 0.241)
				(xy 1.677 0.281) (xy 1.706 0.324) (xy 1.729 0.358) (xy 1.768 0.413) (xy 1.8 0.461) (xy 1.827 0.502)
				(xy 1.85 0.535) (xy 1.867 0.562) (xy 1.88 0.583) (xy 1.889 0.598) (xy 1.893 0.608) (xy 1.894 0.612)
				(xy 1.893 0.616) (xy 1.89 0.622) (xy 1.885 0.63) (xy 1.876 0.64) (xy 1.863 0.655) (xy 1.846 0.673)
				(xy 1.825 0.695) (xy 1.798 0.723) (xy 1.765 0.756) (xy 1.727 0.795) (xy 1.682 0.839) (xy 1.635 0.886)
				(xy 1.595 0.926) (xy 1.561 0.96) (xy 1.532 0.989) (xy 1.508 1.012) (xy 1.488 1.03) (xy 1.473 1.044)
				(xy 1.461 1.054) (xy 1.452 1.061) (xy 1.445 1.065) (xy 1.44 1.066) (xy 1.438 1.066) (xy 1.433 1.064)
				(xy 1.421 1.055) (xy 1.401 1.043) (xy 1.376 1.026) (xy 1.345 1.005) (xy 1.31 0.981) (xy 1.27 0.954)
				(xy 1.228 0.925) (xy 1.193 0.901) (xy 1.138 0.864) (xy 1.089 0.83) (xy 1.046 0.802) (xy 1.01 0.778)
				(xy 0.981 0.759) (xy 0.96 0.746) (xy 0.946 0.738) (xy 0.94 0.736) (xy 0.932 0.738) (xy 0.917 0.745)
				(xy 0.895 0.755) (xy 0.869 0.768) (xy 0.84 0.783) (xy 0.816 0.795) (xy 0.781 0.814) (xy 0.753 0.828)
				(xy 0.732 0.838) (xy 0.717 0.845) (xy 0.707 0.849) (xy 0.699 0.85) (xy 0.694 0.849) (xy 0.691 0.847)
				(xy 0.687 0.84) (xy 0.682 0.829) (xy 0.674 0.814) (xy 0.665 0.793) (xy 0.653 0.767) (xy 0.639 0.735)
				(xy 0.623 0.696) (xy 0.604 0.651) (xy 0.582 0.598) (xy 0.556 0.538) (xy 0.528 0.469) (xy 0.496 0.391)
				(xy 0.47 0.329) (xy 0.436 0.247) (xy 0.406 0.173) (xy 0.379 0.108) (xy 0.355 0.05) (xy 0.335 0)
				(xy 0.317 -0.043) (xy 0.303 -0.079) (xy 0.291 -0.11) (xy 0.281 -0.135) (xy 0.273 -0.155) (xy 0.268 -0.171)
				(xy 0.264 -0.183) (xy 0.262 -0.191) (xy 0.262 -0.196) (xy 0.262 -0.198) (xy 0.269 -0.207) (xy 0.283 -0.219)
				(xy 0.302 -0.233) (xy 0.303 -0.234) (xy 0.354 -0.268) (xy 0.398 -0.3) (xy 0.435 -0.331) (xy 0.469 -0.363)
				(xy 0.5 -0.397) (xy 0.507 -0.405) (xy 0.556 -0.472) (xy 0.596 -0.543) (xy 0.627 -0.619) (xy 0.643 -0.672)
				(xy 0.651 -0.718) (xy 0.657 -0.77) (xy 0.66 -0.824) (xy 0.659 -0.878) (xy 0.654 -0.927) (xy 0.652 -0.936)
				(xy 0.634 -1.015) (xy 0.607 -1.09) (xy 0.571 -1.161) (xy 0.528 -1.227) (xy 0.477 -1.287) (xy 0.419 -1.341)
				(xy 0.355 -1.387) (xy 0.285 -1.426) (xy 0.21 -1.456) (xy 0.205 -1.458) (xy 0.131 -1.477) (xy 0.054 -1.487)
				(xy -0.025 -1.489) (xy -0.103 -1.482) (xy -0.178 -1.466) (xy -0.206 -1.458) (xy -0.281 -1.428) (xy -0.351 -1.39)
				(xy -0.416 -1.344) (xy -0.474 -1.29) (xy -0.526 -1.23) (xy -0.571 -1.164) (xy -0.607 -1.093) (xy -0.63 -1.034)
				(xy -0.649 -0.96) (xy -0.659 -0.883) (xy -0.661 -0.804) (xy -0.654 -0.726) (xy -0.638 -0.651) (xy -0.63 -0.623)
				(xy -0.618 -0.591) (xy -0.602 -0.554) (xy -0.584 -0.518) (xy -0.566 -0.485) (xy -0.553 -0.463) (xy -0.509 -0.407)
				(xy -0.457 -0.352) (xy -0.397 -0.299) (xy -0.33 -0.25) (xy -0.289 -0.224) (xy -0.273 -0.212) (xy -0.263 -0.2)
				(xy -0.262 -0.197) (xy -0.263 -0.19) (xy -0.268 -0.175) (xy -0.277 -0.151) (xy -0.288 -0.121) (xy -0.302 -0.084)
				(xy -0.319 -0.042) (xy -0.338 0.005) (xy -0.358 0.056) (xy -0.381 0.111) (xy -0.404 0.168) (xy -0.428 0.228)
				(xy -0.453 0.288) (xy -0.478 0.349) (xy -0.504 0.41) (xy -0.529 0.47) (xy -0.553 0.527) (xy -0.576 0.583)
				(xy -0.598 0.635) (xy -0.619 0.683) (xy -0.638 0.727) (xy -0.655 0.765) (xy -0.669 0.797) (xy -0.68 0.822)
				(xy -0.689 0.839) (xy -0.694 0.848) (xy -0.695 0.849) (xy -0.699 0.85) (xy -0.706 0.849) (xy -0.717 0.845)
				(xy -0.732 0.839) (xy -0.752 0.829) (xy -0.779 0.815) (xy -0.814 0.797) (xy -0.817 0.795) (xy -0.848 0.779)
				(xy -0.877 0.764) (xy -0.902 0.752) (xy -0.922 0.743) (xy -0.936 0.737) (xy -0.941 0.736) (xy -0.949 0.739)
				(xy -0.964 0.748) (xy -0.987 0.761) (xy -1.015 0.78) (xy -1.05 0.803) (xy -1.072 0.818) (xy -1.138 0.863)
				(xy -1.195 0.903) (xy -1.245 0.937) (xy -1.289 0.966) (xy -1.325 0.991) (xy -1.356 1.012) (xy -1.381 1.029)
				(xy -1.401 1.042) (xy -1.416 1.052) (xy -1.427 1.059) (xy -1.435 1.064) (xy -1.439 1.066) (xy -1.44 1.066)
				(xy -1.449 1.064) (xy -1.453 1.061) (xy -1.458 1.057) (xy -1.47 1.046) (xy -1.487 1.029) (xy -1.509 1.007)
				(xy -1.537 0.98) (xy -1.568 0.95) (xy -1.602 0.915) (xy -1.639 0.879) (xy -1.678 0.84) (xy -1.678 0.839)
				(xy -1.726 0.792) (xy -1.767 0.751) (xy -1.801 0.716) (xy -1.829 0.687) (xy -1.852 0.663) (xy -1.869 0.644)
				(xy -1.882 0.63) (xy -1.89 0.62) (xy -1.894 0.613) (xy -1.895 0.61) (xy -1.892 0.603) (xy -1.884 0.588)
				(xy -1.87 0.565) (xy -1.85 0.536) (xy -1.826 0.499) (xy -1.797 0.455) (xy -1.763 0.405) (xy -1.73 0.358)
				(xy -1.7 0.313) (xy -1.671 0.271) (xy -1.645 0.232) (xy -1.621 0.197) (xy -1.601 0.166) (xy -1.584 0.141)
				(xy -1.572 0.121) (xy -1.565 0.109) (xy -1.563 0.105) (xy -1.563 0.099) (xy -1.566 0.087) (xy -1.572 0.07)
				(xy -1.58 0.045) (xy -1.592 0.013) (xy -1.607 -0.026) (xy -1.626 -0.074) (xy -1.648 -0.13) (xy -1.654 -0.145)
				(xy -1.676 -0.199) (xy -1.695 -0.245) (xy -1.71 -0.282) (xy -1.723 -0.313) (xy -1.733 -0.337) (xy -1.741 -0.356)
				(xy -1.748 -0.369) (xy -1.753 -0.379) (xy -1.758 -0.385) (xy -1.761 -0.388) (xy -1.763 -0.389) (xy -1.767 -0.39)
				(xy -1.774 -0.392) (xy -1.784 -0.395) (xy -1.799 -0.398) (xy -1.818 -0.402) (xy -1.843 -0.407) (xy -1.873 -0.413)
				(xy -1.91 -0.42) (xy -1.954 -0.429) (xy -2.005 -0.438) (xy -2.065 -0.449) (xy -2.133 -0.462) (xy -2.211 -0.477)
				(xy -2.22 -0.478) (xy -2.26 -0.486) (xy -2.29 -0.491) (xy -2.313 -0.496) (xy -2.33 -0.499) (xy -2.341 -0.502)
				(xy -2.349 -0.504) (xy -2.353 -0.506) (xy -2.356 -0.508) (xy -2.359 -0.51) (xy -2.36 -0.511) (xy -2.361 -0.514)
				(xy -2.363 -0.518) (xy -2.364 -0.526) (xy -2.365 -0.536) (xy -2.366 -0.551) (xy -2.366 -0.571) (xy -2.367 -0.597)
				(xy -2.367 -0.629) (xy -2.368 -0.668) (xy -2.368 -0.715) (xy -2.368 -0.771) (xy -2.368 -0.834) (xy -2.368 -1.148)
				(xy -2.356 -1.155) (xy -2.349 -1.158) (xy -2.333 -1.162) (xy -2.309 -1.167) (xy -2.278 -1.173) (xy -2.24 -1.181)
				(xy -2.197 -1.189) (xy -2.149 -1.198) (xy -2.098 -1.208) (xy -2.051 -1.217) (xy -1.996 -1.227) (xy -1.945 -1.237)
				(xy -1.897 -1.246) (xy -1.854 -1.254) (xy -1.817 -1.262) (xy -1.787 -1.268) (xy -1.764 -1.273) (xy -1.75 -1.277)
				(xy -1.745 -1.279) (xy -1.741 -1.285) (xy -1.733 -1.3) (xy -1.722 -1.322) (xy -1.709 -1.35) (xy -1.694 -1.382)
				(xy -1.677 -1.419) (xy -1.66 -1.458) (xy -1.642 -1.498) (xy -1.625 -1.539) (xy -1.608 -1.58) (xy -1.592 -1.618)
				(xy -1.578 -1.653) (xy -1.565 -1.684) (xy -1.556 -1.709) (xy -1.549 -1.729) (xy -1.546 -1.74) (xy -1.546 -1.742)
				(xy -1.549 -1.749) (xy -1.558 -1.763) (xy -1.571 -1.784) (xy -1.588 -1.811) (xy -1.61 -1.843) (xy -1.634 -1.88)
				(xy -1.661 -1.92) (xy -1.691 -1.963) (xy -1.722 -2.008) (xy -1.762 -2.067) (xy -1.796 -2.117) (xy -1.825 -2.16)
				(xy -1.848 -2.196) (xy -1.867 -2.225) (xy -1.881 -2.247) (xy -1.89 -2.262) (xy -1.895 -2.272) (xy -1.895 -2.275)
				(xy -1.894 -2.279) (xy -1.891 -2.285) (xy -1.884 -2.293) (xy -1.875 -2.305) (xy -1.861 -2.32) (xy -1.843 -2.339)
				(xy -1.82 -2.363) (xy -1.792 -2.392) (xy -1.758 -2.426) (xy -1.718 -2.466) (xy -1.676 -2.509) (xy -1.627 -2.557)
				(xy -1.585 -2.599) (xy -1.549 -2.634) (xy -1.52 -2.663) (xy -1.495 -2.686) (xy -1.476 -2.704) (xy -1.462 -2.716)
				(xy -1.452 -2.724) (xy -1.446 -2.728) (xy -1.444 -2.728) (xy -1.437 -2.726) (xy -1.423 -2.717) (xy -1.401 -2.703)
				(xy -1.372 -2.685) (xy -1.337 -2.661) (xy -1.295 -2.634) (xy -1.248 -2.602) (xy -1.196 -2.566) (xy -1.173 -2.551)
				(xy -1.118 -2.513) (xy -1.071 -2.481) (xy -1.031 -2.454) (xy -0.998 -2.432) (xy -0.97 -2.413) (xy -0.948 -2.399)
				(xy -0.931 -2.389) (xy -0.917 -2.381) (xy -0.907 -2.376) (xy -0.901 -2.373) (xy -0.897 -2.373) (xy -0.888 -2.375)
				(xy -0.87 -2.38) (xy -0.845 -2.39) (xy -0.813 -2.402) (xy -0.774 -2.417) (xy -0.73 -2.434) (xy -0.681 -2.454)
				(xy -0.629 -2.475) (xy -0.586 -2.493) (xy -0.55 -2.508) (xy -0.522 -2.52) (xy -0.499 -2.529) (xy -0.482 -2.537)
				(xy -0.47 -2.543) (xy -0.461 -2.548) (xy -0.455 -2.551) (xy -0.452 -2.554) (xy -0.449 -2.557) (xy -0.448 -2.56)
				(xy -0.447 -2.566) (xy -0.443 -2.582) (xy -0.438 -2.605) (xy -0.432 -2.637) (xy -0.425 -2.674) (xy -0.417 -2.717)
				(xy -0.407 -2.765) (xy -0.398 -2.817) (xy -0.388 -2.871) (xy -0.387 -2.876) (xy -0.375 -2.94) (xy -0.364 -2.995)
				(xy -0.356 -3.042) (xy -0.348 -3.081) (xy -0.342 -3.112) (xy -0.337 -3.137) (xy -0.332 -3.157) (xy -0.328 -3.171)
				(xy -0.325 -3.181) (xy -0.323 -3.188) (xy -0.32 -3.191) (xy -0.32 -3.192) (xy -0.317 -3.194) (xy -0.313 -3.195)
				(xy -0.307 -3.197) (xy -0.298 -3.198) (xy -0.286 -3.199) (xy -0.269 -3.199) (xy -0.247 -3.2) (xy -0.219 -3.2)
				(xy -0.184 -3.201) (xy -0.142 -3.201) (xy -0.092 -3.201) (xy -0.033 -3.201) (xy -0.001 -3.201) (xy 0.063 -3.201)
			)
			(stroke
				(width 0.01)
				(type solid)
			)
			(fill yes)
			(layer "F.Cu")
		)
		(fp_poly
			(pts
				(xy -0.843 2.558) (xy -0.815 2.564) (xy -0.794 2.572) (xy -0.773 2.581) (xy -0.759 2.589) (xy -0.738 2.603)
				(xy -0.783 2.658) (xy -0.8 2.677) (xy -0.814 2.694) (xy -0.825 2.706) (xy -0.831 2.712) (xy -0.832 2.712)
				(xy -0.837 2.71) (xy -0.847 2.703) (xy -0.849 2.702) (xy -0.874 2.69) (xy -0.904 2.684) (xy -0.935 2.685)
				(xy -0.942 2.686) (xy -0.975 2.698) (xy -1.001 2.717) (xy -1.02 2.741) (xy -1.034 2.766) (xy -1.039 3.197)
				(xy -1.164 3.2) (xy -1.164 2.565) (xy -1.037 2.565) (xy -1.037 2.626) (xy -1.009 2.604) (xy -0.972 2.579)
				(xy -0.931 2.563) (xy -0.887 2.556) (xy -0.843 2.558)
			)
			(stroke
				(width 0.01)
				(type solid)
			)
			(fill yes)
			(layer "F.Mask")
		)
		(fp_poly
			(pts
				(xy 1.889 1.554) (xy 1.907 1.559) (xy 1.927 1.566) (xy 1.948 1.574) (xy 1.966 1.583) (xy 1.979 1.592)
				(xy 1.984 1.597) (xy 1.982 1.604) (xy 1.974 1.616) (xy 1.962 1.633) (xy 1.946 1.652) (xy 1.945 1.654)
				(xy 1.929 1.673) (xy 1.915 1.689) (xy 1.906 1.7) (xy 1.901 1.706) (xy 1.896 1.705) (xy 1.885 1.7)
				(xy 1.873 1.695) (xy 1.84 1.683) (xy 1.808 1.68) (xy 1.776 1.685) (xy 1.747 1.698) (xy 1.723 1.717)
				(xy 1.704 1.742) (xy 1.696 1.763) (xy 1.695 1.772) (xy 1.694 1.79) (xy 1.693 1.817) (xy 1.692 1.85)
				(xy 1.692 1.89) (xy 1.691 1.934) (xy 1.691 1.983) (xy 1.691 2.194) (xy 1.559 2.194) (xy 1.559 1.559)
				(xy 1.691 1.559) (xy 1.691 1.626) (xy 1.71 1.607) (xy 1.739 1.585) (xy 1.775 1.568) (xy 1.814 1.556)
				(xy 1.855 1.552) (xy 1.889 1.554)
			)
			(stroke
				(width 0.01)
				(type solid)
			)
			(fill yes)
			(layer "F.Mask")
		)
		(fp_poly
			(pts
				(xy -0.837 1.56) (xy -0.797 1.576) (xy -0.761 1.6) (xy -0.73 1.63) (xy -0.706 1.667) (xy -0.69 1.709)
				(xy -0.687 1.721) (xy -0.685 1.734) (xy -0.684 1.757) (xy -0.683 1.79) (xy -0.682 1.833) (xy -0.681 1.884)
				(xy -0.681 1.945) (xy -0.681 1.971) (xy -0.681 2.194) (xy -0.808 2.194) (xy -0.809 1.984) (xy -0.811 1.774)
				(xy -0.826 1.744) (xy -0.845 1.716) (xy -0.868 1.697) (xy -0.897 1.686) (xy -0.925 1.682) (xy -0.947 1.682)
				(xy -0.967 1.684) (xy -0.979 1.686) (xy -1.001 1.698) (xy -1.023 1.716) (xy -1.041 1.738) (xy -1.049 1.752)
				(xy -1.052 1.758) (xy -1.054 1.765) (xy -1.056 1.773) (xy -1.057 1.783) (xy -1.058 1.797) (xy -1.059 1.815)
				(xy -1.06 1.839) (xy -1.06 1.869) (xy -1.061 1.907) (xy -1.061 1.953) (xy -1.061 1.985) (xy -1.063 2.194)
				(xy -1.189 2.194) (xy -1.189 1.559) (xy -1.062 1.559) (xy -1.062 1.625) (xy -1.033 1.602) (xy -1.001 1.579)
				(xy -0.969 1.564) (xy -0.934 1.555) (xy -0.927 1.554) (xy -0.881 1.553) (xy -0.837 1.56)
			)
			(stroke
				(width 0.01)
				(type solid)
			)
			(fill yes)
			(layer "F.Mask")
		)
		(fp_poly
			(pts
				(xy 1.042 1.769) (xy 1.043 1.979) (xy 1.059 2.009) (xy 1.077 2.036) (xy 1.1 2.056) (xy 1.129 2.067)
				(xy 1.159 2.071) (xy 1.193 2.07) (xy 1.221 2.063) (xy 1.245 2.047) (xy 1.258 2.034) (xy 1.266 2.025)
				(xy 1.273 2.016) (xy 1.278 2.008) (xy 1.282 1.997) (xy 1.286 1.985) (xy 1.288 1.969) (xy 1.29 1.948)
				(xy 1.291 1.922) (xy 1.292 1.89) (xy 1.293 1.85) (xy 1.293 1.801) (xy 1.294 1.766) (xy 1.295 1.559)
				(xy 1.422 1.559) (xy 1.422 2.194) (xy 1.295 2.194) (xy 1.295 2.161) (xy 1.295 2.144) (xy 1.293 2.132)
				(xy 1.292 2.128) (xy 1.287 2.131) (xy 1.278 2.14) (xy 1.271 2.147) (xy 1.256 2.159) (xy 1.236 2.171)
				(xy 1.219 2.181) (xy 1.202 2.188) (xy 1.186 2.193) (xy 1.17 2.196) (xy 1.148 2.197) (xy 1.135 2.198)
				(xy 1.107 2.198) (xy 1.087 2.197) (xy 1.07 2.194) (xy 1.059 2.19) (xy 1.036 2.181) (xy 1.019 2.172)
				(xy 1.003 2.161) (xy 0.985 2.146) (xy 0.981 2.141) (xy 0.952 2.107) (xy 0.931 2.068) (xy 0.92 2.033)
				(xy 0.918 2.019) (xy 0.917 1.996) (xy 0.916 1.963) (xy 0.915 1.92) (xy 0.914 1.869) (xy 0.914 1.808)
				(xy 0.914 1.782) (xy 0.914 1.559) (xy 1.04 1.559) (xy 1.042 1.769)
			)
			(stroke
				(width 0.01)
				(type solid)
			)
			(fill yes)
			(layer "F.Mask")
		)
		(fp_poly
			(pts
				(xy 1.753 2.563) (xy 1.768 2.568) (xy 1.787 2.577) (xy 1.804 2.586) (xy 1.818 2.595) (xy 1.826 2.602)
				(xy 1.827 2.606) (xy 1.824 2.611) (xy 1.815 2.621) (xy 1.803 2.636) (xy 1.789 2.654) (xy 1.775 2.671)
				(xy 1.761 2.688) (xy 1.749 2.701) (xy 1.742 2.71) (xy 1.739 2.712) (xy 1.735 2.71) (xy 1.724 2.704)
				(xy 1.713 2.698) (xy 1.697 2.69) (xy 1.682 2.686) (xy 1.664 2.685) (xy 1.653 2.685) (xy 1.618 2.688)
				(xy 1.59 2.699) (xy 1.566 2.718) (xy 1.561 2.723) (xy 1.554 2.732) (xy 1.548 2.74) (xy 1.544 2.748)
				(xy 1.54 2.758) (xy 1.537 2.769) (xy 1.534 2.785) (xy 1.533 2.804) (xy 1.532 2.829) (xy 1.531 2.861)
				(xy 1.53 2.899) (xy 1.53 2.947) (xy 1.53 2.988) (xy 1.528 3.2) (xy 1.468 3.2) (xy 1.444 3.2) (xy 1.425 3.199)
				(xy 1.411 3.198) (xy 1.405 3.197) (xy 1.404 3.191) (xy 1.404 3.176) (xy 1.403 3.153) (xy 1.403 3.122)
				(xy 1.402 3.085) (xy 1.402 3.042) (xy 1.402 2.993) (xy 1.402 2.941) (xy 1.402 2.886) (xy 1.402 2.565)
				(xy 1.529 2.565) (xy 1.529 2.595) (xy 1.529 2.611) (xy 1.53 2.623) (xy 1.532 2.626) (xy 1.537 2.623)
				(xy 1.547 2.615) (xy 1.554 2.608) (xy 1.588 2.584) (xy 1.627 2.567) (xy 1.669 2.558) (xy 1.712 2.556)
				(xy 1.753 2.563)
			)
			(stroke
				(width 0.01)
				(type solid)
			)
			(fill yes)
			(layer "F.Mask")
		)
		(fp_poly
			(pts
				(xy 2.316 1.557) (xy 2.365 1.57) (xy 2.41 1.593) (xy 2.453 1.625) (xy 2.46 1.631) (xy 2.491 1.661)
				(xy 2.466 1.684) (xy 2.448 1.699) (xy 2.43 1.715) (xy 2.419 1.725) (xy 2.397 1.743) (xy 2.376 1.724)
				(xy 2.345 1.701) (xy 2.312 1.687) (xy 2.274 1.681) (xy 2.265 1.681) (xy 2.226 1.684) (xy 2.195 1.693)
				(xy 2.167 1.708) (xy 2.159 1.715) (xy 2.136 1.741) (xy 2.118 1.776) (xy 2.107 1.817) (xy 2.103 1.866)
				(xy 2.103 1.876) (xy 2.106 1.926) (xy 2.116 1.97) (xy 2.132 2.006) (xy 2.155 2.034) (xy 2.184 2.055)
				(xy 2.219 2.067) (xy 2.259 2.072) (xy 2.274 2.071) (xy 2.309 2.066) (xy 2.339 2.056) (xy 2.366 2.038)
				(xy 2.377 2.028) (xy 2.386 2.02) (xy 2.393 2.016) (xy 2.4 2.015) (xy 2.409 2.018) (xy 2.42 2.027)
				(xy 2.436 2.041) (xy 2.456 2.059) (xy 2.491 2.092) (xy 2.476 2.108) (xy 2.449 2.132) (xy 2.416 2.155)
				(xy 2.38 2.174) (xy 2.35 2.186) (xy 2.327 2.193) (xy 2.306 2.197) (xy 2.283 2.199) (xy 2.259 2.199)
				(xy 2.233 2.198) (xy 2.209 2.196) (xy 2.189 2.193) (xy 2.182 2.191) (xy 2.133 2.173) (xy 2.089 2.146)
				(xy 2.053 2.112) (xy 2.023 2.071) (xy 2.012 2.051) (xy 2 2.023) (xy 1.991 1.999) (xy 1.984 1.975)
				(xy 1.981 1.948) (xy 1.979 1.917) (xy 1.978 1.879) (xy 1.978 1.877) (xy 1.979 1.838) (xy 1.98 1.806)
				(xy 1.984 1.78) (xy 1.99 1.756) (xy 1.999 1.731) (xy 2.011 1.704) (xy 2.012 1.701) (xy 2.039 1.657)
				(xy 2.072 1.62) (xy 2.111 1.591) (xy 2.156 1.57) (xy 2.207 1.557) (xy 2.263 1.552) (xy 2.316 1.557)
			)
			(stroke
				(width 0.01)
				(type solid)
			)
			(fill yes)
			(layer "F.Mask")
		)
		(fp_poly
			(pts
				(xy -1.494 1.56) (xy -1.447 1.576) (xy -1.405 1.6) (xy -1.368 1.633) (xy -1.341 1.668) (xy -1.326 1.692)
				(xy -1.316 1.716) (xy -1.308 1.743) (xy -1.302 1.774) (xy -1.299 1.811) (xy -1.297 1.845) (xy -1.294 1.925)
				(xy -1.692 1.925) (xy -1.692 1.942) (xy -1.687 1.977) (xy -1.673 2.011) (xy -1.65 2.039) (xy -1.626 2.059)
				(xy -1.601 2.071) (xy -1.572 2.078) (xy -1.537 2.079) (xy -1.497 2.074) (xy -1.458 2.06) (xy -1.422 2.036)
				(xy -1.421 2.036) (xy -1.402 2.021) (xy -1.359 2.057) (xy -1.342 2.072) (xy -1.327 2.085) (xy -1.317 2.094)
				(xy -1.314 2.098) (xy -1.316 2.103) (xy -1.324 2.113) (xy -1.338 2.126) (xy -1.354 2.139) (xy -1.372 2.152)
				(xy -1.389 2.163) (xy -1.399 2.168) (xy -1.421 2.178) (xy -1.445 2.187) (xy -1.461 2.191) (xy -1.488 2.196)
				(xy -1.522 2.199) (xy -1.557 2.199) (xy -1.591 2.196) (xy -1.62 2.192) (xy -1.629 2.19) (xy -1.677 2.171)
				(xy -1.718 2.146) (xy -1.752 2.114) (xy -1.779 2.074) (xy -1.8 2.026) (xy -1.802 2.02) (xy -1.81 1.989)
				(xy -1.815 1.951) (xy -1.818 1.908) (xy -1.819 1.865) (xy -1.818 1.823) (xy -1.816 1.804) (xy -1.692 1.804)
				(xy -1.692 1.818) (xy -1.428 1.818) (xy -1.428 1.801) (xy -1.432 1.775) (xy -1.442 1.748) (xy -1.457 1.722)
				(xy -1.469 1.707) (xy -1.495 1.688) (xy -1.526 1.676) (xy -1.56 1.672) (xy -1.593 1.676) (xy -1.619 1.685)
				(xy -1.646 1.704) (xy -1.668 1.73) (xy -1.683 1.76) (xy -1.691 1.792) (xy -1.692 1.804) (xy -1.816 1.804)
				(xy -1.814 1.786) (xy -1.812 1.777) (xy -1.797 1.724) (xy -1.775 1.676) (xy -1.747 1.636) (xy -1.713 1.603)
				(xy -1.673 1.578) (xy -1.629 1.561) (xy -1.597 1.554) (xy -1.544 1.552) (xy -1.494 1.56)
			)
			(stroke
				(width 0.01)
				(type solid)
			)
			(fill yes)
			(layer "F.Mask")
		)
		(fp_poly
			(pts
				(xy 2.835 1.557) (xy 2.883 1.57) (xy 2.926 1.592) (xy 2.964 1.621) (xy 2.996 1.657) (xy 3.021 1.699)
				(xy 3.038 1.747) (xy 3.04 1.757) (xy 3.043 1.776) (xy 3.045 1.802) (xy 3.047 1.832) (xy 3.047 1.858)
				(xy 3.047 1.925) (xy 2.65 1.925) (xy 2.653 1.951) (xy 2.663 1.991) (xy 2.68 2.024) (xy 2.703 2.049)
				(xy 2.733 2.067) (xy 2.77 2.077) (xy 2.801 2.079) (xy 2.845 2.075) (xy 2.883 2.063) (xy 2.916 2.042)
				(xy 2.92 2.039) (xy 2.929 2.031) (xy 2.935 2.026) (xy 2.941 2.025) (xy 2.949 2.027) (xy 2.959 2.034)
				(xy 2.974 2.047) (xy 2.994 2.064) (xy 3.01 2.078) (xy 3.023 2.088) (xy 3.03 2.095) (xy 3.032 2.096)
				(xy 3.03 2.1) (xy 3.022 2.11) (xy 3.01 2.122) (xy 3.009 2.123) (xy 2.98 2.147) (xy 2.945 2.169)
				(xy 2.906 2.185) (xy 2.887 2.191) (xy 2.861 2.196) (xy 2.828 2.198) (xy 2.793 2.198) (xy 2.759 2.197)
				(xy 2.729 2.193) (xy 2.721 2.191) (xy 2.675 2.175) (xy 2.634 2.15) (xy 2.599 2.118) (xy 2.569 2.077)
				(xy 2.547 2.029) (xy 2.536 1.996) (xy 2.532 1.973) (xy 2.529 1.942) (xy 2.527 1.906) (xy 2.527 1.869)
				(xy 2.528 1.832) (xy 2.529 1.818) (xy 2.65 1.818) (xy 2.922 1.818) (xy 2.918 1.799) (xy 2.908 1.758)
				(xy 2.891 1.725) (xy 2.869 1.7) (xy 2.84 1.683) (xy 2.826 1.678) (xy 2.788 1.672) (xy 2.753 1.675)
				(xy 2.722 1.687) (xy 2.695 1.706) (xy 2.674 1.734) (xy 2.659 1.768) (xy 2.654 1.794) (xy 2.65 1.818)
				(xy 2.529 1.818) (xy 2.53 1.798) (xy 2.534 1.769) (xy 2.536 1.76) (xy 2.554 1.707) (xy 2.578 1.662)
				(xy 2.609 1.624) (xy 2.645 1.593) (xy 2.687 1.571) (xy 2.734 1.557) (xy 2.783 1.553) (xy 2.835 1.557)
			)
			(stroke
				(width 0.01)
				(type solid)
			)
			(fill yes)
			(layer "F.Mask")
		)
		(fp_poly
			(pts
				(xy -2.733 1.557) (xy -2.685 1.57) (xy -2.642 1.592) (xy -2.604 1.622) (xy -2.581 1.649) (xy -2.562 1.676)
				(xy -2.548 1.706) (xy -2.537 1.739) (xy -2.53 1.777) (xy -2.527 1.821) (xy -2.526 1.873) (xy -2.527 1.907)
				(xy -2.529 1.956) (xy -2.534 1.997) (xy -2.542 2.031) (xy -2.553 2.06) (xy -2.567 2.086) (xy -2.587 2.111)
				(xy -2.603 2.129) (xy -2.637 2.158) (xy -2.673 2.178) (xy -2.714 2.192) (xy -2.76 2.198) (xy -2.789 2.199)
				(xy -2.813 2.198) (xy -2.835 2.196) (xy -2.852 2.194) (xy -2.857 2.194) (xy -2.898 2.179) (xy -2.937 2.155)
				(xy -2.97 2.126) (xy -2.993 2.101) (xy -3.011 2.077) (xy -3.024 2.051) (xy -3.034 2.022) (xy -3.041 1.988)
				(xy -3.045 1.947) (xy -3.047 1.91) (xy -3.047 1.882) (xy -2.919 1.882) (xy -2.919 1.968) (xy -2.903 2.001)
				(xy -2.885 2.031) (xy -2.863 2.051) (xy -2.837 2.064) (xy -2.804 2.07) (xy -2.779 2.07) (xy -2.755 2.069)
				(xy -2.737 2.065) (xy -2.722 2.058) (xy -2.717 2.055) (xy -2.697 2.041) (xy -2.681 2.025) (xy -2.67 2.004)
				(xy -2.662 1.978) (xy -2.657 1.945) (xy -2.654 1.903) (xy -2.654 1.899) (xy -2.653 1.848) (xy -2.656 1.806)
				(xy -2.662 1.772) (xy -2.673 1.744) (xy -2.687 1.722) (xy -2.707 1.705) (xy -2.723 1.695) (xy -2.755 1.684)
				(xy -2.788 1.68) (xy -2.821 1.684) (xy -2.851 1.695) (xy -2.877 1.713) (xy -2.892 1.729) (xy -2.901 1.745)
				(xy -2.908 1.76) (xy -2.913 1.778) (xy -2.916 1.8) (xy -2.918 1.828) (xy -2.919 1.864) (xy -2.919 1.882)
				(xy -3.047 1.882) (xy -3.048 1.844) (xy -3.043 1.786) (xy -3.034 1.736) (xy -3.021 1.695) (xy -3.004 1.664)
				(xy -2.972 1.624) (xy -2.935 1.594) (xy -2.893 1.571) (xy -2.846 1.558) (xy -2.794 1.553) (xy -2.787 1.553)
				(xy -2.733 1.557)
			)
			(stroke
				(width 0.01)
				(type solid)
			)
			(fill yes)
			(layer "F.Mask")
		)
		(fp_poly
			(pts
				(xy 2.148 2.561) (xy 2.193 2.574) (xy 2.235 2.595) (xy 2.273 2.623) (xy 2.304 2.657) (xy 2.326 2.691)
				(xy 2.338 2.718) (xy 2.346 2.745) (xy 2.352 2.774) (xy 2.355 2.808) (xy 2.357 2.85) (xy 2.357 2.858)
				(xy 2.357 2.931) (xy 1.96 2.931) (xy 1.963 2.955) (xy 1.973 2.993) (xy 1.991 3.026) (xy 2.015 3.053)
				(xy 2.039 3.069) (xy 2.057 3.076) (xy 2.08 3.08) (xy 2.103 3.082) (xy 2.144 3.081) (xy 2.18 3.071)
				(xy 2.214 3.054) (xy 2.227 3.045) (xy 2.24 3.035) (xy 2.25 3.029) (xy 2.253 3.027) (xy 2.258 3.03)
				(xy 2.269 3.039) (xy 2.284 3.05) (xy 2.3 3.064) (xy 2.315 3.078) (xy 2.329 3.09) (xy 2.338 3.099)
				(xy 2.341 3.103) (xy 2.337 3.11) (xy 2.327 3.121) (xy 2.312 3.134) (xy 2.294 3.148) (xy 2.276 3.161)
				(xy 2.259 3.171) (xy 2.252 3.175) (xy 2.204 3.192) (xy 2.152 3.202) (xy 2.098 3.204) (xy 2.046 3.198)
				(xy 2.032 3.195) (xy 1.984 3.178) (xy 1.943 3.154) (xy 1.909 3.123) (xy 1.881 3.084) (xy 1.859 3.037)
				(xy 1.847 3.003) (xy 1.841 2.972) (xy 1.838 2.934) (xy 1.836 2.893) (xy 1.837 2.851) (xy 1.839 2.824)
				(xy 1.96 2.824) (xy 2.23 2.824) (xy 2.23 2.813) (xy 2.225 2.783) (xy 2.214 2.753) (xy 2.196 2.725)
				(xy 2.175 2.702) (xy 2.151 2.686) (xy 2.128 2.68) (xy 2.101 2.677) (xy 2.072 2.678) (xy 2.051 2.683)
				(xy 2.023 2.696) (xy 2 2.717) (xy 1.981 2.746) (xy 1.968 2.779) (xy 1.963 2.8) (xy 1.96 2.824) (xy 1.839 2.824)
				(xy 1.839 2.811) (xy 1.844 2.776) (xy 1.848 2.76) (xy 1.866 2.708) (xy 1.889 2.663) (xy 1.919 2.627)
				(xy 1.954 2.598) (xy 1.996 2.575) (xy 2.007 2.571) (xy 2.054 2.559) (xy 2.101 2.556) (xy 2.148 2.561)
			)
			(stroke
				(width 0.01)
				(type solid)
			)
			(fill yes)
			(layer "F.Mask")
		)
		(fp_poly
			(pts
				(xy -0.229 3.2) (xy -0.354 3.197) (xy -0.355 3.165) (xy -0.357 3.133) (xy -0.374 3.148) (xy -0.411 3.175)
				(xy -0.453 3.193) (xy -0.497 3.203) (xy -0.542 3.204) (xy -0.585 3.195) (xy -0.586 3.195) (xy -0.621 3.181)
				(xy -0.651 3.16) (xy -0.673 3.141) (xy -0.689 3.123) (xy -0.702 3.106) (xy -0.712 3.086) (xy -0.72 3.064)
				(xy -0.726 3.038) (xy -0.73 3.007) (xy -0.732 2.968) (xy -0.733 2.922) (xy -0.733 2.88) (xy -0.602 2.88)
				(xy -0.602 2.915) (xy -0.602 2.942) (xy -0.601 2.962) (xy -0.6 2.977) (xy -0.598 2.988) (xy -0.596 2.998)
				(xy -0.592 3.007) (xy -0.591 3.01) (xy -0.574 3.039) (xy -0.552 3.059) (xy -0.525 3.071) (xy -0.492 3.076)
				(xy -0.472 3.076) (xy -0.442 3.072) (xy -0.418 3.063) (xy -0.398 3.048) (xy -0.382 3.029) (xy -0.371 3.004)
				(xy -0.363 2.972) (xy -0.358 2.933) (xy -0.356 2.885) (xy -0.356 2.88) (xy -0.358 2.828) (xy -0.363 2.785)
				(xy -0.373 2.75) (xy -0.387 2.724) (xy -0.406 2.704) (xy -0.43 2.692) (xy -0.46 2.686) (xy -0.483 2.685)
				(xy -0.517 2.687) (xy -0.544 2.696) (xy -0.565 2.711) (xy -0.583 2.734) (xy -0.591 2.751) (xy -0.595 2.76)
				(xy -0.598 2.769) (xy -0.6 2.779) (xy -0.601 2.793) (xy -0.602 2.811) (xy -0.602 2.836) (xy -0.602 2.869)
				(xy -0.602 2.88) (xy -0.733 2.88) (xy -0.733 2.827) (xy -0.732 2.783) (xy -0.729 2.746) (xy -0.725 2.716)
				(xy -0.719 2.691) (xy -0.71 2.67) (xy -0.699 2.651) (xy -0.685 2.633) (xy -0.668 2.616) (xy -0.668 2.615)
				(xy -0.632 2.587) (xy -0.592 2.567) (xy -0.55 2.557) (xy -0.506 2.556) (xy -0.463 2.564) (xy -0.421 2.582)
				(xy -0.411 2.587) (xy -0.394 2.598) (xy -0.377 2.61) (xy -0.373 2.614) (xy -0.356 2.627) (xy -0.356 2.306)
				(xy -0.229 2.306) (xy -0.229 3.2)
			)
			(stroke
				(width 0.01)
				(type solid)
			)
			(fill yes)
			(layer "F.Mask")
		)
		(fp_poly
			(pts
				(xy 0.605 1.558) (xy 0.651 1.574) (xy 0.694 1.598) (xy 0.728 1.627) (xy 0.75 1.652) (xy 0.768 1.678)
				(xy 0.781 1.707) (xy 0.791 1.739) (xy 0.797 1.777) (xy 0.801 1.822) (xy 0.802 1.876) (xy 0.802 1.877)
				(xy 0.801 1.929) (xy 0.798 1.973) (xy 0.792 2.009) (xy 0.784 2.04) (xy 0.774 2.062) (xy 0.748 2.103)
				(xy 0.715 2.139) (xy 0.675 2.167) (xy 0.632 2.187) (xy 0.626 2.189) (xy 0.599 2.195) (xy 0.567 2.198)
				(xy 0.532 2.199) (xy 0.499 2.197) (xy 0.471 2.193) (xy 0.466 2.192) (xy 0.428 2.177) (xy 0.391 2.155)
				(xy 0.359 2.129) (xy 0.354 2.123) (xy 0.332 2.098) (xy 0.316 2.073) (xy 0.303 2.047) (xy 0.294 2.017)
				(xy 0.287 1.983) (xy 0.284 1.943) (xy 0.282 1.894) (xy 0.282 1.877) (xy 0.409 1.877) (xy 0.41 1.918)
				(xy 0.412 1.95) (xy 0.416 1.976) (xy 0.423 1.997) (xy 0.432 2.015) (xy 0.445 2.03) (xy 0.451 2.037)
				(xy 0.471 2.054) (xy 0.491 2.064) (xy 0.514 2.07) (xy 0.543 2.072) (xy 0.569 2.07) (xy 0.59 2.065)
				(xy 0.601 2.06) (xy 0.625 2.047) (xy 0.642 2.031) (xy 0.656 2.009) (xy 0.661 1.998) (xy 0.665 1.989)
				(xy 0.668 1.98) (xy 0.67 1.969) (xy 0.671 1.954) (xy 0.672 1.935) (xy 0.673 1.909) (xy 0.673 1.877)
				(xy 0.673 1.842) (xy 0.672 1.817) (xy 0.671 1.798) (xy 0.67 1.784) (xy 0.668 1.773) (xy 0.665 1.764)
				(xy 0.661 1.755) (xy 0.647 1.73) (xy 0.632 1.712) (xy 0.612 1.698) (xy 0.601 1.693) (xy 0.569 1.683)
				(xy 0.535 1.681) (xy 0.501 1.686) (xy 0.471 1.7) (xy 0.447 1.719) (xy 0.434 1.736) (xy 0.424 1.753)
				(xy 0.417 1.774) (xy 0.412 1.8) (xy 0.41 1.833) (xy 0.409 1.873) (xy 0.409 1.877) (xy 0.282 1.877)
				(xy 0.283 1.824) (xy 0.286 1.78) (xy 0.292 1.742) (xy 0.301 1.711) (xy 0.313 1.683) (xy 0.33 1.657)
				(xy 0.35 1.633) (xy 0.351 1.632) (xy 0.385 1.601) (xy 0.42 1.578) (xy 0.46 1.563) (xy 0.505 1.554)
				(xy 0.555 1.551) (xy 0.605 1.558)
			)
			(stroke
				(width 0.01)
				(type solid)
			)
			(fill yes)
			(layer "F.Mask")
		)
		(fp_poly
			(pts
				(xy 0.004 1.556) (xy 0.054 1.566) (xy 0.102 1.582) (xy 0.146 1.605) (xy 0.154 1.61) (xy 0.193 1.636)
				(xy 0.178 1.655) (xy 0.166 1.668) (xy 0.152 1.686) (xy 0.138 1.7) (xy 0.114 1.727) (xy 0.07 1.705)
				(xy 0.032 1.688) (xy -0.007 1.677) (xy -0.044 1.672) (xy -0.079 1.672) (xy -0.11 1.678) (xy -0.136 1.69)
				(xy -0.154 1.707) (xy -0.162 1.724) (xy -0.164 1.745) (xy -0.164 1.761) (xy -0.159 1.772) (xy -0.15 1.782)
				(xy -0.149 1.783) (xy -0.139 1.791) (xy -0.128 1.797) (xy -0.114 1.802) (xy -0.095 1.805) (xy -0.07 1.808)
				(xy -0.037 1.811) (xy -0.02 1.813) (xy 0.027 1.817) (xy 0.065 1.823) (xy 0.096 1.832) (xy 0.122 1.842)
				(xy 0.14 1.854) (xy 0.166 1.879) (xy 0.186 1.91) (xy 0.2 1.947) (xy 0.206 1.987) (xy 0.206 2.018)
				(xy 0.198 2.06) (xy 0.181 2.097) (xy 0.155 2.129) (xy 0.122 2.156) (xy 0.08 2.177) (xy 0.042 2.189)
				(xy 0.005 2.196) (xy -0.038 2.199) (xy -0.083 2.198) (xy -0.125 2.194) (xy -0.153 2.189) (xy -0.177 2.181)
				(xy -0.204 2.171) (xy -0.229 2.16) (xy -0.232 2.159) (xy -0.251 2.148) (xy -0.272 2.136) (xy -0.292 2.122)
				(xy -0.309 2.109) (xy -0.323 2.098) (xy -0.33 2.09) (xy -0.331 2.088) (xy -0.327 2.084) (xy -0.318 2.073)
				(xy -0.304 2.059) (xy -0.288 2.043) (xy -0.246 2) (xy -0.221 2.021) (xy -0.184 2.047) (xy -0.145 2.065)
				(xy -0.102 2.075) (xy -0.053 2.079) (xy -0.049 2.079) (xy -0.023 2.079) (xy -0.004 2.078) (xy 0.011 2.074)
				(xy 0.025 2.069) (xy 0.029 2.068) (xy 0.054 2.052) (xy 0.071 2.033) (xy 0.079 2.01) (xy 0.078 1.986)
				(xy 0.074 1.975) (xy 0.068 1.964) (xy 0.06 1.956) (xy 0.048 1.949) (xy 0.031 1.944) (xy 0.007 1.939)
				(xy -0.024 1.935) (xy -0.052 1.932) (xy -0.089 1.929) (xy -0.119 1.925) (xy -0.142 1.921) (xy -0.16 1.917)
				(xy -0.176 1.912) (xy -0.192 1.906) (xy -0.201 1.901) (xy -0.235 1.879) (xy -0.262 1.85) (xy -0.28 1.816)
				(xy -0.29 1.776) (xy -0.292 1.75) (xy -0.291 1.727) (xy -0.289 1.705) (xy -0.286 1.689) (xy -0.286 1.688)
				(xy -0.273 1.659) (xy -0.253 1.63) (xy -0.229 1.604) (xy -0.221 1.599) (xy -0.185 1.577) (xy -0.143 1.562)
				(xy -0.096 1.554) (xy -0.047 1.552) (xy 0.004 1.556)
			)
			(stroke
				(width 0.01)
				(type solid)
			)
			(fill yes)
			(layer "F.Mask")
		)
		(fp_poly
			(pts
				(xy 1.038 2.556) (xy 1.091 2.563) (xy 1.137 2.576) (xy 1.177 2.595) (xy 1.209 2.62) (xy 1.234 2.65)
				(xy 1.242 2.665) (xy 1.247 2.677) (xy 1.251 2.691) (xy 1.255 2.708) (xy 1.258 2.727) (xy 1.26 2.751)
				(xy 1.262 2.78) (xy 1.263 2.815) (xy 1.263 2.858) (xy 1.264 2.908) (xy 1.263 2.967) (xy 1.263 2.989)
				(xy 1.262 3.197) (xy 1.135 3.197) (xy 1.133 3.171) (xy 1.132 3.144) (xy 1.119 3.159) (xy 1.096 3.179)
				(xy 1.065 3.193) (xy 1.026 3.202) (xy 0.98 3.204) (xy 0.976 3.204) (xy 0.955 3.204) (xy 0.937 3.203)
				(xy 0.925 3.202) (xy 0.924 3.201) (xy 0.879 3.189) (xy 0.839 3.17) (xy 0.806 3.144) (xy 0.781 3.113)
				(xy 0.763 3.077) (xy 0.753 3.037) (xy 0.753 3.005) (xy 0.873 3.005) (xy 0.874 3.023) (xy 0.878 3.035)
				(xy 0.887 3.047) (xy 0.89 3.05) (xy 0.903 3.063) (xy 0.917 3.072) (xy 0.935 3.078) (xy 0.957 3.081)
				(xy 0.986 3.082) (xy 1.013 3.082) (xy 1.043 3.081) (xy 1.065 3.079) (xy 1.08 3.077) (xy 1.091 3.073)
				(xy 1.096 3.071) (xy 1.112 3.058) (xy 1.123 3.039) (xy 1.13 3.012) (xy 1.132 2.977) (xy 1.132 2.975)
				(xy 1.132 2.931) (xy 1.035 2.931) (xy 0.999 2.931) (xy 0.973 2.931) (xy 0.953 2.932) (xy 0.939 2.934)
				(xy 0.928 2.936) (xy 0.919 2.939) (xy 0.916 2.94) (xy 0.893 2.954) (xy 0.88 2.971) (xy 0.874 2.994)
				(xy 0.873 3.005) (xy 0.753 3.005) (xy 0.753 2.994) (xy 0.761 2.951) (xy 0.768 2.931) (xy 0.776 2.915)
				(xy 0.786 2.901) (xy 0.802 2.884) (xy 0.804 2.882) (xy 0.82 2.867) (xy 0.835 2.854) (xy 0.85 2.845)
				(xy 0.867 2.838) (xy 0.887 2.833) (xy 0.912 2.829) (xy 0.943 2.827) (xy 0.982 2.826) (xy 1.015 2.825)
				(xy 1.133 2.823) (xy 1.132 2.771) (xy 1.131 2.746) (xy 1.129 2.73) (xy 1.127 2.719) (xy 1.123 2.711)
				(xy 1.117 2.705) (xy 1.098 2.691) (xy 1.07 2.682) (xy 1.032 2.677) (xy 1.006 2.677) (xy 0.972 2.678)
				(xy 0.945 2.682) (xy 0.924 2.688) (xy 0.907 2.699) (xy 0.9 2.706) (xy 0.882 2.723) (xy 0.834 2.686)
				(xy 0.816 2.672) (xy 0.801 2.66) (xy 0.79 2.652) (xy 0.787 2.648) (xy 0.791 2.639) (xy 0.801 2.626)
				(xy 0.816 2.612) (xy 0.832 2.6) (xy 0.864 2.581) (xy 0.902 2.568) (xy 0.946 2.559) (xy 0.98 2.556)
				(xy 1.038 2.556)
			)
			(stroke
				(width 0.01)
				(type solid)
			)
			(fill yes)
			(layer "F.Mask")
		)
		(fp_poly
			(pts
				(xy -1.521 2.559) (xy -1.485 2.562) (xy -1.454 2.568) (xy -1.427 2.577) (xy -1.401 2.589) (xy -1.371 2.61)
				(xy -1.345 2.639) (xy -1.325 2.67) (xy -1.321 2.679) (xy -1.309 2.71) (xy -1.309 3.197) (xy -1.433 3.2)
				(xy -1.433 3.172) (xy -1.434 3.157) (xy -1.435 3.147) (xy -1.436 3.144) (xy -1.44 3.147) (xy -1.449 3.156)
				(xy -1.453 3.161) (xy -1.472 3.178) (xy -1.496 3.19) (xy -1.526 3.198) (xy -1.563 3.202) (xy -1.578 3.203)
				(xy -1.603 3.203) (xy -1.627 3.203) (xy -1.647 3.201) (xy -1.656 3.2) (xy -1.686 3.191) (xy -1.717 3.176)
				(xy -1.746 3.159) (xy -1.765 3.143) (xy -1.79 3.111) (xy -1.807 3.075) (xy -1.816 3.037) (xy -1.817 2.998)
				(xy -1.817 2.997) (xy -1.697 2.997) (xy -1.696 3.02) (xy -1.687 3.042) (xy -1.67 3.06) (xy -1.668 3.062)
				(xy -1.654 3.07) (xy -1.64 3.076) (xy -1.624 3.08) (xy -1.602 3.081) (xy -1.574 3.082) (xy -1.558 3.082)
				(xy -1.529 3.081) (xy -1.508 3.08) (xy -1.494 3.078) (xy -1.483 3.075) (xy -1.474 3.07) (xy -1.458 3.058)
				(xy -1.447 3.041) (xy -1.44 3.017) (xy -1.435 2.985) (xy -1.435 2.977) (xy -1.432 2.931) (xy -1.533 2.931)
				(xy -1.568 2.931) (xy -1.595 2.931) (xy -1.615 2.932) (xy -1.63 2.934) (xy -1.641 2.936) (xy -1.65 2.938)
				(xy -1.655 2.941) (xy -1.676 2.955) (xy -1.69 2.974) (xy -1.697 2.997) (xy -1.817 2.997) (xy -1.811 2.96)
				(xy -1.797 2.924) (xy -1.775 2.892) (xy -1.747 2.864) (xy -1.715 2.845) (xy -1.7 2.838) (xy -1.685 2.833)
				(xy -1.668 2.83) (xy -1.648 2.827) (xy -1.623 2.825) (xy -1.591 2.824) (xy -1.551 2.824) (xy -1.54 2.824)
				(xy -1.432 2.824) (xy -1.434 2.776) (xy -1.436 2.747) (xy -1.441 2.726) (xy -1.448 2.711) (xy -1.46 2.699)
				(xy -1.474 2.689) (xy -1.483 2.685) (xy -1.492 2.682) (xy -1.505 2.68) (xy -1.524 2.68) (xy -1.55 2.679)
				(xy -1.56 2.679) (xy -1.594 2.68) (xy -1.62 2.682) (xy -1.639 2.686) (xy -1.654 2.692) (xy -1.666 2.701)
				(xy -1.675 2.711) (xy -1.686 2.724) (xy -1.735 2.686) (xy -1.754 2.672) (xy -1.769 2.659) (xy -1.78 2.65)
				(xy -1.784 2.646) (xy -1.78 2.64) (xy -1.77 2.629) (xy -1.756 2.616) (xy -1.74 2.604) (xy -1.724 2.592)
				(xy -1.711 2.584) (xy -1.71 2.583) (xy -1.688 2.574) (xy -1.668 2.566) (xy -1.647 2.562) (xy -1.623 2.559)
				(xy -1.593 2.558) (xy -1.565 2.558) (xy -1.521 2.559)
			)
			(stroke
				(width 0.01)
				(type solid)
			)
			(fill yes)
			(layer "F.Mask")
		)
		(fp_poly
			(pts
				(xy 0.035 2.777) (xy 0.047 2.822) (xy 0.059 2.864) (xy 0.069 2.903) (xy 0.078 2.936) (xy 0.086 2.963)
				(xy 0.092 2.984) (xy 0.095 2.996) (xy 0.096 2.999) (xy 0.098 2.999) (xy 0.103 2.991) (xy 0.109 2.975)
				(xy 0.118 2.95) (xy 0.129 2.917) (xy 0.143 2.874) (xy 0.152 2.849) (xy 0.165 2.807) (xy 0.179 2.766)
				(xy 0.192 2.726) (xy 0.204 2.689) (xy 0.214 2.658) (xy 0.221 2.634) (xy 0.224 2.627) (xy 0.244 2.565)
				(xy 0.338 2.565) (xy 0.406 2.774) (xy 0.42 2.819) (xy 0.434 2.861) (xy 0.446 2.899) (xy 0.457 2.932)
				(xy 0.466 2.96) (xy 0.473 2.981) (xy 0.477 2.993) (xy 0.478 2.997) (xy 0.48 2.998) (xy 0.482 2.996)
				(xy 0.485 2.99) (xy 0.49 2.978) (xy 0.495 2.96) (xy 0.502 2.936) (xy 0.511 2.905) (xy 0.523 2.865)
				(xy 0.536 2.817) (xy 0.543 2.789) (xy 0.556 2.744) (xy 0.568 2.701) (xy 0.578 2.663) (xy 0.587 2.629)
				(xy 0.595 2.602) (xy 0.601 2.582) (xy 0.605 2.57) (xy 0.606 2.567) (xy 0.611 2.566) (xy 0.625 2.566)
				(xy 0.645 2.566) (xy 0.669 2.566) (xy 0.673 2.566) (xy 0.739 2.567) (xy 0.656 2.827) (xy 0.64 2.878)
				(xy 0.624 2.928) (xy 0.609 2.976) (xy 0.595 3.02) (xy 0.582 3.06) (xy 0.571 3.094) (xy 0.563 3.121)
				(xy 0.557 3.139) (xy 0.556 3.143) (xy 0.538 3.2) (xy 0.425 3.197) (xy 0.358 2.975) (xy 0.341 2.917)
				(xy 0.327 2.87) (xy 0.315 2.831) (xy 0.305 2.801) (xy 0.297 2.78) (xy 0.292 2.766) (xy 0.289 2.761)
				(xy 0.288 2.761) (xy 0.286 2.768) (xy 0.281 2.783) (xy 0.274 2.806) (xy 0.265 2.836) (xy 0.254 2.871)
				(xy 0.242 2.911) (xy 0.23 2.953) (xy 0.223 2.976) (xy 0.21 3.02) (xy 0.197 3.062) (xy 0.186 3.099)
				(xy 0.177 3.132) (xy 0.169 3.158) (xy 0.163 3.177) (xy 0.16 3.189) (xy 0.159 3.191) (xy 0.157 3.195)
				(xy 0.151 3.198) (xy 0.141 3.199) (xy 0.124 3.2) (xy 0.101 3.2) (xy 0.073 3.199) (xy 0.055 3.198)
				(xy 0.045 3.196) (xy 0.043 3.194) (xy 0.041 3.188) (xy 0.036 3.173) (xy 0.029 3.15) (xy 0.019 3.121)
				(xy 0.008 3.084) (xy -0.006 3.043) (xy -0.02 2.996) (xy -0.036 2.946) (xy -0.053 2.893) (xy -0.057 2.883)
				(xy -0.074 2.83) (xy -0.09 2.779) (xy -0.105 2.732) (xy -0.119 2.689) (xy -0.131 2.652) (xy -0.141 2.621)
				(xy -0.148 2.596) (xy -0.154 2.58) (xy -0.156 2.572) (xy -0.156 2.569) (xy -0.151 2.567) (xy -0.14 2.566)
				(xy -0.123 2.565) (xy -0.096 2.565) (xy -0.091 2.565) (xy -0.023 2.565) (xy 0.035 2.777)
			)
			(stroke
				(width 0.01)
				(type solid)
			)
			(fill yes)
			(layer "F.Mask")
		)
		(fp_poly
			(pts
				(xy -2.065 1.559) (xy -2.024 1.576) (xy -1.986 1.601) (xy -1.973 1.612) (xy -1.957 1.63) (xy -1.943 1.649)
				(xy -1.932 1.668) (xy -1.924 1.69) (xy -1.918 1.716) (xy -1.914 1.747) (xy -1.911 1.785) (xy -1.91 1.831)
				(xy -1.91 1.877) (xy -1.91 1.93) (xy -1.912 1.974) (xy -1.914 2.011) (xy -1.919 2.041) (xy -1.925 2.067)
				(xy -1.934 2.088) (xy -1.945 2.107) (xy -1.959 2.125) (xy -1.972 2.139) (xy -1.993 2.157) (xy -2.018 2.173)
				(xy -2.031 2.18) (xy -2.047 2.188) (xy -2.06 2.192) (xy -2.074 2.195) (xy -2.091 2.196) (xy -2.114 2.197)
				(xy -2.122 2.197) (xy -2.147 2.196) (xy -2.165 2.195) (xy -2.179 2.193) (xy -2.191 2.189) (xy -2.205 2.183)
				(xy -2.21 2.18) (xy -2.231 2.169) (xy -2.251 2.156) (xy -2.265 2.146) (xy -2.286 2.127) (xy -2.286 2.627)
				(xy -2.266 2.608) (xy -2.248 2.595) (xy -2.227 2.582) (xy -2.217 2.577) (xy -2.173 2.562) (xy -2.129 2.556)
				(xy -2.086 2.559) (xy -2.045 2.57) (xy -2.007 2.589) (xy -1.974 2.616) (xy -1.946 2.648) (xy -1.926 2.687)
				(xy -1.919 2.707) (xy -1.917 2.715) (xy -1.915 2.724) (xy -1.914 2.737) (xy -1.913 2.753) (xy -1.912 2.774)
				(xy -1.911 2.8) (xy -1.911 2.833) (xy -1.911 2.874) (xy -1.911 2.923) (xy -1.911 2.967) (xy -1.911 3.2)
				(xy -2.035 3.197) (xy -2.038 2.984) (xy -2.038 2.932) (xy -2.039 2.889) (xy -2.039 2.854) (xy -2.04 2.826)
				(xy -2.041 2.805) (xy -2.042 2.788) (xy -2.043 2.776) (xy -2.045 2.767) (xy -2.046 2.76) (xy -2.049 2.755)
				(xy -2.051 2.75) (xy -2.072 2.721) (xy -2.098 2.701) (xy -2.128 2.688) (xy -2.161 2.683) (xy -2.195 2.687)
				(xy -2.22 2.697) (xy -2.24 2.71) (xy -2.259 2.729) (xy -2.274 2.75) (xy -2.278 2.757) (xy -2.28 2.765)
				(xy -2.281 2.781) (xy -2.283 2.806) (xy -2.284 2.839) (xy -2.285 2.881) (xy -2.286 2.933) (xy -2.286 2.984)
				(xy -2.289 3.197) (xy -2.413 3.2) (xy -2.413 1.877) (xy -2.286 1.877) (xy -2.285 1.926) (xy -2.281 1.966)
				(xy -2.274 1.998) (xy -2.262 2.024) (xy -2.247 2.043) (xy -2.228 2.058) (xy -2.215 2.064) (xy -2.194 2.07)
				(xy -2.168 2.072) (xy -2.141 2.071) (xy -2.117 2.066) (xy -2.106 2.063) (xy -2.079 2.044) (xy -2.058 2.019)
				(xy -2.05 2.001) (xy -2.045 1.984) (xy -2.042 1.959) (xy -2.04 1.929) (xy -2.038 1.895) (xy -2.038 1.861)
				(xy -2.039 1.829) (xy -2.041 1.8) (xy -2.044 1.777) (xy -2.045 1.772) (xy -2.057 1.738) (xy -2.073 1.712)
				(xy -2.094 1.695) (xy -2.122 1.684) (xy -2.156 1.681) (xy -2.159 1.681) (xy -2.192 1.683) (xy -2.22 1.691)
				(xy -2.243 1.705) (xy -2.26 1.725) (xy -2.273 1.753) (xy -2.281 1.788) (xy -2.285 1.832) (xy -2.286 1.877)
				(xy -2.413 1.877) (xy -2.413 1.559) (xy -2.286 1.559) (xy -2.286 1.62) (xy -2.26 1.6) (xy -2.225 1.577)
				(xy -2.19 1.563) (xy -2.154 1.554) (xy -2.109 1.552) (xy -2.065 1.559)
			)
			(stroke
				(width 0.01)
				(type solid)
			)
			(fill yes)
			(layer "F.Mask")
		)
		(fp_poly
			(pts
				(xy 0.063 -3.201) (xy 0.118 -3.201) (xy 0.164 -3.201) (xy 0.202 -3.2) (xy 0.233 -3.2) (xy 0.258 -3.2)
				(xy 0.277 -3.199) (xy 0.292 -3.198) (xy 0.302 -3.197) (xy 0.309 -3.196) (xy 0.314 -3.195) (xy 0.317 -3.193)
				(xy 0.319 -3.192) (xy 0.321 -3.189) (xy 0.324 -3.183) (xy 0.327 -3.174) (xy 0.33 -3.161) (xy 0.334 -3.144)
				(xy 0.339 -3.12) (xy 0.345 -3.091) (xy 0.352 -3.054) (xy 0.361 -3.01) (xy 0.371 -2.958) (xy 0.382 -2.897)
				(xy 0.385 -2.878) (xy 0.395 -2.824) (xy 0.405 -2.772) (xy 0.414 -2.724) (xy 0.423 -2.68) (xy 0.43 -2.642)
				(xy 0.437 -2.61) (xy 0.442 -2.586) (xy 0.446 -2.569) (xy 0.448 -2.562) (xy 0.456 -2.55) (xy 0.464 -2.544)
				(xy 0.476 -2.539) (xy 0.495 -2.53) (xy 0.521 -2.519) (xy 0.552 -2.506) (xy 0.587 -2.492) (xy 0.624 -2.477)
				(xy 0.664 -2.461) (xy 0.704 -2.445) (xy 0.743 -2.43) (xy 0.78 -2.415) (xy 0.814 -2.402) (xy 0.843 -2.391)
				(xy 0.868 -2.382) (xy 0.885 -2.376) (xy 0.895 -2.373) (xy 0.896 -2.373) (xy 0.911 -2.376) (xy 0.931 -2.386)
				(xy 0.948 -2.397) (xy 0.962 -2.406) (xy 0.983 -2.421) (xy 1.011 -2.44) (xy 1.043 -2.462) (xy 1.079 -2.487)
				(xy 1.118 -2.513) (xy 1.158 -2.541) (xy 1.198 -2.568) (xy 1.238 -2.595) (xy 1.275 -2.621) (xy 1.309 -2.644)
				(xy 1.338 -2.665) (xy 1.362 -2.681) (xy 1.377 -2.691) (xy 1.398 -2.705) (xy 1.418 -2.717) (xy 1.433 -2.725)
				(xy 1.442 -2.728) (xy 1.443 -2.728) (xy 1.448 -2.726) (xy 1.456 -2.72) (xy 1.468 -2.71) (xy 1.486 -2.694)
				(xy 1.508 -2.673) (xy 1.535 -2.647) (xy 1.568 -2.614) (xy 1.608 -2.575) (xy 1.654 -2.53) (xy 1.675 -2.509)
				(xy 1.721 -2.462) (xy 1.761 -2.422) (xy 1.794 -2.388) (xy 1.822 -2.36) (xy 1.844 -2.337) (xy 1.862 -2.318)
				(xy 1.875 -2.304) (xy 1.884 -2.293) (xy 1.89 -2.284) (xy 1.893 -2.279) (xy 1.894 -2.275) (xy 1.892 -2.269)
				(xy 1.886 -2.257) (xy 1.875 -2.239) (xy 1.86 -2.215) (xy 1.839 -2.183) (xy 1.814 -2.145) (xy 1.783 -2.1)
				(xy 1.747 -2.046) (xy 1.721 -2.009) (xy 1.69 -1.964) (xy 1.661 -1.921) (xy 1.634 -1.88) (xy 1.609 -1.844)
				(xy 1.588 -1.811) (xy 1.57 -1.785) (xy 1.557 -1.764) (xy 1.549 -1.75) (xy 1.546 -1.743) (xy 1.547 -1.735)
				(xy 1.552 -1.719) (xy 1.56 -1.696) (xy 1.571 -1.667) (xy 1.585 -1.634) (xy 1.6 -1.597) (xy 1.616 -1.557)
				(xy 1.633 -1.516) (xy 1.651 -1.476) (xy 1.668 -1.436) (xy 1.685 -1.398) (xy 1.701 -1.363) (xy 1.715 -1.333)
				(xy 1.727 -1.309) (xy 1.736 -1.291) (xy 1.742 -1.281) (xy 1.744 -1.279) (xy 1.751 -1.277) (xy 1.767 -1.273)
				(xy 1.791 -1.268) (xy 1.822 -1.261) (xy 1.86 -1.254) (xy 1.903 -1.245) (xy 1.951 -1.236) (xy 2.002 -1.226)
				(xy 2.049 -1.217) (xy 2.103 -1.207) (xy 2.154 -1.198) (xy 2.201 -1.188) (xy 2.244 -1.18) (xy 2.281 -1.173)
				(xy 2.311 -1.166) (xy 2.335 -1.161) (xy 2.35 -1.157) (xy 2.355 -1.156) (xy 2.367 -1.148) (xy 2.367 -0.834)
				(xy 2.367 -0.768) (xy 2.367 -0.712) (xy 2.367 -0.664) (xy 2.366 -0.625) (xy 2.366 -0.592) (xy 2.365 -0.566)
				(xy 2.364 -0.546) (xy 2.363 -0.531) (xy 2.361 -0.52) (xy 2.358 -0.512) (xy 2.355 -0.507) (xy 2.352 -0.504)
				(xy 2.348 -0.503) (xy 2.343 -0.501) (xy 2.34 -0.501) (xy 2.333 -0.499) (xy 2.317 -0.496) (xy 2.293 -0.492)
				(xy 2.261 -0.486) (xy 2.224 -0.479) (xy 2.181 -0.471) (xy 2.134 -0.462) (xy 2.084 -0.453) (xy 2.054 -0.448)
				(xy 2.002 -0.438) (xy 1.953 -0.429) (xy 1.907 -0.42) (xy 1.866 -0.412) (xy 1.831 -0.404) (xy 1.802 -0.398)
				(xy 1.78 -0.394) (xy 1.767 -0.391) (xy 1.764 -0.39) (xy 1.76 -0.387) (xy 1.757 -0.384) (xy 1.753 -0.379)
				(xy 1.748 -0.371) (xy 1.742 -0.36) (xy 1.735 -0.344) (xy 1.726 -0.324) (xy 1.715 -0.297) (xy 1.701 -0.264)
				(xy 1.685 -0.223) (xy 1.665 -0.174) (xy 1.653 -0.145) (xy 1.63 -0.086) (xy 1.61 -0.037) (xy 1.594 0.005)
				(xy 1.582 0.038) (xy 1.572 0.064) (xy 1.566 0.084) (xy 1.562 0.097) (xy 1.561 0.104) (xy 1.562 0.105)
				(xy 1.565 0.111) (xy 1.574 0.125) (xy 1.587 0.146) (xy 1.604 0.173) (xy 1.626 0.205) (xy 1.65 0.241)
				(xy 1.677 0.281) (xy 1.706 0.324) (xy 1.729 0.358) (xy 1.768 0.413) (xy 1.8 0.461) (xy 1.827 0.502)
				(xy 1.85 0.535) (xy 1.867 0.562) (xy 1.88 0.583) (xy 1.889 0.598) (xy 1.893 0.608) (xy 1.894 0.612)
				(xy 1.893 0.616) (xy 1.89 0.622) (xy 1.885 0.63) (xy 1.876 0.64) (xy 1.863 0.655) (xy 1.846 0.673)
				(xy 1.825 0.695) (xy 1.798 0.723) (xy 1.765 0.756) (xy 1.727 0.795) (xy 1.682 0.839) (xy 1.635 0.886)
				(xy 1.595 0.926) (xy 1.561 0.96) (xy 1.532 0.989) (xy 1.508 1.012) (xy 1.488 1.03) (xy 1.473 1.044)
				(xy 1.461 1.054) (xy 1.452 1.061) (xy 1.445 1.065) (xy 1.44 1.066) (xy 1.438 1.066) (xy 1.433 1.064)
				(xy 1.421 1.055) (xy 1.401 1.043) (xy 1.376 1.026) (xy 1.345 1.005) (xy 1.31 0.981) (xy 1.27 0.954)
				(xy 1.228 0.925) (xy 1.193 0.901) (xy 1.138 0.864) (xy 1.089 0.83) (xy 1.046 0.802) (xy 1.01 0.778)
				(xy 0.981 0.759) (xy 0.96 0.746) (xy 0.946 0.738) (xy 0.94 0.736) (xy 0.932 0.738) (xy 0.917 0.745)
				(xy 0.895 0.755) (xy 0.869 0.768) (xy 0.84 0.783) (xy 0.816 0.795) (xy 0.781 0.814) (xy 0.753 0.828)
				(xy 0.732 0.838) (xy 0.717 0.845) (xy 0.707 0.849) (xy 0.699 0.85) (xy 0.694 0.849) (xy 0.691 0.847)
				(xy 0.687 0.84) (xy 0.682 0.829) (xy 0.674 0.814) (xy 0.665 0.793) (xy 0.653 0.767) (xy 0.639 0.735)
				(xy 0.623 0.696) (xy 0.604 0.651) (xy 0.582 0.598) (xy 0.556 0.538) (xy 0.528 0.469) (xy 0.496 0.391)
				(xy 0.47 0.329) (xy 0.436 0.247) (xy 0.406 0.173) (xy 0.379 0.108) (xy 0.355 0.05) (xy 0.335 0)
				(xy 0.317 -0.043) (xy 0.303 -0.079) (xy 0.291 -0.11) (xy 0.281 -0.135) (xy 0.273 -0.155) (xy 0.268 -0.171)
				(xy 0.264 -0.183) (xy 0.262 -0.191) (xy 0.262 -0.196) (xy 0.262 -0.198) (xy 0.269 -0.207) (xy 0.283 -0.219)
				(xy 0.302 -0.233) (xy 0.303 -0.234) (xy 0.354 -0.268) (xy 0.398 -0.3) (xy 0.435 -0.331) (xy 0.469 -0.363)
				(xy 0.5 -0.397) (xy 0.507 -0.405) (xy 0.556 -0.472) (xy 0.596 -0.543) (xy 0.627 -0.619) (xy 0.643 -0.672)
				(xy 0.651 -0.718) (xy 0.657 -0.77) (xy 0.66 -0.824) (xy 0.659 -0.878) (xy 0.654 -0.927) (xy 0.652 -0.936)
				(xy 0.634 -1.015) (xy 0.607 -1.09) (xy 0.571 -1.161) (xy 0.528 -1.227) (xy 0.477 -1.287) (xy 0.419 -1.341)
				(xy 0.355 -1.387) (xy 0.285 -1.426) (xy 0.21 -1.456) (xy 0.205 -1.458) (xy 0.131 -1.477) (xy 0.054 -1.487)
				(xy -0.025 -1.489) (xy -0.103 -1.482) (xy -0.178 -1.466) (xy -0.206 -1.458) (xy -0.281 -1.428) (xy -0.351 -1.39)
				(xy -0.416 -1.344) (xy -0.474 -1.29) (xy -0.526 -1.23) (xy -0.571 -1.164) (xy -0.607 -1.093) (xy -0.63 -1.034)
				(xy -0.649 -0.96) (xy -0.659 -0.883) (xy -0.661 -0.804) (xy -0.654 -0.726) (xy -0.638 -0.651) (xy -0.63 -0.623)
				(xy -0.618 -0.591) (xy -0.602 -0.554) (xy -0.584 -0.518) (xy -0.566 -0.485) (xy -0.553 -0.463) (xy -0.509 -0.407)
				(xy -0.457 -0.352) (xy -0.397 -0.299) (xy -0.33 -0.25) (xy -0.289 -0.224) (xy -0.273 -0.212) (xy -0.263 -0.2)
				(xy -0.262 -0.197) (xy -0.263 -0.19) (xy -0.268 -0.175) (xy -0.277 -0.151) (xy -0.288 -0.121) (xy -0.302 -0.084)
				(xy -0.319 -0.042) (xy -0.338 0.005) (xy -0.358 0.056) (xy -0.381 0.111) (xy -0.404 0.168) (xy -0.428 0.228)
				(xy -0.453 0.288) (xy -0.478 0.349) (xy -0.504 0.41) (xy -0.529 0.47) (xy -0.553 0.527) (xy -0.576 0.583)
				(xy -0.598 0.635) (xy -0.619 0.683) (xy -0.638 0.727) (xy -0.655 0.765) (xy -0.669 0.797) (xy -0.68 0.822)
				(xy -0.689 0.839) (xy -0.694 0.848) (xy -0.695 0.849) (xy -0.699 0.85) (xy -0.706 0.849) (xy -0.717 0.845)
				(xy -0.732 0.839) (xy -0.752 0.829) (xy -0.779 0.815) (xy -0.814 0.797) (xy -0.817 0.795) (xy -0.848 0.779)
				(xy -0.877 0.764) (xy -0.902 0.752) (xy -0.922 0.743) (xy -0.936 0.737) (xy -0.941 0.736) (xy -0.949 0.739)
				(xy -0.964 0.748) (xy -0.987 0.761) (xy -1.015 0.78) (xy -1.05 0.803) (xy -1.072 0.818) (xy -1.138 0.863)
				(xy -1.195 0.903) (xy -1.245 0.937) (xy -1.289 0.966) (xy -1.325 0.991) (xy -1.356 1.012) (xy -1.381 1.029)
				(xy -1.401 1.042) (xy -1.416 1.052) (xy -1.427 1.059) (xy -1.435 1.064) (xy -1.439 1.066) (xy -1.44 1.066)
				(xy -1.449 1.064) (xy -1.453 1.061) (xy -1.458 1.057) (xy -1.47 1.046) (xy -1.487 1.029) (xy -1.509 1.007)
				(xy -1.537 0.98) (xy -1.568 0.95) (xy -1.602 0.915) (xy -1.639 0.879) (xy -1.678 0.84) (xy -1.678 0.839)
				(xy -1.726 0.792) (xy -1.767 0.751) (xy -1.801 0.716) (xy -1.829 0.687) (xy -1.852 0.663) (xy -1.869 0.644)
				(xy -1.882 0.63) (xy -1.89 0.62) (xy -1.894 0.613) (xy -1.895 0.61) (xy -1.892 0.603) (xy -1.884 0.588)
				(xy -1.87 0.565) (xy -1.85 0.536) (xy -1.826 0.499) (xy -1.797 0.455) (xy -1.763 0.405) (xy -1.73 0.358)
				(xy -1.7 0.313) (xy -1.671 0.271) (xy -1.645 0.232) (xy -1.621 0.197) (xy -1.601 0.166) (xy -1.584 0.141)
				(xy -1.572 0.121) (xy -1.565 0.109) (xy -1.563 0.105) (xy -1.563 0.099) (xy -1.566 0.087) (xy -1.572 0.07)
				(xy -1.58 0.045) (xy -1.592 0.013) (xy -1.607 -0.026) (xy -1.626 -0.074) (xy -1.648 -0.13) (xy -1.654 -0.145)
				(xy -1.676 -0.199) (xy -1.695 -0.245) (xy -1.71 -0.282) (xy -1.723 -0.313) (xy -1.733 -0.337) (xy -1.741 -0.356)
				(xy -1.748 -0.369) (xy -1.753 -0.379) (xy -1.758 -0.385) (xy -1.761 -0.388) (xy -1.763 -0.389) (xy -1.767 -0.39)
				(xy -1.774 -0.392) (xy -1.784 -0.395) (xy -1.799 -0.398) (xy -1.818 -0.402) (xy -1.843 -0.407) (xy -1.873 -0.413)
				(xy -1.91 -0.42) (xy -1.954 -0.429) (xy -2.005 -0.438) (xy -2.065 -0.449) (xy -2.133 -0.462) (xy -2.211 -0.477)
				(xy -2.22 -0.478) (xy -2.26 -0.486) (xy -2.29 -0.491) (xy -2.313 -0.496) (xy -2.33 -0.499) (xy -2.341 -0.502)
				(xy -2.349 -0.504) (xy -2.353 -0.506) (xy -2.356 -0.508) (xy -2.359 -0.51) (xy -2.36 -0.511) (xy -2.361 -0.514)
				(xy -2.363 -0.518) (xy -2.364 -0.526) (xy -2.365 -0.536) (xy -2.366 -0.551) (xy -2.366 -0.571) (xy -2.367 -0.597)
				(xy -2.367 -0.629) (xy -2.368 -0.668) (xy -2.368 -0.715) (xy -2.368 -0.771) (xy -2.368 -0.834) (xy -2.368 -1.148)
				(xy -2.356 -1.155) (xy -2.349 -1.158) (xy -2.333 -1.162) (xy -2.309 -1.167) (xy -2.278 -1.173) (xy -2.24 -1.181)
				(xy -2.197 -1.189) (xy -2.149 -1.198) (xy -2.098 -1.208) (xy -2.051 -1.217) (xy -1.996 -1.227) (xy -1.945 -1.237)
				(xy -1.897 -1.246) (xy -1.854 -1.254) (xy -1.817 -1.262) (xy -1.787 -1.268) (xy -1.764 -1.273) (xy -1.75 -1.277)
				(xy -1.745 -1.279) (xy -1.741 -1.285) (xy -1.733 -1.3) (xy -1.722 -1.322) (xy -1.709 -1.35) (xy -1.694 -1.382)
				(xy -1.677 -1.419) (xy -1.66 -1.458) (xy -1.642 -1.498) (xy -1.625 -1.539) (xy -1.608 -1.58) (xy -1.592 -1.618)
				(xy -1.578 -1.653) (xy -1.565 -1.684) (xy -1.556 -1.709) (xy -1.549 -1.729) (xy -1.546 -1.74) (xy -1.546 -1.742)
				(xy -1.549 -1.749) (xy -1.558 -1.763) (xy -1.571 -1.784) (xy -1.588 -1.811) (xy -1.61 -1.843) (xy -1.634 -1.88)
				(xy -1.661 -1.92) (xy -1.691 -1.963) (xy -1.722 -2.008) (xy -1.762 -2.067) (xy -1.796 -2.117) (xy -1.825 -2.16)
				(xy -1.848 -2.196) (xy -1.867 -2.225) (xy -1.881 -2.247) (xy -1.89 -2.262) (xy -1.895 -2.272) (xy -1.895 -2.275)
				(xy -1.894 -2.279) (xy -1.891 -2.285) (xy -1.884 -2.293) (xy -1.875 -2.305) (xy -1.861 -2.32) (xy -1.843 -2.339)
				(xy -1.82 -2.363) (xy -1.792 -2.392) (xy -1.758 -2.426) (xy -1.718 -2.466) (xy -1.676 -2.509) (xy -1.627 -2.557)
				(xy -1.585 -2.599) (xy -1.549 -2.634) (xy -1.52 -2.663) (xy -1.495 -2.686) (xy -1.476 -2.704) (xy -1.462 -2.716)
				(xy -1.452 -2.724) (xy -1.446 -2.728) (xy -1.444 -2.728) (xy -1.437 -2.726) (xy -1.423 -2.717) (xy -1.401 -2.703)
				(xy -1.372 -2.685) (xy -1.337 -2.661) (xy -1.295 -2.634) (xy -1.248 -2.602) (xy -1.196 -2.566) (xy -1.173 -2.551)
				(xy -1.118 -2.513) (xy -1.071 -2.481) (xy -1.031 -2.454) (xy -0.998 -2.432) (xy -0.97 -2.413) (xy -0.948 -2.399)
				(xy -0.931 -2.389) (xy -0.917 -2.381) (xy -0.907 -2.376) (xy -0.901 -2.373) (xy -0.897 -2.373) (xy -0.888 -2.375)
				(xy -0.87 -2.38) (xy -0.845 -2.39) (xy -0.813 -2.402) (xy -0.774 -2.417) (xy -0.73 -2.434) (xy -0.681 -2.454)
				(xy -0.629 -2.475) (xy -0.586 -2.493) (xy -0.55 -2.508) (xy -0.522 -2.52) (xy -0.499 -2.529) (xy -0.482 -2.537)
				(xy -0.47 -2.543) (xy -0.461 -2.548) (xy -0.455 -2.551) (xy -0.452 -2.554) (xy -0.449 -2.557) (xy -0.448 -2.56)
				(xy -0.447 -2.566) (xy -0.443 -2.582) (xy -0.438 -2.605) (xy -0.432 -2.637) (xy -0.425 -2.674) (xy -0.417 -2.717)
				(xy -0.407 -2.765) (xy -0.398 -2.817) (xy -0.388 -2.871) (xy -0.387 -2.876) (xy -0.375 -2.94) (xy -0.364 -2.995)
				(xy -0.356 -3.042) (xy -0.348 -3.081) (xy -0.342 -3.112) (xy -0.337 -3.137) (xy -0.332 -3.157) (xy -0.328 -3.171)
				(xy -0.325 -3.181) (xy -0.323 -3.188) (xy -0.32 -3.191) (xy -0.32 -3.192) (xy -0.317 -3.194) (xy -0.313 -3.195)
				(xy -0.307 -3.197) (xy -0.298 -3.198) (xy -0.286 -3.199) (xy -0.269 -3.199) (xy -0.247 -3.2) (xy -0.219 -3.2)
				(xy -0.184 -3.201) (xy -0.142 -3.201) (xy -0.092 -3.201) (xy -0.033 -3.201) (xy -0.001 -3.201) (xy 0.063 -3.201)
			)
			(stroke
				(width 0.01)
				(type solid)
			)
			(fill yes)
			(layer "F.Mask")
		)
	)
	(footprint "antmicro-footprints:C_0402_1005Metric"
		(layer "F.Cu")
		(at 134.175 85.2 90)
		(descr "Capacitor SMD 0402")
		(tags "capacitor SMD 0402")
		(property "Reference" "C34"
			(at -1.08 1.285 90)
			(layer "F.SilkS")
			(effects
				(font
					(size 0.7 0.7)
					(thickness 0.15)
				)
				(justify left bottom)
			)
		)
		(property "Value" "C_4u7_0402"
			(at 0 1.4 90)
			(layer "F.Fab")
			(hide yes)
			(effects
				(font
					(size 0.7 0.7)
					(thickness 0.15)
				)
				(justify left bottom)
			)
		)
		(property "Description" " "
			(at 0 0 90)
			(layer "F.Fab")
			(hide yes)
			(effects
				(font
					(size 1.27 1.27)
					(thickness 0.15)
				)
			)
		)
		(property "Author" "Antmicro"
			(at 219.375 -48.975 0)
			(layer "F.Fab")
			(hide yes)
			(effects
				(font
					(size 1 1)
					(thickness 0.15)
				)
			)
		)
		(property "Dielectric" ""
			(at 219.375 -48.975 0)
			(layer "F.Fab")
			(hide yes)
			(effects
				(font
					(size 1 1)
					(thickness 0.15)
				)
			)
		)
		(property "License" "Apache-2.0"
			(at 219.375 -48.975 0)
			(layer "F.Fab")
			(hide yes)
			(effects
				(font
					(size 1 1)
					(thickness 0.15)
				)
			)
		)
		(property "MPN" "GRM155R61A475MEAAD"
			(at 219.375 -48.975 0)
			(layer "F.Fab")
			(hide yes)
			(effects
				(font
					(size 1 1)
					(thickness 0.15)
				)
			)
		)
		(property "Manufacturer" "Murata"
			(at 219.375 -48.975 0)
			(layer "F.Fab")
			(hide yes)
			(effects
				(font
					(size 1 1)
					(thickness 0.15)
				)
			)
		)
		(property "Val" "4u7"
			(at 219.375 -48.975 0)
			(layer "F.Fab")
			(hide yes)
			(effects
				(font
					(size 1 1)
					(thickness 0.15)
				)
			)
		)
		(property "Voltage" ""
			(at 219.375 -48.975 0)
			(layer "F.Fab")
			(hide yes)
			(effects
				(font
					(size 1 1)
					(thickness 0.15)
				)
			)
		)
		(sheetname "EEPROM")
		(sheetfile "EEPROM.kicad_sch")
		(attr smd)
		(fp_rect
			(start -0.925 -0.47)
			(end 0.925 0.47)
			(stroke
				(width 0.05)
				(type default)
			)
			(fill no)
			(layer "F.CrtYd")
		)
		(fp_line
			(start 0.504 -0.25)
			(end 0.504 0.248)
			(stroke
				(width 0.15)
				(type solid)
			)
			(layer "F.Fab")
		)
		(fp_line
			(start -0.494 -0.25)
			(end 0.504 -0.25)
			(stroke
				(width 0.15)
				(type solid)
			)
			(layer "F.Fab")
		)
		(fp_line
			(start 0.504 0.248)
			(end -0.494 0.248)
			(stroke
				(width 0.15)
				(type solid)
			)
			(layer "F.Fab")
		)
		(fp_line
			(start -0.494 0.248)
			(end -0.494 -0.25)
			(stroke
				(width 0.15)
				(type solid)
			)
			(layer "F.Fab")
		)
		(pad "1" smd roundrect
			(at -0.48 0 90)
			(size 0.59 0.64)
			(layers "F.Cu" "F.Mask" "F.Paste")
			(roundrect_rratio 0.25)
			(net 50 "1V8_SYS")
			(pintype "passive")
		)
		(pad "2" smd roundrect
			(at 0.48 0 90)
			(size 0.59 0.64)
			(layers "F.Cu" "F.Mask" "F.Paste")
			(roundrect_rratio 0.25)
			(net 1 "GND")
			(pintype "passive")
		)
	)
	(footprint "antmicro-footprints:C_0402_1005Metric"
		(layer "F.Cu")
		(at 130.66 81.15)
		(descr "Capacitor SMD 0402")
		(tags "capacitor SMD 0402")
		(property "Reference" "C37"
			(at -1.05 -0.57 0)
			(layer "F.SilkS")
			(effects
				(font
					(size 0.7 0.7)
					(thickness 0.15)
				)
				(justify left bottom)
			)
		)
		(property "Value" "C_4u7_0402"
			(at 0 1.4 0)
			(layer "F.Fab")
			(hide yes)
			(effects
				(font
					(size 0.7 0.7)
					(thickness 0.15)
				)
				(justify left bottom)
			)
		)
		(property "Description" " "
			(at 0 0 0)
			(layer "F.Fab")
			(hide yes)
			(effects
				(font
					(size 1.27 1.27)
					(thickness 0.15)
				)
			)
		)
		(property "Author" "Antmicro"
			(at 0 0 0)
			(layer "F.Fab")
			(hide yes)
			(effects
				(font
					(size 1 1)
					(thickness 0.15)
				)
			)
		)
		(property "Dielectric" ""
			(at 0 0 0)
			(layer "F.Fab")
			(hide yes)
			(effects
				(font
					(size 1 1)
					(thickness 0.15)
				)
			)
		)
		(property "License" "Apache-2.0"
			(at 0 0 0)
			(layer "F.Fab")
			(hide yes)
			(effects
				(font
					(size 1 1)
					(thickness 0.15)
				)
			)
		)
		(property "MPN" "GRM155R61A475MEAAD"
			(at 0 0 0)
			(layer "F.Fab")
			(hide yes)
			(effects
				(font
					(size 1 1)
					(thickness 0.15)
				)
			)
		)
		(property "Manufacturer" "Murata"
			(at 0 0 0)
			(layer "F.Fab")
			(hide yes)
			(effects
				(font
					(size 1 1)
					(thickness 0.15)
				)
			)
		)
		(property "Val" "4u7"
			(at 0 0 0)
			(layer "F.Fab")
			(hide yes)
			(effects
				(font
					(size 1 1)
					(thickness 0.15)
				)
			)
		)
		(property "Voltage" ""
			(at 0 0 0)
			(layer "F.Fab")
			(hide yes)
			(effects
				(font
					(size 1 1)
					(thickness 0.15)
				)
			)
		)
		(sheetname "EEPROM")
		(sheetfile "EEPROM.kicad_sch")
		(attr smd)
		(fp_rect
			(start -0.925 -0.47)
			(end 0.925 0.47)
			(stroke
				(width 0.05)
				(type default)
			)
			(fill no)
			(layer "F.CrtYd")
		)
		(fp_line
			(start -0.494 -0.25)
			(end 0.504 -0.25)
			(stroke
				(width 0.15)
				(type solid)
			)
			(layer "F.Fab")
		)
		(fp_line
			(start -0.494 0.248)
			(end -0.494 -0.25)
			(stroke
				(width 0.15)
				(type solid)
			)
			(layer "F.Fab")
		)
		(fp_line
			(start 0.504 -0.25)
			(end 0.504 0.248)
			(stroke
				(width 0.15)
				(type solid)
			)
			(layer "F.Fab")
		)
		(fp_line
			(start 0.504 0.248)
			(end -0.494 0.248)
			(stroke
				(width 0.15)
				(type solid)
			)
			(layer "F.Fab")
		)
		(pad "1" smd roundrect
			(at -0.48 0)
			(size 0.59 0.64)
			(layers "F.Cu" "F.Mask" "F.Paste")
			(roundrect_rratio 0.25)
			(net 52 "/EEPROM/VDD_LED")
			(pintype "passive")
		)
		(pad "2" smd roundrect
			(at 0.48 0)
			(size 0.59 0.64)
			(layers "F.Cu" "F.Mask" "F.Paste")
			(roundrect_rratio 0.25)
			(net 1 "GND")
			(pintype "passive")
		)
	)
	(footprint "antmicro-footprints:C_0402_1005Metric"
		(layer "F.Cu")
		(at 122.76 81.545)
		(descr "Capacitor SMD 0402")
		(tags "capacitor SMD 0402")
		(property "Reference" "C38"
			(at 0.92 0.345 0)
			(layer "F.SilkS")
			(effects
				(font
					(size 0.7 0.7)
					(thickness 0.15)
				)
				(justify left bottom)
			)
		)
		(property "Value" "C_100n_0402"
			(at 0 1.4 0)
			(layer "F.Fab")
			(hide yes)
			(effects
				(font
					(size 0.7 0.7)
					(thickness 0.15)
				)
				(justify left bottom)
			)
		)
		(property "Description" " "
			(at 0 0 0)
			(layer "F.Fab")
			(hide yes)
			(effects
				(font
					(size 1.27 1.27)
					(thickness 0.15)
				)
			)
		)
		(property "Author" "Antmicro"
			(at 0 0 0)
			(layer "F.Fab")
			(hide yes)
			(effects
				(font
					(size 1 1)
					(thickness 0.15)
				)
			)
		)
		(property "Dielectric" "X5R"
			(at 0 0 0)
			(layer "F.Fab")
			(hide yes)
			(effects
				(font
					(size 1 1)
					(thickness 0.15)
				)
			)
		)
		(property "License" "Apache-2.0"
			(at 0 0 0)
			(layer "F.Fab")
			(hide yes)
			(effects
				(font
					(size 1 1)
					(thickness 0.15)
				)
			)
		)
		(property "MPN" "GRM155R61H104KE14D"
			(at 0 0 0)
			(layer "F.Fab")
			(hide yes)
			(effects
				(font
					(size 1 1)
					(thickness 0.15)
				)
			)
		)
		(property "Manufacturer" "Murata"
			(at 0 0 0)
			(layer "F.Fab")
			(hide yes)
			(effects
				(font
					(size 1 1)
					(thickness 0.15)
				)
			)
		)
		(property "Val" "100n"
			(at 0 0 0)
			(layer "F.Fab")
			(hide yes)
			(effects
				(font
					(size 1 1)
					(thickness 0.15)
				)
			)
		)
		(property "Voltage" "50V"
			(at 0 0 0)
			(layer "F.Fab")
			(hide yes)
			(effects
				(font
					(size 1 1)
					(thickness 0.15)
				)
			)
		)
		(sheetname "EEPROM")
		(sheetfile "EEPROM.kicad_sch")
		(attr smd)
		(fp_rect
			(start -0.925 -0.47)
			(end 0.925 0.47)
			(stroke
				(width 0.05)
				(type default)
			)
			(fill no)
			(layer "F.CrtYd")
		)
		(fp_line
			(start -0.494 -0.25)
			(end 0.504 -0.25)
			(stroke
				(width 0.15)
				(type solid)
			)
			(layer "F.Fab")
		)
		(fp_line
			(start -0.494 0.248)
			(end -0.494 -0.25)
			(stroke
				(width 0.15)
				(type solid)
			)
			(layer "F.Fab")
		)
		(fp_line
			(start 0.504 -0.25)
			(end 0.504 0.248)
			(stroke
				(width 0.15)
				(type solid)
			)
			(layer "F.Fab")
		)
		(fp_line
			(start 0.504 0.248)
			(end -0.494 0.248)
			(stroke
				(width 0.15)
				(type solid)
			)
			(layer "F.Fab")
		)
		(pad "1" smd roundrect
			(at -0.48 0)
			(size 0.59 0.64)
			(layers "F.Cu" "F.Mask" "F.Paste")
			(roundrect_rratio 0.25)
			(net 50 "1V8_SYS")
			(pintype "passive")
		)
		(pad "2" smd roundrect
			(at 0.48 0)
			(size 0.59 0.64)
			(layers "F.Cu" "F.Mask" "F.Paste")
			(roundrect_rratio 0.25)
			(net 1 "GND")
			(pintype "passive")
		)
	)
	(footprint "antmicro-footprints:LED_0603_1608Metric_G"
		(layer "F.Cu")
		(at 131.075 72.9 90)
		(descr "LED SMD 0603 Green")
		(tags "LED SMD 0603 Green")
		(property "Reference" "D4"
			(at 1.53 -0.775 180)
			(layer "F.SilkS")
			(effects
				(font
					(size 0.7 0.7)
					(thickness 0.15)
				)
				(justify left bottom)
			)
		)
		(property "Value" "LED_G_0603_KP-1608CGCK"
			(at 0 1.6 90)
			(layer "F.Fab")
			(hide yes)
			(effects
				(font
					(size 0.7 0.7)
					(thickness 0.15)
				)
				(justify left bottom)
			)
		)
		(property "Author" "Antmicro"
			(at 203.975 -58.175 0)
			(layer "F.Fab")
			(hide yes)
			(effects
				(font
					(size 1 1)
					(thickness 0.15)
				)
			)
		)
		(property "License" "Apache-2.0"
			(at 203.975 -58.175 0)
			(layer "F.Fab")
			(hide yes)
			(effects
				(font
					(size 1 1)
					(thickness 0.15)
				)
			)
		)
		(property "MPN" "KP-1608CGCK"
			(at 203.975 -58.175 0)
			(layer "F.Fab")
			(hide yes)
			(effects
				(font
					(size 1 1)
					(thickness 0.15)
				)
			)
		)
		(property "Manufacturer" "Kingbright"
			(at 203.975 -58.175 0)
			(layer "F.Fab")
			(hide yes)
			(effects
				(font
					(size 1 1)
					(thickness 0.15)
				)
			)
		)
		(sheetname "EEPROM")
		(sheetfile "EEPROM.kicad_sch")
		(attr smd)
		(fp_line
			(start 0.22 -0.35)
			(end -0.22 -0.35)
			(stroke
				(width 0.15)
				(type solid)
			)
			(layer "F.SilkS")
		)
		(fp_line
			(start -1.18 -0.319)
			(end -1.18 0.321)
			(stroke
				(width 0.15)
				(type solid)
			)
			(layer "F.SilkS")
		)
		(fp_line
			(start 0.105328 0.001008)
			(end 0.24 0.001)
			(stroke
				(width 0.1)
				(type solid)
			)
			(layer "F.SilkS")
		)
		(fp_line
			(start -0.094672 0.001008)
			(end 0.105328 -0.198992)
			(stroke
				(width 0.1)
				(type solid)
			)
			(layer "F.SilkS")
		)
		(fp_line
			(start -0.094672 0.001008)
			(end -0.24 0.001008)
			(stroke
				(width 0.1)
				(type solid)
			)
			(layer "F.SilkS")
		)
		(fp_line
			(start 0.105328 0.201008)
			(end 0.105328 -0.198992)
			(stroke
				(width 0.1)
				(type solid)
			)
			(layer "F.SilkS")
		)
		(fp_line
			(start 0.105328 0.201008)
			(end -0.094672 0.001008)
			(stroke
				(width 0.1)
				(type solid)
			)
			(layer "F.SilkS")
		)
		(fp_line
			(start -0.094672 0.201008)
			(end -0.094672 -0.198992)
			(stroke
				(width 0.1)
				(type solid)
			)
			(layer "F.SilkS")
		)
		(fp_line
			(start 0.22 0.35)
			(end -0.22 0.35)
			(stroke
				(width 0.15)
				(type solid)
			)
			(layer "F.SilkS")
		)
		(fp_rect
			(start 1.25 0.65)
			(end -1.25 -0.65)
			(stroke
				(width 0.05)
				(type solid)
			)
			(fill no)
			(layer "F.CrtYd")
		)
		(fp_line
			(start 0.201 -0.202)
			(end -0.101 0)
			(stroke
				(width 0.15)
				(type solid)
			)
			(layer "F.Fab")
		)
		(fp_line
			(start -0.199 -0.202)
			(end -0.199 0.1)
			(stroke
				(width 0.15)
				(type solid)
			)
			(layer "F.Fab")
		)
		(fp_line
			(start 0.599 0)
			(end 0.201 0)
			(stroke
				(width 0.15)
				(type solid)
			)
			(layer "F.Fab")
		)
		(fp_line
			(start 0.201 0)
			(end 0.201 -0.202)
			(stroke
				(width 0.15)
				(type solid)
			)
			(layer "F.Fab")
		)
		(fp_line
			(start -0.101 0)
			(end 0.201 0.2)
			(stroke
				(width 0.15)
				(type solid)
			)
			(layer "F.Fab")
		)
		(fp_line
			(start -0.199 0)
			(end -0.597 0)
			(stroke
				(width 0.15)
				(type solid)
			)
			(layer "F.Fab")
		)
		(fp_line
			(start 0.201 0.2)
			(end 0.201 0)
			(stroke
				(width 0.15)
				(type solid)
			)
			(layer "F.Fab")
		)
		(fp_line
			(start -0.199 0.2)
			(end -0.199 0.1)
			(stroke
				(width 0.15)
				(type solid)
			)
			(layer "F.Fab")
		)
		(fp_rect
			(start 0.848 0.4)
			(end -0.85 -0.402)
			(stroke
				(width 0.15)
				(type solid)
			)
			(fill no)
			(layer "F.Fab")
		)
		(pad "1" smd roundrect
			(at -0.7 0 270)
			(size 0.8 1)
			(layers "F.Cu" "F.Mask" "F.Paste")
			(roundrect_rratio 0.2)
			(net 7 "Net-(D4-Pad1)")
			(pinfunction "1")
			(pintype "passive")
		)
		(pad "2" smd roundrect
			(at 0.7 0 270)
			(size 0.8 1)
			(layers "F.Cu" "F.Mask" "F.Paste")
			(roundrect_rratio 0.2)
			(net 1 "GND")
			(pinfunction "2")
			(pintype "passive")
		)
	)
	(footprint "antmicro-footprints:LED_0603_1608Metric_G"
		(layer "F.Cu")
		(at 129.258332 72.9 90)
		(descr "LED SMD 0603 Green")
		(tags "LED SMD 0603 Green")
		(property "Reference" "D3"
			(at 1.53 -0.688332 180)
			(layer "F.SilkS")
			(effects
				(font
					(size 0.7 0.7)
					(thickness 0.15)
				)
				(justify left bottom)
			)
		)
		(property "Value" "LED_G_0603_KP-1608CGCK"
			(at 0 1.6 90)
			(layer "F.Fab")
			(hide yes)
			(effects
				(font
					(size 0.7 0.7)
					(thickness 0.15)
				)
				(justify left bottom)
			)
		)
		(property "Author" "Antmicro"
			(at 202.158332 -56.358332 0)
			(layer "F.Fab")
			(hide yes)
			(effects
				(font
					(size 1 1)
					(thickness 0.15)
				)
			)
		)
		(property "License" "Apache-2.0"
			(at 202.158332 -56.358332 0)
			(layer "F.Fab")
			(hide yes)
			(effects
				(font
					(size 1 1)
					(thickness 0.15)
				)
			)
		)
		(property "MPN" "KP-1608CGCK"
			(at 202.158332 -56.358332 0)
			(layer "F.Fab")
			(hide yes)
			(effects
				(font
					(size 1 1)
					(thickness 0.15)
				)
			)
		)
		(property "Manufacturer" "Kingbright"
			(at 202.158332 -56.358332 0)
			(layer "F.Fab")
			(hide yes)
			(effects
				(font
					(size 1 1)
					(thickness 0.15)
				)
			)
		)
		(sheetname "EEPROM")
		(sheetfile "EEPROM.kicad_sch")
		(attr smd)
		(fp_line
			(start 0.22 -0.35)
			(end -0.22 -0.35)
			(stroke
				(width 0.15)
				(type solid)
			)
			(layer "F.SilkS")
		)
		(fp_line
			(start -1.18 -0.319)
			(end -1.18 0.321)
			(stroke
				(width 0.15)
				(type solid)
			)
			(layer "F.SilkS")
		)
		(fp_line
			(start 0.105328 0.001008)
			(end 0.24 0.001)
			(stroke
				(width 0.1)
				(type solid)
			)
			(layer "F.SilkS")
		)
		(fp_line
			(start -0.094672 0.001008)
			(end 0.105328 -0.198992)
			(stroke
				(width 0.1)
				(type solid)
			)
			(layer "F.SilkS")
		)
		(fp_line
			(start -0.094672 0.001008)
			(end -0.24 0.001008)
			(stroke
				(width 0.1)
				(type solid)
			)
			(layer "F.SilkS")
		)
		(fp_line
			(start 0.105328 0.201008)
			(end 0.105328 -0.198992)
			(stroke
				(width 0.1)
				(type solid)
			)
			(layer "F.SilkS")
		)
		(fp_line
			(start 0.105328 0.201008)
			(end -0.094672 0.001008)
			(stroke
				(width 0.1)
				(type solid)
			)
			(layer "F.SilkS")
		)
		(fp_line
			(start -0.094672 0.201008)
			(end -0.094672 -0.198992)
			(stroke
				(width 0.1)
				(type solid)
			)
			(layer "F.SilkS")
		)
		(fp_line
			(start 0.22 0.35)
			(end -0.22 0.35)
			(stroke
				(width 0.15)
				(type solid)
			)
			(layer "F.SilkS")
		)
		(fp_rect
			(start 1.25 0.65)
			(end -1.25 -0.65)
			(stroke
				(width 0.05)
				(type solid)
			)
			(fill no)
			(layer "F.CrtYd")
		)
		(fp_line
			(start 0.201 -0.202)
			(end -0.101 0)
			(stroke
				(width 0.15)
				(type solid)
			)
			(layer "F.Fab")
		)
		(fp_line
			(start -0.199 -0.202)
			(end -0.199 0.1)
			(stroke
				(width 0.15)
				(type solid)
			)
			(layer "F.Fab")
		)
		(fp_line
			(start 0.599 0)
			(end 0.201 0)
			(stroke
				(width 0.15)
				(type solid)
			)
			(layer "F.Fab")
		)
		(fp_line
			(start 0.201 0)
			(end 0.201 -0.202)
			(stroke
				(width 0.15)
				(type solid)
			)
			(layer "F.Fab")
		)
		(fp_line
			(start -0.101 0)
			(end 0.201 0.2)
			(stroke
				(width 0.15)
				(type solid)
			)
			(layer "F.Fab")
		)
		(fp_line
			(start -0.199 0)
			(end -0.597 0)
			(stroke
				(width 0.15)
				(type solid)
			)
			(layer "F.Fab")
		)
		(fp_line
			(start 0.201 0.2)
			(end 0.201 0)
			(stroke
				(width 0.15)
				(type solid)
			)
			(layer "F.Fab")
		)
		(fp_line
			(start -0.199 0.2)
			(end -0.199 0.1)
			(stroke
				(width 0.15)
				(type solid)
			)
			(layer "F.Fab")
		)
		(fp_rect
			(start 0.848 0.4)
			(end -0.85 -0.402)
			(stroke
				(width 0.15)
				(type solid)
			)
			(fill no)
			(layer "F.Fab")
		)
		(pad "1" smd roundrect
			(at -0.7 0 270)
			(size 0.8 1)
			(layers "F.Cu" "F.Mask" "F.Paste")
			(roundrect_rratio 0.2)
			(net 6 "Net-(D3-Pad1)")
			(pinfunction "1")
			(pintype "passive")
		)
		(pad "2" smd roundrect
			(at 0.7 0 270)
			(size 0.8 1)
			(layers "F.Cu" "F.Mask" "F.Paste")
			(roundrect_rratio 0.2)
			(net 1 "GND")
			(pinfunction "2")
			(pintype "passive")
		)
	)
	(footprint "antmicro-footprints:LED_0603_1608Metric_G"
		(layer "F.Cu")
		(at 125.625 72.9 90)
		(descr "LED SMD 0603 Green")
		(tags "LED SMD 0603 Green")
		(property "Reference" "D1"
			(at 1.56 -0.715 180)
			(layer "F.SilkS")
			(effects
				(font
					(size 0.7 0.7)
					(thickness 0.15)
				)
				(justify left bottom)
			)
		)
		(property "Value" "LED_G_0603_KP-1608CGCK"
			(at 0 1.6 90)
			(layer "F.Fab")
			(hide yes)
			(effects
				(font
					(size 0.7 0.7)
					(thickness 0.15)
				)
				(justify left bottom)
			)
		)
		(property "Author" "Antmicro"
			(at 198.525 -52.725 0)
			(layer "F.Fab")
			(hide yes)
			(effects
				(font
					(size 1 1)
					(thickness 0.15)
				)
			)
		)
		(property "License" "Apache-2.0"
			(at 198.525 -52.725 0)
			(layer "F.Fab")
			(hide yes)
			(effects
				(font
					(size 1 1)
					(thickness 0.15)
				)
			)
		)
		(property "MPN" "KP-1608CGCK"
			(at 198.525 -52.725 0)
			(layer "F.Fab")
			(hide yes)
			(effects
				(font
					(size 1 1)
					(thickness 0.15)
				)
			)
		)
		(property "Manufacturer" "Kingbright"
			(at 198.525 -52.725 0)
			(layer "F.Fab")
			(hide yes)
			(effects
				(font
					(size 1 1)
					(thickness 0.15)
				)
			)
		)
		(sheetname "EEPROM")
		(sheetfile "EEPROM.kicad_sch")
		(attr smd)
		(fp_line
			(start 0.22 -0.35)
			(end -0.22 -0.35)
			(stroke
				(width 0.15)
				(type solid)
			)
			(layer "F.SilkS")
		)
		(fp_line
			(start -1.18 -0.319)
			(end -1.18 0.321)
			(stroke
				(width 0.15)
				(type solid)
			)
			(layer "F.SilkS")
		)
		(fp_line
			(start 0.105328 0.001008)
			(end 0.24 0.001)
			(stroke
				(width 0.1)
				(type solid)
			)
			(layer "F.SilkS")
		)
		(fp_line
			(start -0.094672 0.001008)
			(end 0.105328 -0.198992)
			(stroke
				(width 0.1)
				(type solid)
			)
			(layer "F.SilkS")
		)
		(fp_line
			(start -0.094672 0.001008)
			(end -0.24 0.001008)
			(stroke
				(width 0.1)
				(type solid)
			)
			(layer "F.SilkS")
		)
		(fp_line
			(start 0.105328 0.201008)
			(end 0.105328 -0.198992)
			(stroke
				(width 0.1)
				(type solid)
			)
			(layer "F.SilkS")
		)
		(fp_line
			(start 0.105328 0.201008)
			(end -0.094672 0.001008)
			(stroke
				(width 0.1)
				(type solid)
			)
			(layer "F.SilkS")
		)
		(fp_line
			(start -0.094672 0.201008)
			(end -0.094672 -0.198992)
			(stroke
				(width 0.1)
				(type solid)
			)
			(layer "F.SilkS")
		)
		(fp_line
			(start 0.22 0.35)
			(end -0.22 0.35)
			(stroke
				(width 0.15)
				(type solid)
			)
			(layer "F.SilkS")
		)
		(fp_rect
			(start 1.25 0.65)
			(end -1.25 -0.65)
			(stroke
				(width 0.05)
				(type solid)
			)
			(fill no)
			(layer "F.CrtYd")
		)
		(fp_line
			(start 0.201 -0.202)
			(end -0.101 0)
			(stroke
				(width 0.15)
				(type solid)
			)
			(layer "F.Fab")
		)
		(fp_line
			(start -0.199 -0.202)
			(end -0.199 0.1)
			(stroke
				(width 0.15)
				(type solid)
			)
			(layer "F.Fab")
		)
		(fp_line
			(start 0.599 0)
			(end 0.201 0)
			(stroke
				(width 0.15)
				(type solid)
			)
			(layer "F.Fab")
		)
		(fp_line
			(start 0.201 0)
			(end 0.201 -0.202)
			(stroke
				(width 0.15)
				(type solid)
			)
			(layer "F.Fab")
		)
		(fp_line
			(start -0.101 0)
			(end 0.201 0.2)
			(stroke
				(width 0.15)
				(type solid)
			)
			(layer "F.Fab")
		)
		(fp_line
			(start -0.199 0)
			(end -0.597 0)
			(stroke
				(width 0.15)
				(type solid)
			)
			(layer "F.Fab")
		)
		(fp_line
			(start 0.201 0.2)
			(end 0.201 0)
			(stroke
				(width 0.15)
				(type solid)
			)
			(layer "F.Fab")
		)
		(fp_line
			(start -0.199 0.2)
			(end -0.199 0.1)
			(stroke
				(width 0.15)
				(type solid)
			)
			(layer "F.Fab")
		)
		(fp_rect
			(start 0.848 0.4)
			(end -0.85 -0.402)
			(stroke
				(width 0.15)
				(type solid)
			)
			(fill no)
			(layer "F.Fab")
		)
		(pad "1" smd roundrect
			(at -0.7 0 270)
			(size 0.8 1)
			(layers "F.Cu" "F.Mask" "F.Paste")
			(roundrect_rratio 0.2)
			(net 4 "Net-(D1-Pad1)")
			(pinfunction "1")
			(pintype "passive")
		)
		(pad "2" smd roundrect
			(at 0.7 0 270)
			(size 0.8 1)
			(layers "F.Cu" "F.Mask" "F.Paste")
			(roundrect_rratio 0.2)
			(net 1 "GND")
			(pinfunction "2")
			(pintype "passive")
		)
	)
	(footprint "antmicro-footprints:SOT-23-5"
		(layer "F.Cu")
		(at 129.375 91.15)
		(property "Reference" "IC2"
			(at -1.035 2.69 0)
			(layer "F.SilkS")
			(effects
				(font
					(size 0.7 0.7)
					(thickness 0.15)
				)
				(justify left bottom)
			)
		)
		(property "Value" "AT24CS01_SOT23"
			(at 0.002 2.799 0)
			(layer "F.Fab")
			(hide yes)
			(effects
				(font
					(size 0.7 0.7)
					(thickness 0.15)
				)
				(justify left bottom)
			)
		)
		(property "Description" "SOT-23-5"
			(at 0 0 0)
			(layer "F.Fab")
			(hide yes)
			(effects
				(font
					(size 1.27 1.27)
					(thickness 0.15)
				)
			)
		)
		(property "Author" "Antmicro"
			(at 0 0 0)
			(layer "F.Fab")
			(hide yes)
			(effects
				(font
					(size 1 1)
					(thickness 0.15)
				)
			)
		)
		(property "License" "Apache-2.0"
			(at 0 0 0)
			(layer "F.Fab")
			(hide yes)
			(effects
				(font
					(size 1 1)
					(thickness 0.15)
				)
			)
		)
		(property "MPN" "AT24CS01-ST"
			(at 0 0 0)
			(layer "F.Fab")
			(hide yes)
			(effects
				(font
					(size 1 1)
					(thickness 0.15)
				)
			)
		)
		(property "Manufacturer" "Atmel"
			(at 0 0 0)
			(layer "F.Fab")
			(hide yes)
			(effects
				(font
					(size 1 1)
					(thickness 0.15)
				)
			)
		)
		(sheetname "EEPROM")
		(sheetfile "EEPROM.kicad_sch")
		(attr smd)
		(fp_line
			(start -0.85 1.6)
			(end -0.85 1.301)
			(stroke
				(width 0.15)
				(type solid)
			)
			(layer "F.SilkS")
		)
		(fp_line
			(start -0.8 -1.6)
			(end -0.8 -1.3)
			(stroke
				(width 0.15)
				(type solid)
			)
			(layer "F.SilkS")
		)
		(fp_line
			(start -0.8 -1.6)
			(end -0.5 -1.6)
			(stroke
				(width 0.15)
				(type solid)
			)
			(layer "F.SilkS")
		)
		(fp_line
			(start -0.55 1.6)
			(end -0.85 1.6)
			(stroke
				(width 0.15)
				(type solid)
			)
			(layer "F.SilkS")
		)
		(fp_line
			(start 0.8 -1.6)
			(end 0.5 -1.6)
			(stroke
				(width 0.15)
				(type solid)
			)
			(layer "F.SilkS")
		)
		(fp_line
			(start 0.8 -1.3)
			(end 0.8 -1.6)
			(stroke
				(width 0.15)
				(type solid)
			)
			(layer "F.SilkS")
		)
		(fp_line
			(start 0.8 0.55)
			(end 0.8 -0.55)
			(stroke
				(width 0.15)
				(type solid)
			)
			(layer "F.SilkS")
		)
		(fp_line
			(start 0.8 1.3)
			(end 0.8 1.599)
			(stroke
				(width 0.15)
				(type solid)
			)
			(layer "F.SilkS")
		)
		(fp_line
			(start 0.8 1.599)
			(end 0.549 1.599)
			(stroke
				(width 0.15)
				(type solid)
			)
			(layer "F.SilkS")
		)
		(fp_circle
			(center -1.25 -1.5)
			(end -1.2 -1.5)
			(stroke
				(width 0.15)
				(type solid)
			)
			(fill yes)
			(layer "F.SilkS")
		)
		(fp_rect
			(start 1.9 -1.76)
			(end -1.9 1.75)
			(stroke
				(width 0.05)
				(type solid)
			)
			(fill no)
			(layer "F.CrtYd")
		)
		(fp_line
			(start -0.398 -1.526)
			(end -0.874 -1.05)
			(stroke
				(width 0.15)
				(type solid)
			)
			(layer "F.Fab")
		)
		(fp_rect
			(start 0.874 1.523)
			(end -0.873 -1.525)
			(stroke
				(width 0.15)
				(type solid)
			)
			(fill no)
			(layer "F.Fab")
		)
		(pad "1" smd rect
			(at -1.351 -0.951 270)
			(size 0.55 1)
			(layers "F.Cu" "F.Mask" "F.Paste")
			(net 13 "SCL")
			(pinfunction "SCL")
			(pintype "passive")
		)
		(pad "2" smd rect
			(at -1.351 0 270)
			(size 0.55 1)
			(layers "F.Cu" "F.Mask" "F.Paste")
			(net 1 "GND")
			(pinfunction "GND")
			(pintype "passive")
		)
		(pad "3" smd rect
			(at -1.351 0.949 270)
			(size 0.55 1)
			(layers "F.Cu" "F.Mask" "F.Paste")
			(net 12 "SDA")
			(pinfunction "SDA")
			(pintype "passive")
		)
		(pad "4" smd rect
			(at 1.35 0.949 270)
			(size 0.55 1)
			(layers "F.Cu" "F.Mask" "F.Paste")
			(net 50 "1V8_SYS")
			(pinfunction "VCC")
			(pintype "passive")
		)
		(pad "5" smd rect
			(at 1.35 -0.951 270)
			(size 0.55 1)
			(layers "F.Cu" "F.Mask" "F.Paste")
			(net 1 "GND")
			(pinfunction "WP")
			(pintype "passive")
		)
	)
	(footprint "antmicro-footprints:L_0806_2016Metric"
		(layer "F.Cu")
		(at 131.725 86.45 180)
		(property "Reference" "L1"
			(at -1.695 -1.26 180)
			(layer "F.SilkS")
			(effects
				(font
					(size 0.7 0.7)
					(thickness 0.15)
				)
				(justify left bottom)
			)
		)
		(property "Value" "L_2.2u_1.5A_0806"
			(at 0 2 180)
			(layer "F.Fab")
			(hide yes)
			(effects
				(font
					(size 0.7 0.7)
					(thickness 0.15)
				)
				(justify left bottom)
			)
		)
		(property "Author" "Antmicro"
			(at 263.45 172.9 0)
			(layer "F.Fab")
			(hide yes)
			(effects
				(font
					(size 1 1)
					(thickness 0.15)
				)
			)
		)
		(property "IMax" ""
			(at 263.45 172.9 0)
			(layer "F.Fab")
			(hide yes)
			(effects
				(font
					(size 1 1)
					(thickness 0.15)
				)
			)
		)
		(property "ISat" ""
			(at 263.45 172.9 0)
			(layer "F.Fab")
			(hide yes)
			(effects
				(font
					(size 1 1)
					(thickness 0.15)
				)
			)
		)
		(property "License" "Apache-2.0"
			(at 263.45 172.9 0)
			(layer "F.Fab")
			(hide yes)
			(effects
				(font
					(size 1 1)
					(thickness 0.15)
				)
			)
		)
		(property "MPN" "1285AS-H-2R2M=P2"
			(at 263.45 172.9 0)
			(layer "F.Fab")
			(hide yes)
			(effects
				(font
					(size 1 1)
					(thickness 0.15)
				)
			)
		)
		(property "Manufacturer" "Murata"
			(at 263.45 172.9 0)
			(layer "F.Fab")
			(hide yes)
			(effects
				(font
					(size 1 1)
					(thickness 0.15)
				)
			)
		)
		(property "Size" "2.0x1.6"
			(at 263.45 172.9 0)
			(layer "F.Fab")
			(hide yes)
			(effects
				(font
					(size 1 1)
					(thickness 0.15)
				)
			)
		)
		(property "Val" "2.2uH/1.5A"
			(at 263.45 172.9 0)
			(layer "F.Fab")
			(hide yes)
			(effects
				(font
					(size 1 1)
					(thickness 0.15)
				)
			)
		)
		(sheetname "EEPROM")
		(sheetfile "EEPROM.kicad_sch")
		(attr smd)
		(fp_line
			(start -0.3 -0.9)
			(end 0.298 -0.9)
			(stroke
				(width 0.15)
				(type solid)
			)
			(layer "F.SilkS")
		)
		(fp_line
			(start -0.301 0.9)
			(end 0.299 0.9)
			(stroke
				(width 0.15)
				(type solid)
			)
			(layer "F.SilkS")
		)
		(fp_rect
			(start -1.75 -1.05)
			(end 1.75 1.05)
			(stroke
				(width 0.05)
				(type solid)
			)
			(fill no)
			(layer "F.CrtYd")
		)
		(fp_rect
			(start -0.951 -0.882)
			(end 0.949 0.875)
			(stroke
				(width 0.15)
				(type solid)
			)
			(fill no)
			(layer "F.Fab")
		)
		(pad "1" smd roundrect
			(at -1.1 -0.001 180)
			(size 1 1.8)
			(layers "F.Cu" "F.Mask" "F.Paste")
			(roundrect_rratio 0.15)
			(net 50 "1V8_SYS")
			(pintype "passive")
		)
		(pad "2" smd roundrect
			(at 1.1 -0.001 180)
			(size 1 1.8)
			(layers "F.Cu" "F.Mask" "F.Paste")
			(roundrect_rratio 0.15)
			(net 69 "Net-(U2-SW)")
			(pintype "passive")
		)
	)
	(footprint "antmicro-footprints:R_0402_1005Metric"
		(layer "F.Cu")
		(at 128.53 81.145 180)
		(descr "Resistor SMD 0402")
		(tags "resistor SMD 0402")
		(property "Reference" "R8"
			(at 0.74 0.575 180)
			(layer "F.SilkS")
			(effects
				(font
					(size 0.7 0.7)
					(thickness 0.15)
				)
				(justify left bottom)
			)
		)
		(property "Value" "R_0R_0402"
			(at 0 1.4 180)
			(layer "F.Fab")
			(hide yes)
			(effects
				(font
					(size 0.7 0.7)
					(thickness 0.15)
				)
				(justify left bottom)
			)
		)
		(property "Description" "0R resistor in 0402 package with unspecified tolerance"
			(at 0 0 180)
			(layer "F.Fab")
			(hide yes)
			(effects
				(font
					(size 1.27 1.27)
					(thickness 0.15)
				)
			)
		)
		(property "Author" "Antmicro"
			(at 257.06 162.29 0)
			(layer "F.Fab")
			(hide yes)
			(effects
				(font
					(size 1 1)
					(thickness 0.15)
				)
			)
		)
		(property "Current" "1A"
			(at 257.06 162.29 0)
			(layer "F.Fab")
			(hide yes)
			(effects
				(font
					(size 1 1)
					(thickness 0.15)
				)
			)
		)
		(property "License" "Apache-2.0"
			(at 257.06 162.29 0)
			(layer "F.Fab")
			(hide yes)
			(effects
				(font
					(size 1 1)
					(thickness 0.15)
				)
			)
		)
		(property "MPN" "ERJ2GE0R00X"
			(at 257.06 162.29 0)
			(layer "F.Fab")
			(hide yes)
			(effects
				(font
					(size 1 1)
					(thickness 0.15)
				)
			)
		)
		(property "Manufacturer" "Panasonic"
			(at 257.06 162.29 0)
			(layer "F.Fab")
			(hide yes)
			(effects
				(font
					(size 1 1)
					(thickness 0.15)
				)
			)
		)
		(property "Tolerance" ""
			(at 257.06 162.29 0)
			(layer "F.Fab")
			(hide yes)
			(effects
				(font
					(size 1 1)
					(thickness 0.15)
				)
			)
		)
		(property "Val" "0R"
			(at 257.06 162.29 0)
			(layer "F.Fab")
			(hide yes)
			(effects
				(font
					(size 1 1)
					(thickness 0.15)
				)
			)
		)
		(sheetname "EEPROM")
		(sheetfile "EEPROM.kicad_sch")
		(attr smd exclude_from_pos_files exclude_from_bom dnp)
		(fp_rect
			(start -0.925 -0.47)
			(end 0.925 0.47)
			(stroke
				(width 0.05)
				(type default)
			)
			(fill no)
			(layer "F.CrtYd")
		)
		(fp_rect
			(start -0.5 -0.25)
			(end 0.5 0.25)
			(stroke
				(width 0.15)
				(type solid)
			)
			(fill no)
			(layer "F.Fab")
		)
		(pad "1" smd roundrect
			(at -0.48 0 180)
			(size 0.59 0.64)
			(layers "F.Cu" "F.Mask" "F.Paste")
			(roundrect_rratio 0.25)
			(net 50 "1V8_SYS")
			(pintype "passive")
		)
		(pad "2" smd roundrect
			(at 0.48 0 180)
			(size 0.59 0.64)
			(layers "F.Cu" "F.Mask" "F.Paste")
			(roundrect_rratio 0.25)
			(net 52 "/EEPROM/VDD_LED")
			(pintype "passive")
		)
	)
	(footprint "antmicro-footprints:R_0402_1005Metric"
		(layer "F.Cu")
		(at 131.075 75.95 90)
		(descr "Resistor SMD 0402")
		(tags "resistor SMD 0402")
		(property "Reference" "R12"
			(at -3.05 0.345 90)
			(layer "F.SilkS")
			(effects
				(font
					(size 0.7 0.7)
					(thickness 0.15)
				)
				(justify left bottom)
			)
		)
		(property "Value" "R_220R_0402"
			(at 0 1.4 90)
			(layer "F.Fab")
			(hide yes)
			(effects
				(font
					(size 0.7 0.7)
					(thickness 0.15)
				)
				(justify left bottom)
			)
		)
		(property "Description" "220R resistor in 0402 package with 1% tolerance"
			(at 0 0 90)
			(layer "F.Fab")
			(hide yes)
			(effects
				(font
					(size 1.27 1.27)
					(thickness 0.15)
				)
			)
		)
		(property "Author" "Antmicro"
			(at 207.025 -55.125 0)
			(layer "F.Fab")
			(hide yes)
			(effects
				(font
					(size 1 1)
					(thickness 0.15)
				)
			)
		)
		(property "License" "Apache-2.0"
			(at 207.025 -55.125 0)
			(layer "F.Fab")
			(hide yes)
			(effects
				(font
					(size 1 1)
					(thickness 0.15)
				)
			)
		)
		(property "MPN" "CR0402-FX-2200GLF"
			(at 207.025 -55.125 0)
			(layer "F.Fab")
			(hide yes)
			(effects
				(font
					(size 1 1)
					(thickness 0.15)
				)
			)
		)
		(property "Manufacturer" "Bourns"
			(at 207.025 -55.125 0)
			(layer "F.Fab")
			(hide yes)
			(effects
				(font
					(size 1 1)
					(thickness 0.15)
				)
			)
		)
		(property "Tolerance" "1%"
			(at 207.025 -55.125 0)
			(layer "F.Fab")
			(hide yes)
			(effects
				(font
					(size 1 1)
					(thickness 0.15)
				)
			)
		)
		(property "Val" "220R"
			(at 207.025 -55.125 0)
			(layer "F.Fab")
			(hide yes)
			(effects
				(font
					(size 1 1)
					(thickness 0.15)
				)
			)
		)
		(sheetname "EEPROM")
		(sheetfile "EEPROM.kicad_sch")
		(attr smd)
		(fp_rect
			(start -0.925 -0.47)
			(end 0.925 0.47)
			(stroke
				(width 0.05)
				(type default)
			)
			(fill no)
			(layer "F.CrtYd")
		)
		(fp_rect
			(start -0.5 -0.25)
			(end 0.5 0.25)
			(stroke
				(width 0.15)
				(type solid)
			)
			(fill no)
			(layer "F.Fab")
		)
		(pad "1" smd roundrect
			(at -0.48 0 90)
			(size 0.59 0.64)
			(layers "F.Cu" "F.Mask" "F.Paste")
			(roundrect_rratio 0.25)
			(net 11 "Net-(IC1-P3)")
			(pintype "passive")
		)
		(pad "2" smd roundrect
			(at 0.48 0 90)
			(size 0.59 0.64)
			(layers "F.Cu" "F.Mask" "F.Paste")
			(roundrect_rratio 0.25)
			(net 7 "Net-(D4-Pad1)")
			(pintype "passive")
		)
	)
	(footprint "antmicro-footprints:TP_SMD_1mm"
		(layer "F.Cu")
		(at 129.55 88.55)
		(property "Reference" "TP2"
			(at 0.34 -0.62 90)
			(layer "F.SilkS")
			(effects
				(font
					(size 0.7 0.7)
					(thickness 0.15)
				)
				(justify left bottom)
			)
		)
		(property "Value" "TP_1mm_SMD"
			(at 0 1.4 0)
			(layer "F.Fab")
			(hide yes)
			(effects
				(font
					(size 0.7 0.7)
					(thickness 0.15)
				)
				(justify left bottom)
			)
		)
		(property "Description" "Test Point 1mm"
			(at 0 0 0)
			(layer "F.Fab")
			(hide yes)
			(effects
				(font
					(size 1.27 1.27)
					(thickness 0.15)
				)
			)
		)
		(property "Author" "Antmicro"
			(at 0 0 0)
			(layer "F.Fab")
			(hide yes)
			(effects
				(font
					(size 1 1)
					(thickness 0.15)
				)
			)
		)
		(property "License" "Apache-2.0"
			(at 0 0 0)
			(layer "F.Fab")
			(hide yes)
			(effects
				(font
					(size 1 1)
					(thickness 0.15)
				)
			)
		)
		(property "MPN" ""
			(at 0 0 0)
			(layer "F.Fab")
			(hide yes)
			(effects
				(font
					(size 1 1)
					(thickness 0.15)
				)
			)
		)
		(property "Manufacturer" ""
			(at 0 0 0)
			(layer "F.Fab")
			(hide yes)
			(effects
				(font
					(size 1 1)
					(thickness 0.15)
				)
			)
		)
		(sheetname "EEPROM")
		(sheetfile "EEPROM.kicad_sch")
		(attr exclude_from_pos_files)
		(pad "1" smd circle
			(at 0 0)
			(size 1 1)
			(layers "F.Cu" "F.Mask")
			(net 15 "Net-(IC1-P5)")
			(pinfunction "1")
			(pintype "passive")
		)
	)
	(footprint "antmicro-footprints:TP_SMD_1mm"
		(layer "F.Cu")
		(at 131.125 88.55)
		(property "Reference" "TP3"
			(at 0.525 0.29 0)
			(layer "F.SilkS")
			(effects
				(font
					(size 0.7 0.7)
					(thickness 0.15)
				)
				(justify left bottom)
			)
		)
		(property "Value" "TP_1mm_SMD"
			(at 0 1.4 0)
			(layer "F.Fab")
			(hide yes)
			(effects
				(font
					(size 0.7 0.7)
					(thickness 0.15)
				)
				(justify left bottom)
			)
		)
		(property "Description" "Test Point 1mm"
			(at 0 0 0)
			(layer "F.Fab")
			(hide yes)
			(effects
				(font
					(size 1.27 1.27)
					(thickness 0.15)
				)
			)
		)
		(property "Author" "Antmicro"
			(at 0 0 0)
			(layer "F.Fab")
			(hide yes)
			(effects
				(font
					(size 1 1)
					(thickness 0.15)
				)
			)
		)
		(property "License" "Apache-2.0"
			(at 0 0 0)
			(layer "F.Fab")
			(hide yes)
			(effects
				(font
					(size 1 1)
					(thickness 0.15)
				)
			)
		)
		(property "MPN" ""
			(at 0 0 0)
			(layer "F.Fab")
			(hide yes)
			(effects
				(font
					(size 1 1)
					(thickness 0.15)
				)
			)
		)
		(property "Manufacturer" ""
			(at 0 0 0)
			(layer "F.Fab")
			(hide yes)
			(effects
				(font
					(size 1 1)
					(thickness 0.15)
				)
			)
		)
		(sheetname "EEPROM")
		(sheetfile "EEPROM.kicad_sch")
		(attr exclude_from_pos_files)
		(pad "1" smd circle
			(at 0 0)
			(size 1 1)
			(layers "F.Cu" "F.Mask")
			(net 1 "GND")
			(pinfunction "1")
			(pintype "passive")
		)
	)
	(footprint "antmicro-footprints:SOT-23-5"
		(layer "F.Cu")
		(at 131.525 83.55 180)
		(property "Reference" "U2"
			(at -2.485 1.54 0)
			(layer "F.SilkS")
			(effects
				(font
					(size 0.7 0.7)
					(thickness 0.15)
				)
				(justify right bottom)
			)
		)
		(property "Value" "TPS613221A_SOT-23-5"
			(at 0.002 2.799 0)
			(layer "F.Fab")
			(hide yes)
			(effects
				(font
					(size 0.7 0.7)
					(thickness 0.15)
				)
				(justify right bottom)
			)
		)
		(property "Description" "1.8-A switch current boost converter 6.5-μA Quiescent current"
			(at 0 0 180)
			(layer "F.Fab")
			(hide yes)
			(effects
				(font
					(size 1.27 1.27)
					(thickness 0.15)
				)
			)
		)
		(property "Author" "Antmicro"
			(at 263.05 167.1 0)
			(layer "F.Fab")
			(hide yes)
			(effects
				(font
					(size 1 1)
					(thickness 0.15)
				)
			)
		)
		(property "License" "Apache-2.0"
			(at 263.05 167.1 0)
			(layer "F.Fab")
			(hide yes)
			(effects
				(font
					(size 1 1)
					(thickness 0.15)
				)
			)
		)
		(property "MPN" "TPS613221ADBVT"
			(at 263.05 167.1 0)
			(layer "F.Fab")
			(hide yes)
			(effects
				(font
					(size 1 1)
					(thickness 0.15)
				)
			)
		)
		(property "Manufacturer" "Texas Instruments"
			(at 263.05 167.1 0)
			(layer "F.Fab")
			(hide yes)
			(effects
				(font
					(size 1 1)
					(thickness 0.15)
				)
			)
		)
		(sheetname "EEPROM")
		(sheetfile "EEPROM.kicad_sch")
		(attr smd)
		(fp_line
			(start 0.8 1.599)
			(end 0.549 1.599)
			(stroke
				(width 0.15)
				(type solid)
			)
			(layer "F.SilkS")
		)
		(fp_line
			(start 0.8 1.3)
			(end 0.8 1.599)
			(stroke
				(width 0.15)
				(type solid)
			)
			(layer "F.SilkS")
		)
		(fp_line
			(start 0.8 0.55)
			(end 0.8 -0.55)
			(stroke
				(width 0.15)
				(type solid)
			)
			(layer "F.SilkS")
		)
		(fp_line
			(start 0.8 -1.3)
			(end 0.8 -1.6)
			(stroke
				(width 0.15)
				(type solid)
			)
			(layer "F.SilkS")
		)
		(fp_line
			(start 0.8 -1.6)
			(end 0.5 -1.6)
			(stroke
				(width 0.15)
				(type solid)
			)
			(layer "F.SilkS")
		)
		(fp_line
			(start -0.55 1.6)
			(end -0.85 1.6)
			(stroke
				(width 0.15)
				(type solid)
			)
			(layer "F.SilkS")
		)
		(fp_line
			(start -0.8 -1.6)
			(end -0.5 -1.6)
			(stroke
				(width 0.15)
				(type solid)
			)
			(layer "F.SilkS")
		)
		(fp_line
			(start -0.8 -1.6)
			(end -0.8 -1.3)
			(stroke
				(width 0.15)
				(type solid)
			)
			(layer "F.SilkS")
		)
		(fp_line
			(start -0.85 1.6)
			(end -0.85 1.301)
			(stroke
				(width 0.15)
				(type solid)
			)
			(layer "F.SilkS")
		)
		(fp_circle
			(center -1.25 -1.5)
			(end -1.2 -1.5)
			(stroke
				(width 0.15)
				(type solid)
			)
			(fill yes)
			(layer "F.SilkS")
		)
		(fp_rect
			(start 1.9 -1.76)
			(end -1.9 1.75)
			(stroke
				(width 0.05)
				(type solid)
			)
			(fill no)
			(layer "F.CrtYd")
		)
		(fp_line
			(start -0.398 -1.526)
			(end -0.874 -1.05)
			(stroke
				(width 0.15)
				(type solid)
			)
			(layer "F.Fab")
		)
		(fp_rect
			(start 0.874 1.523)
			(end -0.873 -1.525)
			(stroke
				(width 0.15)
				(type solid)
			)
			(fill no)
			(layer "F.Fab")
		)
		(pad "1" smd rect
			(at -1.351 -0.951 90)
			(size 0.55 1)
			(layers "F.Cu" "F.Mask" "F.Paste")
			(net 69 "Net-(U2-SW)")
			(pinfunction "SW")
			(pintype "power_in")
		)
		(pad "2" smd rect
			(at -1.351 0 90)
			(size 0.55 1)
			(layers "F.Cu" "F.Mask" "F.Paste")
			(net 1 "GND")
			(pinfunction "GND")
			(pintype "power_in")
		)
		(pad "3" smd rect
			(at -1.351 0.949 90)
			(size 0.55 1)
			(layers "F.Cu" "F.Mask" "F.Paste")
			(net 223 "unconnected-(U2-NC-Pad3)")
			(pinfunction "NC")
			(pintype "no_connect")
		)
		(pad "4" smd rect
			(at 1.35 0.949 90)
			(size 0.55 1)
			(layers "F.Cu" "F.Mask" "F.Paste")
			(net 52 "/EEPROM/VDD_LED")
			(pinfunction "VOUT")
			(pintype "power_in")
		)
		(pad "5" smd rect
			(at 1.35 -0.951 90)
			(size 0.55 1)
			(layers "F.Cu" "F.Mask" "F.Paste")
			(net 224 "unconnected-(U2-NC-Pad5)")
			(pinfunction "NC")
			(pintype "no_connect")
		)
	)
	(footprint "antmicro-footprints:TSSOP-16_4.4x5mm_P0.65mm"
		(layer "F.Cu")
		(at 125.125 84.9)
		(property "Reference" "IC1"
			(at -2.655 3.76 0)
			(layer "F.SilkS")
			(effects
				(font
					(size 0.7 0.7)
					(thickness 0.15)
				)
				(justify left bottom)
			)
		)
		(property "Value" "PCA6408A_TSSOP"
			(at 0 3.749 0)
			(layer "F.Fab")
			(hide yes)
			(effects
				(font
					(size 0.7 0.7)
					(thickness 0.15)
				)
				(justify left bottom)
			)
		)
		(property "Description" "Low-voltage, 8-bit I2C-bus and SMBus I/O expander"
			(at 0 0 0)
			(layer "F.Fab")
			(hide yes)
			(effects
				(font
					(size 1.27 1.27)
					(thickness 0.15)
				)
			)
		)
		(property "Author" "Antmicro"
			(at 0 0 0)
			(layer "F.Fab")
			(hide yes)
			(effects
				(font
					(size 1 1)
					(thickness 0.15)
				)
			)
		)
		(property "License" "Apache-2.0"
			(at 0 0 0)
			(layer "F.Fab")
			(hide yes)
			(effects
				(font
					(size 1 1)
					(thickness 0.15)
				)
			)
		)
		(property "MPN" "PCA6408APW"
			(at 0 0 0)
			(layer "F.Fab")
			(hide yes)
			(effects
				(font
					(size 1 1)
					(thickness 0.15)
				)
			)
		)
		(property "Manufacturer" "NXP"
			(at 0 0 0)
			(layer "F.Fab")
			(hide yes)
			(effects
				(font
					(size 1 1)
					(thickness 0.15)
				)
			)
		)
		(sheetname "EEPROM")
		(sheetfile "EEPROM.kicad_sch")
		(attr smd)
		(fp_line
			(start -2.149 -2.735)
			(end 2.25 -2.735)
			(stroke
				(width 0.15)
				(type solid)
			)
			(layer "F.SilkS")
		)
		(fp_line
			(start 0.051 2.733)
			(end -2.149 2.733)
			(stroke
				(width 0.15)
				(type solid)
			)
			(layer "F.SilkS")
		)
		(fp_line
			(start 0.051 2.733)
			(end 2.25 2.733)
			(stroke
				(width 0.15)
				(type solid)
			)
			(layer "F.SilkS")
		)
		(fp_circle
			(center -2.815 -3.05)
			(end -2.765 -3.05)
			(stroke
				(width 0.15)
				(type solid)
			)
			(fill yes)
			(layer "F.SilkS")
		)
		(fp_line
			(start -3.81 -2.75)
			(end -3.81 2.74)
			(stroke
				(width 0.05)
				(type solid)
			)
			(layer "F.CrtYd")
		)
		(fp_line
			(start -3.81 2.74)
			(end 3.89 2.74)
			(stroke
				(width 0.05)
				(type solid)
			)
			(layer "F.CrtYd")
		)
		(fp_line
			(start 3.89 -2.75)
			(end -3.81 -2.75)
			(stroke
				(width 0.05)
				(type solid)
			)
			(layer "F.CrtYd")
		)
		(fp_line
			(start 3.89 2.74)
			(end 3.89 -2.75)
			(stroke
				(width 0.05)
				(type solid)
			)
			(layer "F.CrtYd")
		)
		(fp_line
			(start -2.149 -1.5)
			(end -1.15 -2.5)
			(stroke
				(width 0.15)
				(type solid)
			)
			(layer "F.Fab")
		)
		(fp_line
			(start -2.149 2.499)
			(end -2.149 -1.5)
			(stroke
				(width 0.15)
				(type solid)
			)
			(layer "F.Fab")
		)
		(fp_line
			(start -1.15 -2.5)
			(end 2.25 -2.5)
			(stroke
				(width 0.15)
				(type solid)
			)
			(layer "F.Fab")
		)
		(fp_line
			(start 2.25 -2.5)
			(end 2.25 2.499)
			(stroke
				(width 0.15)
				(type solid)
			)
			(layer "F.Fab")
		)
		(fp_line
			(start 2.25 2.499)
			(end -2.149 2.499)
			(stroke
				(width 0.15)
				(type solid)
			)
			(layer "F.Fab")
		)
		(pad "1" smd rect
			(at -2.815 -2.275)
			(size 1.475 0.4)
			(layers "F.Cu" "F.Mask" "F.Paste")
			(net 50 "1V8_SYS")
			(pinfunction "VDD(I2C)")
			(pintype "power_in")
		)
		(pad "2" smd rect
			(at -2.815 -1.625)
			(size 1.475 0.4)
			(layers "F.Cu" "F.Mask" "F.Paste")
			(net 50 "1V8_SYS")
			(pinfunction "ADDR")
			(pintype "input")
		)
		(pad "3" smd rect
			(at -2.815 -0.975)
			(size 1.475 0.4)
			(layers "F.Cu" "F.Mask" "F.Paste")
			(net 50 "1V8_SYS")
			(pinfunction "~{RESET}")
			(pintype "input")
		)
		(pad "4" smd rect
			(at -2.815 -0.325)
			(size 1.475 0.4)
			(layers "F.Cu" "F.Mask" "F.Paste")
			(net 8 "Net-(IC1-P0)")
			(pinfunction "P0")
			(pintype "bidirectional")
		)
		(pad "5" smd rect
			(at -2.815 0.325)
			(size 1.475 0.4)
			(layers "F.Cu" "F.Mask" "F.Paste")
			(net 9 "Net-(IC1-P1)")
			(pinfunction "P1")
			(pintype "bidirectional")
		)
		(pad "6" smd rect
			(at -2.815 0.975)
			(size 1.475 0.4)
			(layers "F.Cu" "F.Mask" "F.Paste")
			(net 10 "Net-(IC1-P2)")
			(pinfunction "P2")
			(pintype "bidirectional")
		)
		(pad "7" smd rect
			(at -2.815 1.625)
			(size 1.475 0.4)
			(layers "F.Cu" "F.Mask" "F.Paste")
			(net 11 "Net-(IC1-P3)")
			(pinfunction "P3")
			(pintype "bidirectional")
		)
		(pad "8" smd rect
			(at -2.815 2.275)
			(size 1.475 0.4)
			(layers "F.Cu" "F.Mask" "F.Paste")
			(net 1 "GND")
			(pinfunction "GND")
			(pintype "power_in")
		)
		(pad "9" smd rect
			(at 2.91 2.275)
			(size 1.475 0.4)
			(layers "F.Cu" "F.Mask" "F.Paste")
			(net 14 "Net-(IC1-P4)")
			(pinfunction "P4")
			(pintype "bidirectional")
		)
		(pad "10" smd rect
			(at 2.91 1.625)
			(size 1.475 0.4)
			(layers "F.Cu" "F.Mask" "F.Paste")
			(net 15 "Net-(IC1-P5)")
			(pinfunction "P5")
			(pintype "bidirectional")
		)
		(pad "11" smd rect
			(at 2.91 0.975)
			(size 1.475 0.4)
			(layers "F.Cu" "F.Mask" "F.Paste")
			(net 16 "unconnected-(IC1-P6-Pad11)")
			(pinfunction "P6")
			(pintype "bidirectional+no_connect")
		)
		(pad "12" smd rect
			(at 2.91 0.325)
			(size 1.475 0.4)
			(layers "F.Cu" "F.Mask" "F.Paste")
			(net 67 "unconnected-(IC1-P7-Pad12)")
			(pinfunction "P7")
			(pintype "bidirectional+no_connect")
		)
		(pad "13" smd rect
			(at 2.91 -0.325)
			(size 1.475 0.4)
			(layers "F.Cu" "F.Mask" "F.Paste")
			(net 68 "unconnected-(IC1-~{INT}-Pad13)")
			(pinfunction "~{INT}")
			(pintype "open_collector+no_connect")
		)
		(pad "14" smd rect
			(at 2.91 -0.975)
			(size 1.475 0.4)
			(layers "F.Cu" "F.Mask" "F.Paste")
			(net 13 "SCL")
			(pinfunction "SCL")
			(pintype "open_collector")
		)
		(pad "15" smd rect
			(at 2.91 -1.625)
			(size 1.475 0.4)
			(layers "F.Cu" "F.Mask" "F.Paste")
			(net 12 "SDA")
			(pinfunction "SDA")
			(pintype "open_collector")
		)
		(pad "16" smd rect
			(at 2.91 -2.275)
			(size 1.475 0.4)
			(layers "F.Cu" "F.Mask" "F.Paste")
			(net 52 "/EEPROM/VDD_LED")
			(pinfunction "VDD(P)")
			(pintype "power_in")
		)
	)
	(footprint "antmicro-footprints:LED_0603_1608Metric_G"
		(layer "F.Cu")
		(at 127.441666 72.9 90)
		(descr "LED SMD 0603 Green")
		(tags "LED SMD 0603 Green")
		(property "Reference" "D2"
			(at 1.54 -0.671666 180)
			(layer "F.SilkS")
			(effects
				(font
					(size 0.7 0.7)
					(thickness 0.15)
				)
				(justify left bottom)
			)
		)
		(property "Value" "LED_G_0603_KP-1608CGCK"
			(at 0 1.6 90)
			(layer "F.Fab")
			(hide yes)
			(effects
				(font
					(size 0.7 0.7)
					(thickness 0.15)
				)
				(justify left bottom)
			)
		)
		(property "Author" "Antmicro"
			(at 200.341666 -54.541666 0)
			(layer "F.Fab")
			(hide yes)
			(effects
				(font
					(size 1 1)
					(thickness 0.15)
				)
			)
		)
		(property "License" "Apache-2.0"
			(at 200.341666 -54.541666 0)
			(layer "F.Fab")
			(hide yes)
			(effects
				(font
					(size 1 1)
					(thickness 0.15)
				)
			)
		)
		(property "MPN" "KP-1608CGCK"
			(at 200.341666 -54.541666 0)
			(layer "F.Fab")
			(hide yes)
			(effects
				(font
					(size 1 1)
					(thickness 0.15)
				)
			)
		)
		(property "Manufacturer" "Kingbright"
			(at 200.341666 -54.541666 0)
			(layer "F.Fab")
			(hide yes)
			(effects
				(font
					(size 1 1)
					(thickness 0.15)
				)
			)
		)
		(sheetname "EEPROM")
		(sheetfile "EEPROM.kicad_sch")
		(attr smd)
		(fp_line
			(start 0.22 -0.35)
			(end -0.22 -0.35)
			(stroke
				(width 0.15)
				(type solid)
			)
			(layer "F.SilkS")
		)
		(fp_line
			(start -1.18 -0.319)
			(end -1.18 0.321)
			(stroke
				(width 0.15)
				(type solid)
			)
			(layer "F.SilkS")
		)
		(fp_line
			(start 0.105328 0.001008)
			(end 0.24 0.001)
			(stroke
				(width 0.1)
				(type solid)
			)
			(layer "F.SilkS")
		)
		(fp_line
			(start -0.094672 0.001008)
			(end 0.105328 -0.198992)
			(stroke
				(width 0.1)
				(type solid)
			)
			(layer "F.SilkS")
		)
		(fp_line
			(start -0.094672 0.001008)
			(end -0.24 0.001008)
			(stroke
				(width 0.1)
				(type solid)
			)
			(layer "F.SilkS")
		)
		(fp_line
			(start 0.105328 0.201008)
			(end 0.105328 -0.198992)
			(stroke
				(width 0.1)
				(type solid)
			)
			(layer "F.SilkS")
		)
		(fp_line
			(start 0.105328 0.201008)
			(end -0.094672 0.001008)
			(stroke
				(width 0.1)
				(type solid)
			)
			(layer "F.SilkS")
		)
		(fp_line
			(start -0.094672 0.201008)
			(end -0.094672 -0.198992)
			(stroke
				(width 0.1)
				(type solid)
			)
			(layer "F.SilkS")
		)
		(fp_line
			(start 0.22 0.35)
			(end -0.22 0.35)
			(stroke
				(width 0.15)
				(type solid)
			)
			(layer "F.SilkS")
		)
		(fp_rect
			(start 1.25 0.65)
			(end -1.25 -0.65)
			(stroke
				(width 0.05)
				(type solid)
			)
			(fill no)
			(layer "F.CrtYd")
		)
		(fp_line
			(start 0.201 -0.202)
			(end -0.101 0)
			(stroke
				(width 0.15)
				(type solid)
			)
			(layer "F.Fab")
		)
		(fp_line
			(start -0.199 -0.202)
			(end -0.199 0.1)
			(stroke
				(width 0.15)
				(type solid)
			)
			(layer "F.Fab")
		)
		(fp_line
			(start 0.599 0)
			(end 0.201 0)
			(stroke
				(width 0.15)
				(type solid)
			)
			(layer "F.Fab")
		)
		(fp_line
			(start 0.201 0)
			(end 0.201 -0.202)
			(stroke
				(width 0.15)
				(type solid)
			)
			(layer "F.Fab")
		)
		(fp_line
			(start -0.101 0)
			(end 0.201 0.2)
			(stroke
				(width 0.15)
				(type solid)
			)
			(layer "F.Fab")
		)
		(fp_line
			(start -0.199 0)
			(end -0.597 0)
			(stroke
				(width 0.15)
				(type solid)
			)
			(layer "F.Fab")
		)
		(fp_line
			(start 0.201 0.2)
			(end 0.201 0)
			(stroke
				(width 0.15)
				(type solid)
			)
			(layer "F.Fab")
		)
		(fp_line
			(start -0.199 0.2)
			(end -0.199 0.1)
			(stroke
				(width 0.15)
				(type solid)
			)
			(layer "F.Fab")
		)
		(fp_rect
			(start 0.848 0.4)
			(end -0.85 -0.402)
			(stroke
				(width 0.15)
				(type solid)
			)
			(fill no)
			(layer "F.Fab")
		)
		(pad "1" smd roundrect
			(at -0.7 0 270)
			(size 0.8 1)
			(layers "F.Cu" "F.Mask" "F.Paste")
			(roundrect_rratio 0.2)
			(net 5 "Net-(D2-Pad1)")
			(pinfunction "1")
			(pintype "passive")
		)
		(pad "2" smd roundrect
			(at 0.7 0 270)
			(size 0.8 1)
			(layers "F.Cu" "F.Mask" "F.Paste")
			(roundrect_rratio 0.2)
			(net 1 "GND")
			(pinfunction "2")
			(pintype "passive")
		)
	)
	(footprint "antmicro-footprints:R_0402_1005Metric"
		(layer "F.Cu")
		(at 125.625 75.95 90)
		(descr "Resistor SMD 0402")
		(tags "resistor SMD 0402")
		(property "Reference" "R9"
			(at -2.5 0.345 90)
			(layer "F.SilkS")
			(effects
				(font
					(size 0.7 0.7)
					(thickness 0.15)
				)
				(justify left bottom)
			)
		)
		(property "Value" "R_220R_0402"
			(at 0 1.4 90)
			(layer "F.Fab")
			(hide yes)
			(effects
				(font
					(size 0.7 0.7)
					(thickness 0.15)
				)
				(justify left bottom)
			)
		)
		(property "Description" "220R resistor in 0402 package with 1% tolerance"
			(at 0 0 90)
			(layer "F.Fab")
			(hide yes)
			(effects
				(font
					(size 1.27 1.27)
					(thickness 0.15)
				)
			)
		)
		(property "Author" "Antmicro"
			(at 201.575 -49.675 0)
			(layer "F.Fab")
			(hide yes)
			(effects
				(font
					(size 1 1)
					(thickness 0.15)
				)
			)
		)
		(property "License" "Apache-2.0"
			(at 201.575 -49.675 0)
			(layer "F.Fab")
			(hide yes)
			(effects
				(font
					(size 1 1)
					(thickness 0.15)
				)
			)
		)
		(property "MPN" "CR0402-FX-2200GLF"
			(at 201.575 -49.675 0)
			(layer "F.Fab")
			(hide yes)
			(effects
				(font
					(size 1 1)
					(thickness 0.15)
				)
			)
		)
		(property "Manufacturer" "Bourns"
			(at 201.575 -49.675 0)
			(layer "F.Fab")
			(hide yes)
			(effects
				(font
					(size 1 1)
					(thickness 0.15)
				)
			)
		)
		(property "Tolerance" "1%"
			(at 201.575 -49.675 0)
			(layer "F.Fab")
			(hide yes)
			(effects
				(font
					(size 1 1)
					(thickness 0.15)
				)
			)
		)
		(property "Val" "220R"
			(at 201.575 -49.675 0)
			(layer "F.Fab")
			(hide yes)
			(effects
				(font
					(size 1 1)
					(thickness 0.15)
				)
			)
		)
		(sheetname "EEPROM")
		(sheetfile "EEPROM.kicad_sch")
		(attr smd)
		(fp_rect
			(start -0.925 -0.47)
			(end 0.925 0.47)
			(stroke
				(width 0.05)
				(type default)
			)
			(fill no)
			(layer "F.CrtYd")
		)
		(fp_rect
			(start -0.5 -0.25)
			(end 0.5 0.25)
			(stroke
				(width 0.15)
				(type solid)
			)
			(fill no)
			(layer "F.Fab")
		)
		(pad "1" smd roundrect
			(at -0.48 0 90)
			(size 0.59 0.64)
			(layers "F.Cu" "F.Mask" "F.Paste")
			(roundrect_rratio 0.25)
			(net 8 "Net-(IC1-P0)")
			(pintype "passive")
		)
		(pad "2" smd roundrect
			(at 0.48 0 90)
			(size 0.59 0.64)
			(layers "F.Cu" "F.Mask" "F.Paste")
			(roundrect_rratio 0.25)
			(net 4 "Net-(D1-Pad1)")
			(pintype "passive")
		)
	)
	(footprint "antmicro-footprints:R_0402_1005Metric"
		(layer "F.Cu")
		(at 127.441666 75.95 90)
		(descr "Resistor SMD 0402")
		(tags "resistor SMD 0402")
		(property "Reference" "R10"
			(at -3.05 0.345 90)
			(layer "F.SilkS")
			(effects
				(font
					(size 0.7 0.7)
					(thickness 0.15)
				)
				(justify left bottom)
			)
		)
		(property "Value" "R_220R_0402"
			(at 0 1.4 90)
			(layer "F.Fab")
			(hide yes)
			(effects
				(font
					(size 0.7 0.7)
					(thickness 0.15)
				)
				(justify left bottom)
			)
		)
		(property "Description" "220R resistor in 0402 package with 1% tolerance"
			(at 0 0 90)
			(layer "F.Fab")
			(hide yes)
			(effects
				(font
					(size 1.27 1.27)
					(thickness 0.15)
				)
			)
		)
		(property "Author" "Antmicro"
			(at 203.391666 -51.491666 0)
			(layer "F.Fab")
			(hide yes)
			(effects
				(font
					(size 1 1)
					(thickness 0.15)
				)
			)
		)
		(property "License" "Apache-2.0"
			(at 203.391666 -51.491666 0)
			(layer "F.Fab")
			(hide yes)
			(effects
				(font
					(size 1 1)
					(thickness 0.15)
				)
			)
		)
		(property "MPN" "CR0402-FX-2200GLF"
			(at 203.391666 -51.491666 0)
			(layer "F.Fab")
			(hide yes)
			(effects
				(font
					(size 1 1)
					(thickness 0.15)
				)
			)
		)
		(property "Manufacturer" "Bourns"
			(at 203.391666 -51.491666 0)
			(layer "F.Fab")
			(hide yes)
			(effects
				(font
					(size 1 1)
					(thickness 0.15)
				)
			)
		)
		(property "Tolerance" "1%"
			(at 203.391666 -51.491666 0)
			(layer "F.Fab")
			(hide yes)
			(effects
				(font
					(size 1 1)
					(thickness 0.15)
				)
			)
		)
		(property "Val" "220R"
			(at 203.391666 -51.491666 0)
			(layer "F.Fab")
			(hide yes)
			(effects
				(font
					(size 1 1)
					(thickness 0.15)
				)
			)
		)
		(sheetname "EEPROM")
		(sheetfile "EEPROM.kicad_sch")
		(attr smd)
		(fp_rect
			(start -0.925 -0.47)
			(end 0.925 0.47)
			(stroke
				(width 0.05)
				(type default)
			)
			(fill no)
			(layer "F.CrtYd")
		)
		(fp_rect
			(start -0.5 -0.25)
			(end 0.5 0.25)
			(stroke
				(width 0.15)
				(type solid)
			)
			(fill no)
			(layer "F.Fab")
		)
		(pad "1" smd roundrect
			(at -0.48 0 90)
			(size 0.59 0.64)
			(layers "F.Cu" "F.Mask" "F.Paste")
			(roundrect_rratio 0.25)
			(net 9 "Net-(IC1-P1)")
			(pintype "passive")
		)
		(pad "2" smd roundrect
			(at 0.48 0 90)
			(size 0.59 0.64)
			(layers "F.Cu" "F.Mask" "F.Paste")
			(roundrect_rratio 0.25)
			(net 5 "Net-(D2-Pad1)")
			(pintype "passive")
		)
	)
	(footprint "antmicro-footprints:R_0402_1005Metric"
		(layer "F.Cu")
		(at 129.258332 75.95 90)
		(descr "Resistor SMD 0402")
		(tags "resistor SMD 0402")
		(property "Reference" "R11"
			(at -3.05 0.345 90)
			(layer "F.SilkS")
			(effects
				(font
					(size 0.7 0.7)
					(thickness 0.15)
				)
				(justify left bottom)
			)
		)
		(property "Value" "R_220R_0402"
			(at 0 1.4 90)
			(layer "F.Fab")
			(hide yes)
			(effects
				(font
					(size 0.7 0.7)
					(thickness 0.15)
				)
				(justify left bottom)
			)
		)
		(property "Description" "220R resistor in 0402 package with 1% tolerance"
			(at 0 0 90)
			(layer "F.Fab")
			(hide yes)
			(effects
				(font
					(size 1.27 1.27)
					(thickness 0.15)
				)
			)
		)
		(property "Author" "Antmicro"
			(at 205.208332 -53.308332 0)
			(layer "F.Fab")
			(hide yes)
			(effects
				(font
					(size 1 1)
					(thickness 0.15)
				)
			)
		)
		(property "License" "Apache-2.0"
			(at 205.208332 -53.308332 0)
			(layer "F.Fab")
			(hide yes)
			(effects
				(font
					(size 1 1)
					(thickness 0.15)
				)
			)
		)
		(property "MPN" "CR0402-FX-2200GLF"
			(at 205.208332 -53.308332 0)
			(layer "F.Fab")
			(hide yes)
			(effects
				(font
					(size 1 1)
					(thickness 0.15)
				)
			)
		)
		(property "Manufacturer" "Bourns"
			(at 205.208332 -53.308332 0)
			(layer "F.Fab")
			(hide yes)
			(effects
				(font
					(size 1 1)
					(thickness 0.15)
				)
			)
		)
		(property "Tolerance" "1%"
			(at 205.208332 -53.308332 0)
			(layer "F.Fab")
			(hide yes)
			(effects
				(font
					(size 1 1)
					(thickness 0.15)
				)
			)
		)
		(property "Val" "220R"
			(at 205.208332 -53.308332 0)
			(layer "F.Fab")
			(hide yes)
			(effects
				(font
					(size 1 1)
					(thickness 0.15)
				)
			)
		)
		(sheetname "EEPROM")
		(sheetfile "EEPROM.kicad_sch")
		(attr smd)
		(fp_rect
			(start -0.925 -0.47)
			(end 0.925 0.47)
			(stroke
				(width 0.05)
				(type default)
			)
			(fill no)
			(layer "F.CrtYd")
		)
		(fp_rect
			(start -0.5 -0.25)
			(end 0.5 0.25)
			(stroke
				(width 0.15)
				(type solid)
			)
			(fill no)
			(layer "F.Fab")
		)
		(pad "1" smd roundrect
			(at -0.48 0 90)
			(size 0.59 0.64)
			(layers "F.Cu" "F.Mask" "F.Paste")
			(roundrect_rratio 0.25)
			(net 10 "Net-(IC1-P2)")
			(pintype "passive")
		)
		(pad "2" smd roundrect
			(at 0.48 0 90)
			(size 0.59 0.64)
			(layers "F.Cu" "F.Mask" "F.Paste")
			(roundrect_rratio 0.25)
			(net 6 "Net-(D3-Pad1)")
			(pintype "passive")
		)
	)
	(footprint "antmicro-footprints:TP_SMD_1mm"
		(layer "F.Cu")
		(at 127.975 88.55)
		(property "Reference" "TP1"
			(at -2.515 0.05 0)
			(layer "F.SilkS")
			(effects
				(font
					(size 0.7 0.7)
					(thickness 0.15)
				)
				(justify left bottom)
			)
		)
		(property "Value" "TP_1mm_SMD"
			(at 0 1.4 0)
			(layer "F.Fab")
			(hide yes)
			(effects
				(font
					(size 0.7 0.7)
					(thickness 0.15)
				)
				(justify left bottom)
			)
		)
		(property "Description" "Test Point 1mm"
			(at 0 0 0)
			(layer "F.Fab")
			(hide yes)
			(effects
				(font
					(size 1.27 1.27)
					(thickness 0.15)
				)
			)
		)
		(property "Author" "Antmicro"
			(at 0 0 0)
			(layer "F.Fab")
			(hide yes)
			(effects
				(font
					(size 1 1)
					(thickness 0.15)
				)
			)
		)
		(property "License" "Apache-2.0"
			(at 0 0 0)
			(layer "F.Fab")
			(hide yes)
			(effects
				(font
					(size 1 1)
					(thickness 0.15)
				)
			)
		)
		(property "MPN" ""
			(at 0 0 0)
			(layer "F.Fab")
			(hide yes)
			(effects
				(font
					(size 1 1)
					(thickness 0.15)
				)
			)
		)
		(property "Manufacturer" ""
			(at 0 0 0)
			(layer "F.Fab")
			(hide yes)
			(effects
				(font
					(size 1 1)
					(thickness 0.15)
				)
			)
		)
		(sheetname "EEPROM")
		(sheetfile "EEPROM.kicad_sch")
		(attr exclude_from_pos_files)
		(pad "1" smd circle
			(at 0 0)
			(size 1 1)
			(layers "F.Cu" "F.Mask")
			(net 14 "Net-(IC1-P4)")
			(pinfunction "1")
			(pintype "passive")
		)
	)
	(footprint "antmicro-footprints:C_0402_1005Metric"
		(layer "F.Cu")
		(at 132.175 91.615 90)
		(descr "Capacitor SMD 0402")
		(tags "capacitor SMD 0402")
		(property "Reference" "C39"
			(at -1.275 1.335 90)
			(layer "F.SilkS")
			(effects
				(font
					(size 0.7 0.7)
					(thickness 0.15)
				)
				(justify left bottom)
			)
		)
		(property "Value" "C_100n_0402"
			(at 0 1.4 90)
			(layer "F.Fab")
			(hide yes)
			(effects
				(font
					(size 0.7 0.7)
					(thickness 0.15)
				)
				(justify left bottom)
			)
		)
		(property "Description" " "
			(at 0 0 90)
			(layer "F.Fab")
			(hide yes)
			(effects
				(font
					(size 1.27 1.27)
					(thickness 0.15)
				)
			)
		)
		(property "Author" "Antmicro"
			(at 223.79 -40.56 0)
			(layer "F.Fab")
			(hide yes)
			(effects
				(font
					(size 1 1)
					(thickness 0.15)
				)
			)
		)
		(property "Dielectric" "X5R"
			(at 223.79 -40.56 0)
			(layer "F.Fab")
			(hide yes)
			(effects
				(font
					(size 1 1)
					(thickness 0.15)
				)
			)
		)
		(property "License" "Apache-2.0"
			(at 223.79 -40.56 0)
			(layer "F.Fab")
			(hide yes)
			(effects
				(font
					(size 1 1)
					(thickness 0.15)
				)
			)
		)
		(property "MPN" "GRM155R61H104KE14D"
			(at 223.79 -40.56 0)
			(layer "F.Fab")
			(hide yes)
			(effects
				(font
					(size 1 1)
					(thickness 0.15)
				)
			)
		)
		(property "Manufacturer" "Murata"
			(at 223.79 -40.56 0)
			(layer "F.Fab")
			(hide yes)
			(effects
				(font
					(size 1 1)
					(thickness 0.15)
				)
			)
		)
		(property "Val" "100n"
			(at 223.79 -40.56 0)
			(layer "F.Fab")
			(hide yes)
			(effects
				(font
					(size 1 1)
					(thickness 0.15)
				)
			)
		)
		(property "Voltage" "50V"
			(at 223.79 -40.56 0)
			(layer "F.Fab")
			(hide yes)
			(effects
				(font
					(size 1 1)
					(thickness 0.15)
				)
			)
		)
		(sheetname "EEPROM")
		(sheetfile "EEPROM.kicad_sch")
		(attr smd)
		(fp_rect
			(start -0.925 -0.47)
			(end 0.925 0.47)
			(stroke
				(width 0.05)
				(type default)
			)
			(fill no)
			(layer "F.CrtYd")
		)
		(fp_line
			(start 0.504 -0.25)
			(end 0.504 0.248)
			(stroke
				(width 0.15)
				(type solid)
			)
			(layer "F.Fab")
		)
		(fp_line
			(start -0.494 -0.25)
			(end 0.504 -0.25)
			(stroke
				(width 0.15)
				(type solid)
			)
			(layer "F.Fab")
		)
		(fp_line
			(start 0.504 0.248)
			(end -0.494 0.248)
			(stroke
				(width 0.15)
				(type solid)
			)
			(layer "F.Fab")
		)
		(fp_line
			(start -0.494 0.248)
			(end -0.494 -0.25)
			(stroke
				(width 0.15)
				(type solid)
			)
			(layer "F.Fab")
		)
		(pad "1" smd roundrect
			(at -0.48 0 90)
			(size 0.59 0.64)
			(layers "F.Cu" "F.Mask" "F.Paste")
			(roundrect_rratio 0.25)
			(net 50 "1V8_SYS")
			(pintype "passive")
		)
		(pad "2" smd roundrect
			(at 0.48 0 90)
			(size 0.59 0.64)
			(layers "F.Cu" "F.Mask" "F.Paste")
			(roundrect_rratio 0.25)
			(net 1 "GND")
			(pintype "passive")
		)
	)
	(footprint "antmicro-footprints:R_0402_1005Metric"
		(layer "F.Cu")
		(at 126.56 92.585 90)
		(descr "Resistor SMD 0402")
		(tags "resistor SMD 0402")
		(property "Reference" "R13"
			(at -1.015 -0.67 90)
			(layer "F.SilkS")
			(effects
				(font
					(size 0.7 0.7)
					(thickness 0.15)
				)
				(justify left bottom)
			)
		)
		(property "Value" "R_10k_0402"
			(at 0 1.4 90)
			(layer "F.Fab")
			(hide yes)
			(effects
				(font
					(size 0.7 0.7)
					(thickness 0.15)
				)
				(justify left bottom)
			)
		)
		(property "Description" "10k resistor in 0402 package with 1% tolerance"
			(at 0 0 90)
			(layer "F.Fab")
			(hide yes)
			(effects
				(font
					(size 1.27 1.27)
					(thickness 0.15)
				)
			)
		)
		(property "Author" "Antmicro"
			(at 219.145 -33.975 0)
			(layer "F.Fab")
			(hide yes)
			(effects
				(font
					(size 1 1)
					(thickness 0.15)
				)
			)
		)
		(property "License" "Apache-2.0"
			(at 219.145 -33.975 0)
			(layer "F.Fab")
			(hide yes)
			(effects
				(font
					(size 1 1)
					(thickness 0.15)
				)
			)
		)
		(property "MPN" "CR0402-FX-1002GLF"
			(at 219.145 -33.975 0)
			(layer "F.Fab")
			(hide yes)
			(effects
				(font
					(size 1 1)
					(thickness 0.15)
				)
			)
		)
		(property "Manufacturer" "Bourns"
			(at 219.145 -33.975 0)
			(layer "F.Fab")
			(hide yes)
			(effects
				(font
					(size 1 1)
					(thickness 0.15)
				)
			)
		)
		(property "Tolerance" "1%"
			(at 219.145 -33.975 0)
			(layer "F.Fab")
			(hide yes)
			(effects
				(font
					(size 1 1)
					(thickness 0.15)
				)
			)
		)
		(property "Val" "10k"
			(at 219.145 -33.975 0)
			(layer "F.Fab")
			(hide yes)
			(effects
				(font
					(size 1 1)
					(thickness 0.15)
				)
			)
		)
		(sheetname "EEPROM")
		(sheetfile "EEPROM.kicad_sch")
		(attr smd)
		(fp_rect
			(start -0.925 -0.47)
			(end 0.925 0.47)
			(stroke
				(width 0.05)
				(type default)
			)
			(fill no)
			(layer "F.CrtYd")
		)
		(fp_rect
			(start -0.5 -0.25)
			(end 0.5 0.25)
			(stroke
				(width 0.15)
				(type solid)
			)
			(fill no)
			(layer "F.Fab")
		)
		(pad "1" smd roundrect
			(at -0.48 0 90)
			(size 0.59 0.64)
			(layers "F.Cu" "F.Mask" "F.Paste")
			(roundrect_rratio 0.25)
			(net 50 "1V8_SYS")
			(pintype "passive")
		)
		(pad "2" smd roundrect
			(at 0.48 0 90)
			(size 0.59 0.64)
			(layers "F.Cu" "F.Mask" "F.Paste")
			(roundrect_rratio 0.25)
			(net 12 "SDA")
			(pintype "passive")
		)
	)
	(footprint "antmicro-footprints:R_0402_1005Metric"
		(layer "F.Cu")
		(at 126.555 89.72 -90)
		(descr "Resistor SMD 0402")
		(tags "resistor SMD 0402")
		(property "Reference" "R14"
			(at 1.04 0.635 270)
			(layer "F.SilkS")
			(effects
				(font
					(size 0.7 0.7)
					(thickness 0.15)
				)
				(justify left bottom)
			)
		)
		(property "Value" "R_10k_0402"
			(at 0 1.4 270)
			(layer "F.Fab")
			(hide yes)
			(effects
				(font
					(size 0.7 0.7)
					(thickness 0.15)
				)
				(justify left bottom)
			)
		)
		(property "Description" "10k resistor in 0402 package with 1% tolerance"
			(at 0 0 270)
			(layer "F.Fab")
			(hide yes)
			(effects
				(font
					(size 1.27 1.27)
					(thickness 0.15)
				)
			)
		)
		(property "Author" "Antmicro"
			(at 36.835 216.275 0)
			(layer "F.Fab")
			(hide yes)
			(effects
				(font
					(size 1 1)
					(thickness 0.15)
				)
			)
		)
		(property "License" "Apache-2.0"
			(at 36.835 216.275 0)
			(layer "F.Fab")
			(hide yes)
			(effects
				(font
					(size 1 1)
					(thickness 0.15)
				)
			)
		)
		(property "MPN" "CR0402-FX-1002GLF"
			(at 36.835 216.275 0)
			(layer "F.Fab")
			(hide yes)
			(effects
				(font
					(size 1 1)
					(thickness 0.15)
				)
			)
		)
		(property "Manufacturer" "Bourns"
			(at 36.835 216.275 0)
			(layer "F.Fab")
			(hide yes)
			(effects
				(font
					(size 1 1)
					(thickness 0.15)
				)
			)
		)
		(property "Tolerance" "1%"
			(at 36.835 216.275 0)
			(layer "F.Fab")
			(hide yes)
			(effects
				(font
					(size 1 1)
					(thickness 0.15)
				)
			)
		)
		(property "Val" "10k"
			(at 36.835 216.275 0)
			(layer "F.Fab")
			(hide yes)
			(effects
				(font
					(size 1 1)
					(thickness 0.15)
				)
			)
		)
		(sheetname "EEPROM")
		(sheetfile "EEPROM.kicad_sch")
		(attr smd)
		(fp_rect
			(start -0.925 -0.47)
			(end 0.925 0.47)
			(stroke
				(width 0.05)
				(type default)
			)
			(fill no)
			(layer "F.CrtYd")
		)
		(fp_rect
			(start -0.5 -0.25)
			(end 0.5 0.25)
			(stroke
				(width 0.15)
				(type solid)
			)
			(fill no)
			(layer "F.Fab")
		)
		(pad "1" smd roundrect
			(at -0.48 0 270)
			(size 0.59 0.64)
			(layers "F.Cu" "F.Mask" "F.Paste")
			(roundrect_rratio 0.25)
			(net 50 "1V8_SYS")
			(pintype "passive")
		)
		(pad "2" smd roundrect
			(at 0.48 0 270)
			(size 0.59 0.64)
			(layers "F.Cu" "F.Mask" "F.Paste")
			(roundrect_rratio 0.25)
			(net 13 "SCL")
			(pintype "passive")
		)
	)
	(footprint "antmicro-footprints:FB_0805_2012Metric"
		(layer "F.Cu")
		(at 138.2 87.2)
		(descr "FERRITE BEAD 0805")
		(tags "FERRITE BEAD 0805")
		(property "Reference" "FB1"
			(at 1.81 0.41 0)
			(layer "F.SilkS")
			(effects
				(font
					(size 0.7 0.7)
					(thickness 0.15)
				)
				(justify left bottom)
			)
		)
		(property "Value" "FB_220Z_1.5A_WE-CBF_0805"
			(at 0 1.8 0)
			(layer "F.Fab")
			(hide yes)
			(effects
				(font
					(size 0.7 0.7)
					(thickness 0.15)
				)
				(justify left bottom)
			)
		)
		(property "Description" "Ferrite Bead, 0805 [2012 Metric], 220 ohm, 2 A, WE-CBF, 0.05 ohm, ± 25%, High Current"
			(at 0 0 0)
			(layer "F.Fab")
			(hide yes)
			(effects
				(font
					(size 1.27 1.27)
					(thickness 0.15)
				)
			)
		)
		(property "Author" "Antmicro"
			(at 0 0 0)
			(layer "F.Fab")
			(hide yes)
			(effects
				(font
					(size 1 1)
					(thickness 0.15)
				)
			)
		)
		(property "Current" "1.5A"
			(at 0 0 0)
			(layer "F.Fab")
			(hide yes)
			(effects
				(font
					(size 1 1)
					(thickness 0.15)
				)
			)
		)
		(property "License" "Apache-2.0"
			(at 0 0 0)
			(layer "F.Fab")
			(hide yes)
			(effects
				(font
					(size 1 1)
					(thickness 0.15)
				)
			)
		)
		(property "MPN" "742792022"
			(at 0 0 0)
			(layer "F.Fab")
			(hide yes)
			(effects
				(font
					(size 1 1)
					(thickness 0.15)
				)
			)
		)
		(property "Manufacturer" "Würth Elektronik"
			(at 0 0 0)
			(layer "F.Fab")
			(hide yes)
			(effects
				(font
					(size 1 1)
					(thickness 0.15)
				)
			)
		)
		(property "Public" "False"
			(at 0 0 0)
			(layer "F.Fab")
			(hide yes)
			(effects
				(font
					(size 1 1)
					(thickness 0.15)
				)
			)
		)
		(property "Val" "220Z/1.5A"
			(at 0 0 0)
			(layer "F.Fab")
			(hide yes)
			(effects
				(font
					(size 1 1)
					(thickness 0.15)
				)
			)
		)
		(sheetname "DDR5")
		(sheetfile "ddr5.kicad_sch")
		(attr smd)
		(fp_line
			(start -0.319 0.698)
			(end 0.281 0.698)
			(stroke
				(width 0.15)
				(type solid)
			)
			(layer "F.SilkS")
		)
		(fp_line
			(start -0.299 -0.698)
			(end 0.299 -0.698)
			(stroke
				(width 0.15)
				(type solid)
			)
			(layer "F.SilkS")
		)
		(fp_rect
			(start 1.95 -0.9)
			(end -1.95 0.9)
			(stroke
				(width 0.05)
				(type default)
			)
			(fill no)
			(layer "F.CrtYd")
		)
		(fp_line
			(start -0.948 -0.681)
			(end 0.948 -0.681)
			(stroke
				(width 0.15)
				(type solid)
			)
			(layer "F.Fab")
		)
		(fp_line
			(start -0.948 -0.676)
			(end -0.948 0.676)
			(stroke
				(width 0.15)
				(type solid)
			)
			(layer "F.Fab")
		)
		(fp_line
			(start -0.948 0.681)
			(end 0.948 0.681)
			(stroke
				(width 0.15)
				(type solid)
			)
			(layer "F.Fab")
		)
		(fp_line
			(start 0.948 -0.676)
			(end 0.948 0.676)
			(stroke
				(width 0.15)
				(type solid)
			)
			(layer "F.Fab")
		)
		(pad "1" smd roundrect
			(at -1.1 0)
			(size 1.2 1.3)
			(layers "F.Cu" "F.Mask" "F.Paste")
			(roundrect_rratio 0.25)
			(net 51 "1V1_SYS")
			(pintype "passive")
		)
		(pad "2" smd roundrect
			(at 1.1 0)
			(size 1.2 1.3)
			(layers "F.Cu" "F.Mask" "F.Paste")
			(roundrect_rratio 0.25)
			(net 18 "VDD")
			(pintype "passive")
		)
	)
	(footprint "antmicro-footprints:FB_0805_2012Metric"
		(layer "F.Cu")
		(at 138.2 85.2)
		(descr "FERRITE BEAD 0805")
		(tags "FERRITE BEAD 0805")
		(property "Reference" "FB2"
			(at 1.81 0.41 0)
			(layer "F.SilkS")
			(effects
				(font
					(size 0.7 0.7)
					(thickness 0.15)
				)
				(justify left bottom)
			)
		)
		(property "Value" "FB_220Z_1.5A_WE-CBF_0805"
			(at 0 1.8 0)
			(layer "F.Fab")
			(hide yes)
			(effects
				(font
					(size 0.7 0.7)
					(thickness 0.15)
				)
				(justify left bottom)
			)
		)
		(property "Description" "Ferrite Bead, 0805 [2012 Metric], 220 ohm, 2 A, WE-CBF, 0.05 ohm, ± 25%, High Current"
			(at 0 0 0)
			(layer "F.Fab")
			(hide yes)
			(effects
				(font
					(size 1.27 1.27)
					(thickness 0.15)
				)
			)
		)
		(property "Author" "Antmicro"
			(at 0 0 0)
			(layer "F.Fab")
			(hide yes)
			(effects
				(font
					(size 1 1)
					(thickness 0.15)
				)
			)
		)
		(property "Current" "1.5A"
			(at 0 0 0)
			(layer "F.Fab")
			(hide yes)
			(effects
				(font
					(size 1 1)
					(thickness 0.15)
				)
			)
		)
		(property "License" "Apache-2.0"
			(at 0 0 0)
			(layer "F.Fab")
			(hide yes)
			(effects
				(font
					(size 1 1)
					(thickness 0.15)
				)
			)
		)
		(property "MPN" "742792022"
			(at 0 0 0)
			(layer "F.Fab")
			(hide yes)
			(effects
				(font
					(size 1 1)
					(thickness 0.15)
				)
			)
		)
		(property "Manufacturer" "Würth Elektronik"
			(at 0 0 0)
			(layer "F.Fab")
			(hide yes)
			(effects
				(font
					(size 1 1)
					(thickness 0.15)
				)
			)
		)
		(property "Public" "False"
			(at 0 0 0)
			(layer "F.Fab")
			(hide yes)
			(effects
				(font
					(size 1 1)
					(thickness 0.15)
				)
			)
		)
		(property "Val" "220Z/1.5A"
			(at 0 0 0)
			(layer "F.Fab")
			(hide yes)
			(effects
				(font
					(size 1 1)
					(thickness 0.15)
				)
			)
		)
		(sheetname "DDR5")
		(sheetfile "ddr5.kicad_sch")
		(attr smd)
		(fp_line
			(start -0.319 0.698)
			(end 0.281 0.698)
			(stroke
				(width 0.15)
				(type solid)
			)
			(layer "F.SilkS")
		)
		(fp_line
			(start -0.299 -0.698)
			(end 0.299 -0.698)
			(stroke
				(width 0.15)
				(type solid)
			)
			(layer "F.SilkS")
		)
		(fp_rect
			(start 1.95 -0.9)
			(end -1.95 0.9)
			(stroke
				(width 0.05)
				(type default)
			)
			(fill no)
			(layer "F.CrtYd")
		)
		(fp_line
			(start -0.948 -0.681)
			(end 0.948 -0.681)
			(stroke
				(width 0.15)
				(type solid)
			)
			(layer "F.Fab")
		)
		(fp_line
			(start -0.948 -0.676)
			(end -0.948 0.676)
			(stroke
				(width 0.15)
				(type solid)
			)
			(layer "F.Fab")
		)
		(fp_line
			(start -0.948 0.681)
			(end 0.948 0.681)
			(stroke
				(width 0.15)
				(type solid)
			)
			(layer "F.Fab")
		)
		(fp_line
			(start 0.948 -0.676)
			(end 0.948 0.676)
			(stroke
				(width 0.15)
				(type solid)
			)
			(layer "F.Fab")
		)
		(pad "1" smd roundrect
			(at -1.1 0)
			(size 1.2 1.3)
			(layers "F.Cu" "F.Mask" "F.Paste")
			(roundrect_rratio 0.25)
			(net 50 "1V8_SYS")
			(pintype "passive")
		)
		(pad "2" smd roundrect
			(at 1.1 0)
			(size 1.2 1.3)
			(layers "F.Cu" "F.Mask" "F.Paste")
			(roundrect_rratio 0.25)
			(net 19 "VPP")
			(pintype "passive")
		)
	)
	(footprint "antmicro-footprints:FB_0805_2012Metric"
		(layer "F.Cu")
		(at 138.2 89.2)
		(descr "FERRITE BEAD 0805")
		(tags "FERRITE BEAD 0805")
		(property "Reference" "FB3"
			(at 1.81 0.41 0)
			(layer "F.SilkS")
			(effects
				(font
					(size 0.7 0.7)
					(thickness 0.15)
				)
				(justify left bottom)
			)
		)
		(property "Value" "FB_220Z_1.5A_WE-CBF_0805"
			(at 0 1.8 0)
			(layer "F.Fab")
			(hide yes)
			(effects
				(font
					(size 0.7 0.7)
					(thickness 0.15)
				)
				(justify left bottom)
			)
		)
		(property "Description" "Ferrite Bead, 0805 [2012 Metric], 220 ohm, 2 A, WE-CBF, 0.05 ohm, ± 25%, High Current"
			(at 0 0 0)
			(layer "F.Fab")
			(hide yes)
			(effects
				(font
					(size 1.27 1.27)
					(thickness 0.15)
				)
			)
		)
		(property "Author" "Antmicro"
			(at 0 0 0)
			(layer "F.Fab")
			(hide yes)
			(effects
				(font
					(size 1 1)
					(thickness 0.15)
				)
			)
		)
		(property "Current" "1.5A"
			(at 0 0 0)
			(layer "F.Fab")
			(hide yes)
			(effects
				(font
					(size 1 1)
					(thickness 0.15)
				)
			)
		)
		(property "License" "Apache-2.0"
			(at 0 0 0)
			(layer "F.Fab")
			(hide yes)
			(effects
				(font
					(size 1 1)
					(thickness 0.15)
				)
			)
		)
		(property "MPN" "742792022"
			(at 0 0 0)
			(layer "F.Fab")
			(hide yes)
			(effects
				(font
					(size 1 1)
					(thickness 0.15)
				)
			)
		)
		(property "Manufacturer" "Würth Elektronik"
			(at 0 0 0)
			(layer "F.Fab")
			(hide yes)
			(effects
				(font
					(size 1 1)
					(thickness 0.15)
				)
			)
		)
		(property "Public" "False"
			(at 0 0 0)
			(layer "F.Fab")
			(hide yes)
			(effects
				(font
					(size 1 1)
					(thickness 0.15)
				)
			)
		)
		(property "Val" "220Z/1.5A"
			(at 0 0 0)
			(layer "F.Fab")
			(hide yes)
			(effects
				(font
					(size 1 1)
					(thickness 0.15)
				)
			)
		)
		(sheetname "DDR5")
		(sheetfile "ddr5.kicad_sch")
		(attr smd)
		(fp_line
			(start -0.319 0.698)
			(end 0.281 0.698)
			(stroke
				(width 0.15)
				(type solid)
			)
			(layer "F.SilkS")
		)
		(fp_line
			(start -0.299 -0.698)
			(end 0.299 -0.698)
			(stroke
				(width 0.15)
				(type solid)
			)
			(layer "F.SilkS")
		)
		(fp_rect
			(start 1.95 -0.9)
			(end -1.95 0.9)
			(stroke
				(width 0.05)
				(type default)
			)
			(fill no)
			(layer "F.CrtYd")
		)
		(fp_line
			(start -0.948 -0.681)
			(end 0.948 -0.681)
			(stroke
				(width 0.15)
				(type solid)
			)
			(layer "F.Fab")
		)
		(fp_line
			(start -0.948 -0.676)
			(end -0.948 0.676)
			(stroke
				(width 0.15)
				(type solid)
			)
			(layer "F.Fab")
		)
		(fp_line
			(start -0.948 0.681)
			(end 0.948 0.681)
			(stroke
				(width 0.15)
				(type solid)
			)
			(layer "F.Fab")
		)
		(fp_line
			(start 0.948 -0.676)
			(end 0.948 0.676)
			(stroke
				(width 0.15)
				(type solid)
			)
			(layer "F.Fab")
		)
		(pad "1" smd roundrect
			(at -1.1 0)
			(size 1.2 1.3)
			(layers "F.Cu" "F.Mask" "F.Paste")
			(roundrect_rratio 0.25)
			(net 51 "1V1_SYS")
			(pintype "passive")
		)
		(pad "2" smd roundrect
			(at 1.1 0)
			(size 1.2 1.3)
			(layers "F.Cu" "F.Mask" "F.Paste")
			(roundrect_rratio 0.25)
			(net 2 "VDDQ")
			(pintype "passive")
		)
	)
	(footprint "antmicro-footprints:PCB-Edge_SODIMM_2x130_DDR4"
		(locked yes)
		(layer "F.Cu")
		(at 100 100)
		(property "Reference" "J1"
			(at 0 -4.2 0)
			(layer "F.SilkS")
			(hide yes)
			(effects
				(font
					(size 0.7 0.7)
					(thickness 0.15)
				)
				(justify left bottom)
			)
		)
		(property "Value" "PCB-Edge_SODIMM_2x130_DDR4"
			(at 0 1 0)
			(layer "F.Fab")
			(effects
				(font
					(size 0.7 0.7)
					(thickness 0.15)
				)
				(justify left bottom)
			)
		)
		(property "Description" "DDR SO-DIMM PCB Edge"
			(at 0 0 0)
			(layer "F.Fab")
			(hide yes)
			(effects
				(font
					(size 1.27 1.27)
					(thickness 0.15)
				)
			)
		)
		(property "Author" "Antmicro"
			(at 0 0 0)
			(layer "F.Fab")
			(hide yes)
			(effects
				(font
					(size 1 1)
					(thickness 0.15)
				)
			)
		)
		(property "License" "Apache-2.0"
			(at 0 0 0)
			(layer "F.Fab")
			(hide yes)
			(effects
				(font
					(size 1 1)
					(thickness 0.15)
				)
			)
		)
		(property "MPN" ""
			(at 0 0 0)
			(layer "F.Fab")
			(hide yes)
			(effects
				(font
					(size 1 1)
					(thickness 0.15)
				)
			)
		)
		(property "Manufacturer" ""
			(at 0 0 0)
			(layer "F.Fab")
			(hide yes)
			(effects
				(font
					(size 1 1)
					(thickness 0.15)
				)
			)
		)
		(property "Public" "False"
			(at 0 0 0)
			(layer "F.Fab")
			(hide yes)
			(effects
				(font
					(size 1 1)
					(thickness 0.15)
				)
			)
		)
		(sheetname "SODIMM")
		(sheetfile "sodim.kicad_sch")
		(attr exclude_from_pos_files exclude_from_bom)
		(fp_circle
			(center 0.6 -3.9)
			(end 0.65 -3.9)
			(stroke
				(width 0.15)
				(type solid)
			)
			(fill yes)
			(layer "F.SilkS")
		)
		(fp_line
			(start 0 -0.75)
			(end 0 -4)
			(stroke
				(width 0.15)
				(type solid)
			)
			(layer "Edge.Cuts")
		)
		(fp_line
			(start 0.75 0)
			(end 37.8 0)
			(stroke
				(width 0.15)
				(type solid)
			)
			(layer "Edge.Cuts")
		)
		(fp_line
			(start 37.8 0)
			(end 37.8 -3.5)
			(stroke
				(width 0.15)
				(type solid)
			)
			(layer "Edge.Cuts")
		)
		(fp_line
			(start 38.8 0)
			(end 38.8 -3.5)
			(stroke
				(width 0.15)
				(type solid)
			)
			(layer "Edge.Cuts")
		)
		(fp_line
			(start 38.8 0)
			(end 68.85 0)
			(stroke
				(width 0.15)
				(type solid)
			)
			(layer "Edge.Cuts")
		)
		(fp_line
			(start 69.6 -0.75)
			(end 69.6 -4)
			(stroke
				(width 0.15)
				(type solid)
			)
			(layer "Edge.Cuts")
		)
		(fp_arc
			(start 0.75 0)
			(mid 0.21967 -0.21967)
			(end 0 -0.75)
			(stroke
				(width 0.15)
				(type solid)
			)
			(layer "Edge.Cuts")
		)
		(fp_arc
			(start 37.8 -3.5)
			(mid 38.3 -4)
			(end 38.8 -3.5)
			(stroke
				(width 0.15)
				(type solid)
			)
			(layer "Edge.Cuts")
		)
		(fp_arc
			(start 69.6 -0.75)
			(mid 69.38033 -0.21967)
			(end 68.85 0)
			(stroke
				(width 0.15)
				(type solid)
			)
			(layer "Edge.Cuts")
		)
		(fp_rect
			(start 0 -4.1)
			(end 69.6 0)
			(stroke
				(width 0.05)
				(type solid)
			)
			(fill no)
			(layer "F.CrtYd")
		)
		(pad "" np_thru_hole circle
			(at 1.999 -6)
			(size 1.8 1.8)
			(drill 1.8)
			(layers "*.Cu" "*.Mask")
		)
		(pad "" np_thru_hole circle
			(at 67.599 -6)
			(size 1.8 1.8)
			(drill 1.8)
			(layers "*.Cu" "*.Mask")
		)
		(pad "1" smd rect
			(at 1.425 -1.301)
			(size 0.35 2.5)
			(layers "F.Cu" "F.Mask")
			(net 1 "GND")
			(pinfunction "1")
			(pintype "passive")
		)
		(pad "2" smd rect
			(at 1.675 -1.301)
			(size 0.35 2.5)
			(layers "B.Cu" "B.Mask")
			(net 1 "GND")
			(pinfunction "2")
			(pintype "passive")
		)
		(pad "3" smd rect
			(at 1.925 -1.301)
			(size 0.35 2.5)
			(layers "F.Cu" "F.Mask")
			(net 1 "GND")
			(pinfunction "3")
			(pintype "passive")
		)
		(pad "4" smd rect
			(at 2.173 -1.301)
			(size 0.35 2.5)
			(layers "B.Cu" "B.Mask")
			(net 1 "GND")
			(pinfunction "4")
			(pintype "passive")
		)
		(pad "5" smd rect
			(at 2.423 -1.301)
			(size 0.35 2.5)
			(layers "F.Cu" "F.Mask")
			(net 1 "GND")
			(pinfunction "5")
			(pintype "passive")
		)
		(pad "6" smd rect
			(at 2.673 -1.301)
			(size 0.35 2.5)
			(layers "B.Cu" "B.Mask")
			(net 1 "GND")
			(pinfunction "6")
			(pintype "passive")
		)
		(pad "7" smd rect
			(at 2.923 -1.301)
			(size 0.35 2.5)
			(layers "F.Cu" "F.Mask")
			(net 1 "GND")
			(pinfunction "7")
			(pintype "passive")
		)
		(pad "8" smd rect
			(at 3.173 -1.301)
			(size 0.35 2.5)
			(layers "B.Cu" "B.Mask")
			(net 1 "GND")
			(pinfunction "8")
			(pintype "passive")
		)
		(pad "9" smd rect
			(at 3.423 -1.301)
			(size 0.35 2.5)
			(layers "F.Cu" "F.Mask")
			(net 1 "GND")
			(pinfunction "9")
			(pintype "passive")
		)
		(pad "10" smd rect
			(at 3.673 -1.301)
			(size 0.35 2.5)
			(layers "B.Cu" "B.Mask")
			(net 1 "GND")
			(pinfunction "10")
			(pintype "passive")
		)
		(pad "11" smd rect
			(at 3.923 -1.301)
			(size 0.35 2.5)
			(layers "F.Cu" "F.Mask")
			(net 1 "GND")
			(pinfunction "11")
			(pintype "passive")
		)
		(pad "12" smd rect
			(at 4.174 -1.301)
			(size 0.35 2.5)
			(layers "B.Cu" "B.Mask")
			(net 1 "GND")
			(pinfunction "12")
			(pintype "passive")
		)
		(pad "13" smd rect
			(at 4.424 -1.301)
			(size 0.35 2.5)
			(layers "F.Cu" "F.Mask")
			(net 1 "GND")
			(pinfunction "13")
			(pintype "passive")
		)
		(pad "14" smd rect
			(at 4.674 -1.301)
			(size 0.35 2.5)
			(layers "B.Cu" "B.Mask")
			(net 1 "GND")
			(pinfunction "14")
			(pintype "passive")
		)
		(pad "15" smd rect
			(at 4.924 -1.301)
			(size 0.35 2.5)
			(layers "F.Cu" "F.Mask")
			(net 1 "GND")
			(pinfunction "15")
			(pintype "passive")
		)
		(pad "16" smd rect
			(at 5.174 -1.301)
			(size 0.35 2.5)
			(layers "B.Cu" "B.Mask")
			(net 1 "GND")
			(pinfunction "16")
			(pintype "passive")
		)
		(pad "17" smd rect
			(at 5.424 -1.301)
			(size 0.35 2.5)
			(layers "F.Cu" "F.Mask")
			(net 1 "GND")
			(pinfunction "17")
			(pintype "passive")
		)
		(pad "18" smd rect
			(at 5.674 -1.301)
			(size 0.35 2.5)
			(layers "B.Cu" "B.Mask")
			(net 1 "GND")
			(pinfunction "18")
			(pintype "passive")
		)
		(pad "19" smd rect
			(at 5.924 -1.301)
			(size 0.35 2.5)
			(layers "F.Cu" "F.Mask")
			(net 1 "GND")
			(pinfunction "19")
			(pintype "passive")
		)
		(pad "20" smd rect
			(at 6.174 -1.301)
			(size 0.35 2.5)
			(layers "B.Cu" "B.Mask")
			(net 1 "GND")
			(pinfunction "20")
			(pintype "passive")
		)
		(pad "21" smd rect
			(at 6.424 -1.301)
			(size 0.35 2.5)
			(layers "F.Cu" "F.Mask")
			(net 1 "GND")
			(pinfunction "21")
			(pintype "passive")
		)
		(pad "22" smd rect
			(at 6.674 -1.301)
			(size 0.35 2.5)
			(layers "B.Cu" "B.Mask")
			(net 1 "GND")
			(pinfunction "22")
			(pintype "passive")
		)
		(pad "23" smd rect
			(at 6.924 -1.301)
			(size 0.35 2.5)
			(layers "F.Cu" "F.Mask")
			(net 1 "GND")
			(pinfunction "23")
			(pintype "passive")
		)
		(pad "24" smd rect
			(at 7.174 -1.301)
			(size 0.35 2.5)
			(layers "B.Cu" "B.Mask")
			(net 1 "GND")
			(pinfunction "24")
			(pintype "passive")
		)
		(pad "25" smd rect
			(at 7.424 -1.301)
			(size 0.35 2.5)
			(layers "F.Cu" "F.Mask")
			(net 1 "GND")
			(pinfunction "25")
			(pintype "passive")
		)
		(pad "26" smd rect
			(at 7.674 -1.301)
			(size 0.35 2.5)
			(layers "B.Cu" "B.Mask")
			(net 1 "GND")
			(pinfunction "26")
			(pintype "passive")
		)
		(pad "27" smd rect
			(at 7.924 -1.301)
			(size 0.35 2.5)
			(layers "F.Cu" "F.Mask")
			(net 1 "GND")
			(pinfunction "27")
			(pintype "passive")
		)
		(pad "28" smd rect
			(at 8.175 -1.301)
			(size 0.35 2.5)
			(layers "B.Cu" "B.Mask")
			(net 1 "GND")
			(pinfunction "28")
			(pintype "passive")
		)
		(pad "29" smd rect
			(at 8.425 -1.301)
			(size 0.35 2.5)
			(layers "F.Cu" "F.Mask")
			(net 1 "GND")
			(pinfunction "29")
			(pintype "passive")
		)
		(pad "30" smd rect
			(at 8.675 -1.301)
			(size 0.35 2.5)
			(layers "B.Cu" "B.Mask")
			(net 1 "GND")
			(pinfunction "30")
			(pintype "passive")
		)
		(pad "31" smd rect
			(at 8.925 -1.301)
			(size 0.35 2.5)
			(layers "F.Cu" "F.Mask")
			(net 1 "GND")
			(pinfunction "31")
			(pintype "passive")
		)
		(pad "32" smd rect
			(at 9.175 -1.301)
			(size 0.35 2.5)
			(layers "B.Cu" "B.Mask")
			(net 1 "GND")
			(pinfunction "32")
			(pintype "passive")
		)
		(pad "33" smd rect
			(at 9.425 -1.301)
			(size 0.35 2.5)
			(layers "F.Cu" "F.Mask")
			(net 1 "GND")
			(pinfunction "33")
			(pintype "passive")
		)
		(pad "34" smd rect
			(at 9.675 -1.301)
			(size 0.35 2.5)
			(layers "B.Cu" "B.Mask")
			(net 1 "GND")
			(pinfunction "34")
			(pintype "passive")
		)
		(pad "35" smd rect
			(at 9.925 -1.301)
			(size 0.35 2.5)
			(layers "F.Cu" "F.Mask")
			(net 1 "GND")
			(pinfunction "35")
			(pintype "passive")
		)
		(pad "36" smd rect
			(at 10.175 -1.301)
			(size 0.35 2.5)
			(layers "B.Cu" "B.Mask")
			(net 1 "GND")
			(pinfunction "36")
			(pintype "passive")
		)
		(pad "37" smd rect
			(at 10.425 -1.301)
			(size 0.35 2.5)
			(layers "F.Cu" "F.Mask")
			(net 1 "GND")
			(pinfunction "37")
			(pintype "passive")
		)
		(pad "38" smd rect
			(at 10.675 -1.301)
			(size 0.35 2.5)
			(layers "B.Cu" "B.Mask")
			(net 1 "GND")
			(pinfunction "38")
			(pintype "passive")
		)
		(pad "39" smd rect
			(at 10.925 -1.301)
			(size 0.35 2.5)
			(layers "F.Cu" "F.Mask")
			(net 1 "GND")
			(pinfunction "39")
			(pintype "passive")
		)
		(pad "40" smd rect
			(at 11.175 -1.301)
			(size 0.35 2.5)
			(layers "B.Cu" "B.Mask")
			(net 1 "GND")
			(pinfunction "40")
			(pintype "passive")
		)
		(pad "41" smd rect
			(at 11.425 -1.301)
			(size 0.35 2.5)
			(layers "F.Cu" "F.Mask")
			(net 1 "GND")
			(pinfunction "41")
			(pintype "passive")
		)
		(pad "42" smd rect
			(at 11.675 -1.301)
			(size 0.35 2.5)
			(layers "B.Cu" "B.Mask")
			(net 1 "GND")
			(pinfunction "42")
			(pintype "passive")
		)
		(pad "43" smd rect
			(at 11.925 -1.301)
			(size 0.35 2.5)
			(layers "F.Cu" "F.Mask")
			(net 1 "GND")
			(pinfunction "43")
			(pintype "passive")
		)
		(pad "44" smd rect
			(at 12.175 -1.301)
			(size 0.35 2.5)
			(layers "B.Cu" "B.Mask")
			(net 1 "GND")
			(pinfunction "44")
			(pintype "passive")
		)
		(pad "45" smd rect
			(at 12.425 -1.301)
			(size 0.35 2.5)
			(layers "F.Cu" "F.Mask")
			(net 1 "GND")
			(pinfunction "45")
			(pintype "passive")
		)
		(pad "46" smd rect
			(at 12.675 -1.301)
			(size 0.35 2.5)
			(layers "B.Cu" "B.Mask")
			(net 1 "GND")
			(pinfunction "46")
			(pintype "passive")
		)
		(pad "47" smd rect
			(at 12.925 -1.301)
			(size 0.35 2.5)
			(layers "F.Cu" "F.Mask")
			(net 1 "GND")
			(pinfunction "47")
			(pintype "passive")
		)
		(pad "48" smd rect
			(at 13.175 -1.301)
			(size 0.35 2.5)
			(layers "B.Cu" "B.Mask")
			(net 1 "GND")
			(pinfunction "48")
			(pintype "passive")
		)
		(pad "49" smd rect
			(at 13.425 -1.301)
			(size 0.35 2.5)
			(layers "F.Cu" "F.Mask")
			(net 1 "GND")
			(pinfunction "49")
			(pintype "passive")
		)
		(pad "50" smd rect
			(at 13.675 -1.301)
			(size 0.35 2.5)
			(layers "B.Cu" "B.Mask")
			(net 1 "GND")
			(pinfunction "50")
			(pintype "passive")
		)
		(pad "51" smd rect
			(at 13.925 -1.301)
			(size 0.35 2.5)
			(layers "F.Cu" "F.Mask")
			(net 70 "unconnected-(J1-Pad51)")
			(pinfunction "51")
			(pintype "passive+no_connect")
		)
		(pad "52" smd rect
			(at 14.175 -1.301)
			(size 0.35 2.5)
			(layers "B.Cu" "B.Mask")
			(net 71 "unconnected-(J1-Pad52)")
			(pinfunction "52")
			(pintype "passive+no_connect")
		)
		(pad "53" smd rect
			(at 14.425 -1.301)
			(size 0.35 2.5)
			(layers "F.Cu" "F.Mask")
			(net 72 "unconnected-(J1-Pad53)")
			(pinfunction "53")
			(pintype "passive+no_connect")
		)
		(pad "54" smd rect
			(at 14.675 -1.301)
			(size 0.35 2.5)
			(layers "B.Cu" "B.Mask")
			(net 73 "unconnected-(J1-Pad54)")
			(pinfunction "54")
			(pintype "passive+no_connect")
		)
		(pad "55" smd rect
			(at 14.925 -1.301)
			(size 0.35 2.5)
			(layers "F.Cu" "F.Mask")
			(net 74 "unconnected-(J1-Pad55)")
			(pinfunction "55")
			(pintype "passive+no_connect")
		)
		(pad "56" smd rect
			(at 15.175 -1.301)
			(size 0.35 2.5)
			(layers "B.Cu" "B.Mask")
			(net 75 "unconnected-(J1-Pad56)")
			(pinfunction "56")
			(pintype "passive+no_connect")
		)
		(pad "57" smd rect
			(at 15.425 -1.301)
			(size 0.35 2.5)
			(layers "F.Cu" "F.Mask")
			(net 76 "unconnected-(J1-Pad57)")
			(pinfunction "57")
			(pintype "passive+no_connect")
		)
		(pad "58" smd rect
			(at 15.675 -1.301)
			(size 0.35 2.5)
			(layers "B.Cu" "B.Mask")
			(net 77 "unconnected-(J1-Pad58)")
			(pinfunction "58")
			(pintype "passive+no_connect")
		)
		(pad "59" smd rect
			(at 15.925 -1.301)
			(size 0.35 2.5)
			(layers "F.Cu" "F.Mask")
			(net 78 "unconnected-(J1-Pad59)")
			(pinfunction "59")
			(pintype "passive+no_connect")
		)
		(pad "60" smd rect
			(at 16.175 -1.301)
			(size 0.35 2.5)
			(layers "B.Cu" "B.Mask")
			(net 79 "unconnected-(J1-Pad60)")
			(pinfunction "60")
			(pintype "passive+no_connect")
		)
		(pad "61" smd rect
			(at 16.425 -1.301)
			(size 0.35 2.5)
			(layers "F.Cu" "F.Mask")
			(net 80 "unconnected-(J1-Pad61)")
			(pinfunction "61")
			(pintype "passive+no_connect")
		)
		(pad "62" smd rect
			(at 16.675 -1.301)
			(size 0.35 2.5)
			(layers "B.Cu" "B.Mask")
			(net 81 "unconnected-(J1-Pad62)")
			(pinfunction "62")
			(pintype "passive+no_connect")
		)
		(pad "63" smd rect
			(at 16.925 -1.301)
			(size 0.35 2.5)
			(layers "F.Cu" "F.Mask")
			(net 82 "unconnected-(J1-Pad63)")
			(pinfunction "63")
			(pintype "passive+no_connect")
		)
		(pad "64" smd rect
			(at 17.175 -1.301)
			(size 0.35 2.5)
			(layers "B.Cu" "B.Mask")
			(net 83 "unconnected-(J1-Pad64)")
			(pinfunction "64")
			(pintype "passive+no_connect")
		)
		(pad "65" smd rect
			(at 17.425 -1.301)
			(size 0.35 2.5)
			(layers "F.Cu" "F.Mask")
			(net 84 "unconnected-(J1-Pad65)")
			(pinfunction "65")
			(pintype "passive+no_connect")
		)
		(pad "66" smd rect
			(at 17.675 -1.301)
			(size 0.35 2.5)
			(layers "B.Cu" "B.Mask")
			(net 85 "unconnected-(J1-Pad66)")
			(pinfunction "66")
			(pintype "passive+no_connect")
		)
		(pad "67" smd rect
			(at 17.925 -1.301)
			(size 0.35 2.5)
			(layers "F.Cu" "F.Mask")
			(net 86 "unconnected-(J1-Pad67)")
			(pinfunction "67")
			(pintype "passive+no_connect")
		)
		(pad "68" smd rect
			(at 18.175 -1.301)
			(size 0.35 2.5)
			(layers "B.Cu" "B.Mask")
			(net 87 "unconnected-(J1-Pad68)")
			(pinfunction "68")
			(pintype "passive+no_connect")
		)
		(pad "69" smd rect
			(at 18.425 -1.301)
			(size 0.35 2.5)
			(layers "F.Cu" "F.Mask")
			(net 88 "unconnected-(J1-Pad69)")
			(pinfunction "69")
			(pintype "passive+no_connect")
		)
		(pad "70" smd rect
			(at 18.675 -1.301)
			(size 0.35 2.5)
			(layers "B.Cu" "B.Mask")
			(net 89 "unconnected-(J1-Pad70)")
			(pinfunction "70")
			(pintype "passive+no_connect")
		)
		(pad "71" smd rect
			(at 18.925 -1.301)
			(size 0.35 2.5)
			(layers "F.Cu" "F.Mask")
			(net 90 "unconnected-(J1-Pad71)")
			(pinfunction "71")
			(pintype "passive+no_connect")
		)
		(pad "72" smd rect
			(at 19.175 -1.301)
			(size 0.35 2.5)
			(layers "B.Cu" "B.Mask")
			(net 91 "unconnected-(J1-Pad72)")
			(pinfunction "72")
			(pintype "passive+no_connect")
		)
		(pad "73" smd rect
			(at 19.425 -1.301)
			(size 0.35 2.5)
			(layers "F.Cu" "F.Mask")
			(net 92 "unconnected-(J1-Pad73)")
			(pinfunction "73")
			(pintype "passive+no_connect")
		)
		(pad "74" smd rect
			(at 19.675 -1.301)
			(size 0.35 2.5)
			(layers "B.Cu" "B.Mask")
			(net 93 "unconnected-(J1-Pad74)")
			(pinfunction "74")
			(pintype "passive+no_connect")
		)
		(pad "75" smd rect
			(at 19.925 -1.301)
			(size 0.35 2.5)
			(layers "F.Cu" "F.Mask")
			(net 94 "unconnected-(J1-Pad75)")
			(pinfunction "75")
			(pintype "passive+no_connect")
		)
		(pad "76" smd rect
			(at 20.175 -1.301)
			(size 0.35 2.5)
			(layers "B.Cu" "B.Mask")
			(net 95 "unconnected-(J1-Pad76)")
			(pinfunction "76")
			(pintype "passive+no_connect")
		)
		(pad "77" smd rect
			(at 20.425 -1.301)
			(size 0.35 2.5)
			(layers "F.Cu" "F.Mask")
			(net 96 "unconnected-(J1-Pad77)")
			(pinfunction "77")
			(pintype "passive+no_connect")
		)
		(pad "78" smd rect
			(at 20.675 -1.301)
			(size 0.35 2.5)
			(layers "B.Cu" "B.Mask")
			(net 97 "unconnected-(J1-Pad78)")
			(pinfunction "78")
			(pintype "passive+no_connect")
		)
		(pad "79" smd rect
			(at 20.925 -1.301)
			(size 0.35 2.5)
			(layers "F.Cu" "F.Mask")
			(net 98 "unconnected-(J1-Pad79)")
			(pinfunction "79")
			(pintype "passive+no_connect")
		)
		(pad "80" smd rect
			(at 21.175 -1.301)
			(size 0.35 2.5)
			(layers "B.Cu" "B.Mask")
			(net 99 "unconnected-(J1-Pad80)")
			(pinfunction "80")
			(pintype "passive+no_connect")
		)
		(pad "81" smd rect
			(at 21.425 -1.301)
			(size 0.35 2.5)
			(layers "F.Cu" "F.Mask")
			(net 100 "unconnected-(J1-Pad81)")
			(pinfunction "81")
			(pintype "passive+no_connect")
		)
		(pad "82" smd rect
			(at 21.675 -1.301)
			(size 0.35 2.5)
			(layers "B.Cu" "B.Mask")
			(net 101 "unconnected-(J1-Pad82)")
			(pinfunction "82")
			(pintype "passive+no_connect")
		)
		(pad "83" smd rect
			(at 21.925 -1.301)
			(size 0.35 2.5)
			(layers "F.Cu" "F.Mask")
			(net 102 "unconnected-(J1-Pad83)")
			(pinfunction "83")
			(pintype "passive+no_connect")
		)
		(pad "84" smd rect
			(at 22.175 -1.301)
			(size 0.35 2.5)
			(layers "B.Cu" "B.Mask")
			(net 103 "unconnected-(J1-Pad84)")
			(pinfunction "84")
			(pintype "passive+no_connect")
		)
		(pad "85" smd rect
			(at 22.425 -1.301)
			(size 0.35 2.5)
			(layers "F.Cu" "F.Mask")
			(net 104 "unconnected-(J1-Pad85)")
			(pinfunction "85")
			(pintype "passive+no_connect")
		)
		(pad "86" smd rect
			(at 22.675 -1.301)
			(size 0.35 2.5)
			(layers "B.Cu" "B.Mask")
			(net 105 "unconnected-(J1-Pad86)")
			(pinfunction "86")
			(pintype "passive+no_connect")
		)
		(pad "87" smd rect
			(at 22.925 -1.301)
			(size 0.35 2.5)
			(layers "F.Cu" "F.Mask")
			(net 106 "unconnected-(J1-Pad87)")
			(pinfunction "87")
			(pintype "passive+no_connect")
		)
		(pad "88" smd rect
			(at 23.175 -1.301)
			(size 0.35 2.5)
			(layers "B.Cu" "B.Mask")
			(net 107 "unconnected-(J1-Pad88)")
			(pinfunction "88")
			(pintype "passive+no_connect")
		)
		(pad "89" smd rect
			(at 23.425 -1.301)
			(size 0.35 2.5)
			(layers "F.Cu" "F.Mask")
			(net 108 "unconnected-(J1-Pad89)")
			(pinfunction "89")
			(pintype "passive+no_connect")
		)
		(pad "90" smd rect
			(at 23.675 -1.301)
			(size 0.35 2.5)
			(layers "B.Cu" "B.Mask")
			(net 109 "unconnected-(J1-Pad90)")
			(pinfunction "90")
			(pintype "passive+no_connect")
		)
		(pad "91" smd rect
			(at 23.925 -1.301)
			(size 0.35 2.5)
			(layers "F.Cu" "F.Mask")
			(net 110 "unconnected-(J1-Pad91)")
			(pinfunction "91")
			(pintype "passive+no_connect")
		)
		(pad "92" smd rect
			(at 24.175 -1.301)
			(size 0.35 2.5)
			(layers "B.Cu" "B.Mask")
			(net 111 "unconnected-(J1-Pad92)")
			(pinfunction "92")
			(pintype "passive+no_connect")
		)
		(pad "93" smd rect
			(at 24.425 -1.301)
			(size 0.35 2.5)
			(layers "F.Cu" "F.Mask")
			(net 51 "1V1_SYS")
			(pinfunction "93")
			(pintype "passive")
		)
		(pad "94" smd rect
			(at 24.675 -1.301)
			(size 0.35 2.5)
			(layers "B.Cu" "B.Mask")
			(net 112 "unconnected-(J1-Pad94)")
			(pinfunction "94")
			(pintype "passive+no_connect")
		)
		(pad "95" smd rect
			(at 24.925 -1.301)
			(size 0.35 2.5)
			(layers "F.Cu" "F.Mask")
			(net 51 "1V1_SYS")
			(pinfunction "95")
			(pintype "passive")
		)
		(pad "96" smd rect
			(at 25.175 -1.301)
			(size 0.35 2.5)
			(layers "B.Cu" "B.Mask")
			(net 113 "unconnected-(J1-Pad96)")
			(pinfunction "96")
			(pintype "passive+no_connect")
		)
		(pad "97" smd rect
			(at 25.425 -1.301)
			(size 0.35 2.5)
			(layers "F.Cu" "F.Mask")
			(net 51 "1V1_SYS")
			(pinfunction "97")
			(pintype "passive")
		)
		(pad "98" smd rect
			(at 25.675 -1.301)
			(size 0.35 2.5)
			(layers "B.Cu" "B.Mask")
			(net 114 "unconnected-(J1-Pad98)")
			(pinfunction "98")
			(pintype "passive+no_connect")
		)
		(pad "99" smd rect
			(at 25.925 -1.301)
			(size 0.35 2.5)
			(layers "F.Cu" "F.Mask")
			(net 51 "1V1_SYS")
			(pinfunction "99")
			(pintype "passive")
		)
		(pad "100" smd rect
			(at 26.175 -1.301)
			(size 0.35 2.5)
			(layers "B.Cu" "B.Mask")
			(net 115 "unconnected-(J1-Pad100)")
			(pinfunction "100")
			(pintype "passive+no_connect")
		)
		(pad "101" smd rect
			(at 26.425 -1.301)
			(size 0.35 2.5)
			(layers "F.Cu" "F.Mask")
			(net 51 "1V1_SYS")
			(pinfunction "101")
			(pintype "passive")
		)
		(pad "102" smd rect
			(at 26.675 -1.301)
			(size 0.35 2.5)
			(layers "B.Cu" "B.Mask")
			(net 116 "unconnected-(J1-Pad102)")
			(pinfunction "102")
			(pintype "passive+no_connect")
		)
		(pad "103" smd rect
			(at 26.925 -1.301)
			(size 0.35 2.5)
			(layers "F.Cu" "F.Mask")
			(net 51 "1V1_SYS")
			(pinfunction "103")
			(pintype "passive")
		)
		(pad "104" smd rect
			(at 27.175 -1.301)
			(size 0.35 2.5)
			(layers "B.Cu" "B.Mask")
			(net 117 "unconnected-(J1-Pad104)")
			(pinfunction "104")
			(pintype "passive+no_connect")
		)
		(pad "105" smd rect
			(at 27.425 -1.301)
			(size 0.35 2.5)
			(layers "F.Cu" "F.Mask")
			(net 51 "1V1_SYS")
			(pinfunction "105")
			(pintype "passive")
		)
		(pad "106" smd rect
			(at 27.675 -1.301)
			(size 0.35 2.5)
			(layers "B.Cu" "B.Mask")
			(net 118 "unconnected-(J1-Pad106)")
			(pinfunction "106")
			(pintype "passive+no_connect")
		)
		(pad "107" smd rect
			(at 27.925 -1.301)
			(size 0.35 2.5)
			(layers "F.Cu" "F.Mask")
			(net 51 "1V1_SYS")
			(pinfunction "107")
			(pintype "passive")
		)
		(pad "108" smd rect
			(at 28.175 -1.301)
			(size 0.35 2.5)
			(layers "B.Cu" "B.Mask")
			(net 119 "unconnected-(J1-Pad108)")
			(pinfunction "108")
			(pintype "passive+no_connect")
		)
		(pad "109" smd rect
			(at 28.425 -1.301)
			(size 0.35 2.5)
			(layers "F.Cu" "F.Mask")
			(net 120 "unconnected-(J1-Pad109)")
			(pinfunction "109")
			(pintype "passive+no_connect")
		)
		(pad "110" smd rect
			(at 28.675 -1.301)
			(size 0.35 2.5)
			(layers "B.Cu" "B.Mask")
			(net 121 "unconnected-(J1-Pad110)")
			(pinfunction "110")
			(pintype "passive+no_connect")
		)
		(pad "111" smd rect
			(at 28.925 -1.301)
			(size 0.35 2.5)
			(layers "F.Cu" "F.Mask")
			(net 122 "unconnected-(J1-Pad111)")
			(pinfunction "111")
			(pintype "passive+no_connect")
		)
		(pad "112" smd rect
			(at 29.175 -1.301)
			(size 0.35 2.5)
			(layers "B.Cu" "B.Mask")
			(net 123 "unconnected-(J1-Pad112)")
			(pinfunction "112")
			(pintype "passive+no_connect")
		)
		(pad "113" smd rect
			(at 29.425 -1.301)
			(size 0.35 2.5)
			(layers "F.Cu" "F.Mask")
			(net 124 "unconnected-(J1-Pad113)")
			(pinfunction "113")
			(pintype "passive+no_connect")
		)
		(pad "114" smd rect
			(at 29.675 -1.301)
			(size 0.35 2.5)
			(layers "B.Cu" "B.Mask")
			(net 125 "unconnected-(J1-Pad114)")
			(pinfunction "114")
			(pintype "passive+no_connect")
		)
		(pad "115" smd rect
			(at 29.925 -1.301)
			(size 0.35 2.5)
			(layers "F.Cu" "F.Mask")
			(net 126 "unconnected-(J1-Pad115)")
			(pinfunction "115")
			(pintype "passive+no_connect")
		)
		(pad "116" smd rect
			(at 30.175 -1.301)
			(size 0.35 2.5)
			(layers "B.Cu" "B.Mask")
			(net 50 "1V8_SYS")
			(pinfunction "116")
			(pintype "passive")
		)
		(pad "117" smd rect
			(at 30.425 -1.301)
			(size 0.35 2.5)
			(layers "F.Cu" "F.Mask")
			(net 127 "unconnected-(J1-Pad117)")
			(pinfunction "117")
			(pintype "passive+no_connect")
		)
		(pad "118" smd rect
			(at 30.675 -1.301)
			(size 0.35 2.5)
			(layers "B.Cu" "B.Mask")
			(net 50 "1V8_SYS")
			(pinfunction "118")
			(pintype "passive")
		)
		(pad "119" smd rect
			(at 30.925 -1.301)
			(size 0.35 2.5)
			(layers "F.Cu" "F.Mask")
			(net 128 "unconnected-(J1-Pad119)")
			(pinfunction "119")
			(pintype "passive+no_connect")
		)
		(pad "120" smd rect
			(at 31.175 -1.301)
			(size 0.35 2.5)
			(layers "B.Cu" "B.Mask")
			(net 50 "1V8_SYS")
			(pinfunction "120")
			(pintype "passive")
		)
		(pad "121" smd rect
			(at 31.425 -1.301)
			(size 0.35 2.5)
			(layers "F.Cu" "F.Mask")
			(net 129 "unconnected-(J1-Pad121)")
			(pinfunction "121")
			(pintype "passive+no_connect")
		)
		(pad "122" smd rect
			(at 31.675 -1.301)
			(size 0.35 2.5)
			(layers "B.Cu" "B.Mask")
			(net 50 "1V8_SYS")
			(pinfunction "122")
			(pintype "passive")
		)
		(pad "123" smd rect
			(at 31.925 -1.301)
			(size 0.35 2.5)
			(layers "F.Cu" "F.Mask")
			(net 130 "unconnected-(J1-Pad123)")
			(pinfunction "123")
			(pintype "passive+no_connect")
		)
		(pad "124" smd rect
			(at 32.173 -1.301)
			(size 0.35 2.5)
			(layers "B.Cu" "B.Mask")
			(net 50 "1V8_SYS")
			(pinfunction "124")
			(pintype "passive")
		)
		(pad "125" smd rect
			(at 32.423 -1.301)
			(size 0.35 2.5)
			(layers "F.Cu" "F.Mask")
			(net 131 "unconnected-(J1-Pad125)")
			(pinfunction "125")
			(pintype "passive+no_connect")
		)
		(pad "126" smd rect
			(at 32.673 -1.301)
			(size 0.35 2.5)
			(layers "B.Cu" "B.Mask")
			(net 132 "unconnected-(J1-Pad126)")
			(pinfunction "126")
			(pintype "passive+no_connect")
		)
		(pad "127" smd rect
			(at 32.923 -1.301)
			(size 0.35 2.5)
			(layers "F.Cu" "F.Mask")
			(net 12 "SDA")
			(pinfunction "127")
			(pintype "passive")
		)
		(pad "128" smd rect
			(at 33.173 -1.301)
			(size 0.35 2.5)
			(layers "B.Cu" "B.Mask")
			(net 133 "unconnected-(J1-Pad128)")
			(pinfunction "128")
			(pintype "passive+no_connect")
		)
		(pad "129" smd rect
			(at 33.423 -1.301)
			(size 0.35 2.5)
			(layers "F.Cu" "F.Mask")
			(net 13 "SCL")
			(pinfunction "129")
			(pintype "passive")
		)
		(pad "130" smd rect
			(at 33.673 -1.301)
			(size 0.35 2.5)
			(layers "B.Cu" "B.Mask")
			(net 134 "unconnected-(J1-Pad130)")
			(pinfunction "130")
			(pintype "passive+no_connect")
		)
		(pad "131" smd rect
			(at 33.923 -1.301)
			(size 0.35 2.5)
			(layers "F.Cu" "F.Mask")
			(net 135 "unconnected-(J1-Pad131)")
			(pinfunction "131")
			(pintype "passive+no_connect")
		)
		(pad "132" smd rect
			(at 34.173 -1.301)
			(size 0.35 2.5)
			(layers "B.Cu" "B.Mask")
			(net 136 "unconnected-(J1-Pad132)")
			(pinfunction "132")
			(pintype "passive+no_connect")
		)
		(pad "133" smd rect
			(at 34.423 -1.301)
			(size 0.35 2.5)
			(layers "F.Cu" "F.Mask")
			(net 137 "unconnected-(J1-Pad133)")
			(pinfunction "133")
			(pintype "passive+no_connect")
		)
		(pad "134" smd rect
			(at 34.673 -1.301)
			(size 0.35 2.5)
			(layers "B.Cu" "B.Mask")
			(net 138 "unconnected-(J1-Pad134)")
			(pinfunction "134")
			(pintype "passive+no_connect")
		)
		(pad "135" smd rect
			(at 34.923 -1.301)
			(size 0.35 2.5)
			(layers "F.Cu" "F.Mask")
			(net 139 "unconnected-(J1-Pad135)")
			(pinfunction "135")
			(pintype "passive+no_connect")
		)
		(pad "136" smd rect
			(at 35.173 -1.301)
			(size 0.35 2.5)
			(layers "B.Cu" "B.Mask")
			(net 140 "unconnected-(J1-Pad136)")
			(pinfunction "136")
			(pintype "passive+no_connect")
		)
		(pad "137" smd rect
			(at 35.423 -1.301)
			(size 0.35 2.5)
			(layers "F.Cu" "F.Mask")
			(net 141 "unconnected-(J1-Pad137)")
			(pinfunction "137")
			(pintype "passive+no_connect")
		)
		(pad "138" smd rect
			(at 35.673 -1.301)
			(size 0.35 2.5)
			(layers "B.Cu" "B.Mask")
			(net 142 "unconnected-(J1-Pad138)")
			(pinfunction "138")
			(pintype "passive+no_connect")
		)
		(pad "139" smd rect
			(at 35.923 -1.301)
			(size 0.35 2.5)
			(layers "F.Cu" "F.Mask")
			(net 143 "unconnected-(J1-Pad139)")
			(pinfunction "139")
			(pintype "passive+no_connect")
		)
		(pad "140" smd rect
			(at 36.173 -1.301)
			(size 0.35 2.5)
			(layers "B.Cu" "B.Mask")
			(net 144 "unconnected-(J1-Pad140)")
			(pinfunction "140")
			(pintype "passive+no_connect")
		)
		(pad "141" smd rect
			(at 36.423 -1.301)
			(size 0.35 2.5)
			(layers "F.Cu" "F.Mask")
			(net 145 "unconnected-(J1-Pad141)")
			(pinfunction "141")
			(pintype "passive+no_connect")
		)
		(pad "142" smd rect
			(at 36.673 -1.301)
			(size 0.35 2.5)
			(layers "B.Cu" "B.Mask")
			(net 146 "unconnected-(J1-Pad142)")
			(pinfunction "142")
			(pintype "passive+no_connect")
		)
		(pad "143" smd rect
			(at 36.923 -1.301)
			(size 0.35 2.5)
			(layers "F.Cu" "F.Mask")
			(net 147 "unconnected-(J1-Pad143)")
			(pinfunction "143")
			(pintype "passive+no_connect")
		)
		(pad "144" smd rect
			(at 37.173 -1.301)
			(size 0.35 2.5)
			(layers "B.Cu" "B.Mask")
			(net 148 "unconnected-(J1-Pad144)")
			(pinfunction "144")
			(pintype "passive+no_connect")
		)
		(pad "145" smd rect
			(at 39.423 -1.301)
			(size 0.35 2.5)
			(layers "F.Cu" "F.Mask")
			(net 149 "unconnected-(J1-Pad145)")
			(pinfunction "145")
			(pintype "passive+no_connect")
		)
		(pad "146" smd rect
			(at 39.673 -1.301)
			(size 0.35 2.5)
			(layers "B.Cu" "B.Mask")
			(net 150 "unconnected-(J1-Pad146)")
			(pinfunction "146")
			(pintype "passive+no_connect")
		)
		(pad "147" smd rect
			(at 39.923 -1.301)
			(size 0.35 2.5)
			(layers "F.Cu" "F.Mask")
			(net 151 "unconnected-(J1-Pad147)")
			(pinfunction "147")
			(pintype "passive+no_connect")
		)
		(pad "148" smd rect
			(at 40.173 -1.301)
			(size 0.35 2.5)
			(layers "B.Cu" "B.Mask")
			(net 152 "unconnected-(J1-Pad148)")
			(pinfunction "148")
			(pintype "passive+no_connect")
		)
		(pad "149" smd rect
			(at 40.423 -1.301)
			(size 0.35 2.5)
			(layers "F.Cu" "F.Mask")
			(net 153 "unconnected-(J1-Pad149)")
			(pinfunction "149")
			(pintype "passive+no_connect")
		)
		(pad "150" smd rect
			(at 40.673 -1.301)
			(size 0.35 2.5)
			(layers "B.Cu" "B.Mask")
			(net 154 "unconnected-(J1-Pad150)")
			(pinfunction "150")
			(pintype "passive+no_connect")
		)
		(pad "151" smd rect
			(at 40.923 -1.301)
			(size 0.35 2.5)
			(layers "F.Cu" "F.Mask")
			(net 155 "unconnected-(J1-Pad151)")
			(pinfunction "151")
			(pintype "passive+no_connect")
		)
		(pad "152" smd rect
			(at 41.173 -1.301)
			(size 0.35 2.5)
			(layers "B.Cu" "B.Mask")
			(net 156 "unconnected-(J1-Pad152)")
			(pinfunction "152")
			(pintype "passive+no_connect")
		)
		(pad "153" smd rect
			(at 41.423 -1.301)
			(size 0.35 2.5)
			(layers "F.Cu" "F.Mask")
			(net 157 "unconnected-(J1-Pad153)")
			(pinfunction "153")
			(pintype "passive+no_connect")
		)
		(pad "154" smd rect
			(at 41.673 -1.301)
			(size 0.35 2.5)
			(layers "B.Cu" "B.Mask")
			(net 1 "GND")
			(pinfunction "154")
			(pintype "passive")
		)
		(pad "155" smd rect
			(at 41.923 -1.301)
			(size 0.35 2.5)
			(layers "F.Cu" "F.Mask")
			(net 158 "unconnected-(J1-Pad155)")
			(pinfunction "155")
			(pintype "passive+no_connect")
		)
		(pad "156" smd rect
			(at 42.173 -1.301)
			(size 0.35 2.5)
			(layers "B.Cu" "B.Mask")
			(net 56 "CAI")
			(pinfunction "156")
			(pintype "passive")
		)
		(pad "157" smd rect
			(at 42.423 -1.301)
			(size 0.35 2.5)
			(layers "F.Cu" "F.Mask")
			(net 159 "unconnected-(J1-Pad157)")
			(pinfunction "157")
			(pintype "passive+no_connect")
		)
		(pad "158" smd rect
			(at 42.673 -1.301)
			(size 0.35 2.5)
			(layers "B.Cu" "B.Mask")
			(net 53 "ALERT_N")
			(pinfunction "158")
			(pintype "passive")
		)
		(pad "159" smd rect
			(at 42.923 -1.301)
			(size 0.35 2.5)
			(layers "F.Cu" "F.Mask")
			(net 160 "unconnected-(J1-Pad159)")
			(pinfunction "159")
			(pintype "passive+no_connect")
		)
		(pad "160" smd rect
			(at 43.173 -1.301)
			(size 0.35 2.5)
			(layers "B.Cu" "B.Mask")
			(net 57 "MIR")
			(pinfunction "160")
			(pintype "passive")
		)
		(pad "161" smd rect
			(at 43.423 -1.301)
			(size 0.35 2.5)
			(layers "F.Cu" "F.Mask")
			(net 1 "GND")
			(pinfunction "161")
			(pintype "passive")
		)
		(pad "162" smd rect
			(at 43.673 -1.301)
			(size 0.35 2.5)
			(layers "B.Cu" "B.Mask")
			(net 17 "CS_N")
			(pinfunction "162")
			(pintype "passive")
		)
		(pad "163" smd rect
			(at 43.923 -1.301)
			(size 0.35 2.5)
			(layers "F.Cu" "F.Mask")
			(net 34 "CA12")
			(pinfunction "163")
			(pintype "passive")
		)
		(pad "164" smd rect
			(at 44.173 -1.301)
			(size 0.35 2.5)
			(layers "B.Cu" "B.Mask")
			(net 39 "TDQS_N")
			(pinfunction "164")
			(pintype "passive")
		)
		(pad "165" smd rect
			(at 44.423 -1.301)
			(size 0.35 2.5)
			(layers "F.Cu" "F.Mask")
			(net 32 "CA10")
			(pinfunction "165")
			(pintype "passive")
		)
		(pad "166" smd rect
			(at 44.673 -1.301)
			(size 0.35 2.5)
			(layers "B.Cu" "B.Mask")
			(net 37 "TDQS_P")
			(pinfunction "166")
			(pintype "passive")
		)
		(pad "167" smd rect
			(at 44.923 -1.301)
			(size 0.35 2.5)
			(layers "F.Cu" "F.Mask")
			(net 43 "CA8")
			(pinfunction "167")
			(pintype "passive")
		)
		(pad "168" smd rect
			(at 45.173 -1.301)
			(size 0.35 2.5)
			(layers "B.Cu" "B.Mask")
			(net 1 "GND")
			(pinfunction "168")
			(pintype "passive")
		)
		(pad "169" smd rect
			(at 45.423 -1.301)
			(size 0.35 2.5)
			(layers "F.Cu" "F.Mask")
			(net 40 "CA6")
			(pinfunction "169")
			(pintype "passive")
		)
		(pad "170" smd rect
			(at 45.673 -1.301)
			(size 0.35 2.5)
			(layers "B.Cu" "B.Mask")
			(net 161 "unconnected-(J1-Pad170)")
			(pinfunction "170")
			(pintype "passive+no_connect")
		)
		(pad "171" smd rect
			(at 45.923 -1.301)
			(size 0.35 2.5)
			(layers "F.Cu" "F.Mask")
			(net 46 "CA2")
			(pinfunction "171")
			(pintype "passive")
		)
		(pad "172" smd rect
			(at 46.173 -1.301)
			(size 0.35 2.5)
			(layers "B.Cu" "B.Mask")
			(net 162 "unconnected-(J1-Pad172)")
			(pinfunction "172")
			(pintype "passive+no_connect")
		)
		(pad "173" smd rect
			(at 46.423 -1.301)
			(size 0.35 2.5)
			(layers "F.Cu" "F.Mask")
			(net 44 "CLK_N")
			(pinfunction "173")
			(pintype "passive")
		)
		(pad "174" smd rect
			(at 46.673 -1.301)
			(size 0.35 2.5)
			(layers "B.Cu" "B.Mask")
			(net 163 "unconnected-(J1-Pad174)")
			(pinfunction "174")
			(pintype "passive+no_connect")
		)
		(pad "175" smd rect
			(at 46.923 -1.301)
			(size 0.35 2.5)
			(layers "F.Cu" "F.Mask")
			(net 42 "CLK_P")
			(pinfunction "175")
			(pintype "passive")
		)
		(pad "176" smd rect
			(at 47.173 -1.301)
			(size 0.35 2.5)
			(layers "B.Cu" "B.Mask")
			(net 164 "unconnected-(J1-Pad176)")
			(pinfunction "176")
			(pintype "passive+no_connect")
		)
		(pad "177" smd rect
			(at 47.423 -1.301)
			(size 0.35 2.5)
			(layers "F.Cu" "F.Mask")
			(net 1 "GND")
			(pinfunction "177")
			(pintype "passive")
		)
		(pad "178" smd rect
			(at 47.673 -1.301)
			(size 0.35 2.5)
			(layers "B.Cu" "B.Mask")
			(net 29 "DQ6")
			(pinfunction "178")
			(pintype "passive")
		)
		(pad "179" smd rect
			(at 47.923 -1.301)
			(size 0.35 2.5)
			(layers "F.Cu" "F.Mask")
			(net 48 "CA4")
			(pinfunction "179")
			(pintype "passive")
		)
		(pad "180" smd rect
			(at 48.173 -1.301)
			(size 0.35 2.5)
			(layers "B.Cu" "B.Mask")
			(net 30 "DQ5")
			(pinfunction "180")
			(pintype "passive")
		)
		(pad "181" smd rect
			(at 48.423 -1.301)
			(size 0.35 2.5)
			(layers "F.Cu" "F.Mask")
			(net 24 "CA0")
			(pinfunction "181")
			(pintype "passive")
		)
		(pad "182" smd rect
			(at 48.673 -1.301)
			(size 0.35 2.5)
			(layers "B.Cu" "B.Mask")
			(net 28 "DQ7")
			(pinfunction "182")
			(pintype "passive")
		)
		(pad "183" smd rect
			(at 48.923 -1.301)
			(size 0.35 2.5)
			(layers "F.Cu" "F.Mask")
			(net 33 "CA11")
			(pinfunction "183")
			(pintype "passive")
		)
		(pad "184" smd rect
			(at 49.173 -1.301)
			(size 0.35 2.5)
			(layers "B.Cu" "B.Mask")
			(net 1 "GND")
			(pinfunction "184")
			(pintype "passive")
		)
		(pad "185" smd rect
			(at 49.423 -1.301)
			(size 0.35 2.5)
			(layers "F.Cu" "F.Mask")
			(net 35 "CA13")
			(pinfunction "185")
			(pintype "passive")
		)
		(pad "186" smd rect
			(at 49.673 -1.301)
			(size 0.35 2.5)
			(layers "B.Cu" "B.Mask")
			(net 31 "DQ4")
			(pinfunction "186")
			(pintype "passive")
		)
		(pad "187" smd rect
			(at 49.923 -1.301)
			(size 0.35 2.5)
			(layers "F.Cu" "F.Mask")
			(net 45 "CA9")
			(pinfunction "187")
			(pintype "passive")
		)
		(pad "188" smd rect
			(at 50.173 -1.301)
			(size 0.35 2.5)
			(layers "B.Cu" "B.Mask")
			(net 165 "unconnected-(J1-Pad188)")
			(pinfunction "188")
			(pintype "passive+no_connect")
		)
		(pad "189" smd rect
			(at 50.423 -1.301)
			(size 0.35 2.5)
			(layers "F.Cu" "F.Mask")
			(net 41 "CA7")
			(pinfunction "189")
			(pintype "passive")
		)
		(pad "190" smd rect
			(at 50.673 -1.301)
			(size 0.35 2.5)
			(layers "B.Cu" "B.Mask")
			(net 166 "unconnected-(J1-Pad190)")
			(pinfunction "190")
			(pintype "passive+no_connect")
		)
		(pad "191" smd rect
			(at 50.923 -1.301)
			(size 0.35 2.5)
			(layers "F.Cu" "F.Mask")
			(net 47 "CA3")
			(pinfunction "191")
			(pintype "passive")
		)
		(pad "192" smd rect
			(at 51.173 -1.301)
			(size 0.35 2.5)
			(layers "B.Cu" "B.Mask")
			(net 23 "DQ1")
			(pinfunction "192")
			(pintype "passive")
		)
		(pad "193" smd rect
			(at 51.423 -1.301)
			(size 0.35 2.5)
			(layers "F.Cu" "F.Mask")
			(net 49 "CA5")
			(pinfunction "193")
			(pintype "passive")
		)
		(pad "194" smd rect
			(at 51.673 -1.301)
			(size 0.35 2.5)
			(layers "B.Cu" "B.Mask")
			(net 20 "DQ3")
			(pinfunction "194")
			(pintype "passive")
		)
		(pad "195" smd rect
			(at 51.923 -1.301)
			(size 0.35 2.5)
			(layers "F.Cu" "F.Mask")
			(net 1 "GND")
			(pinfunction "195")
			(pintype "passive")
		)
		(pad "196" smd rect
			(at 52.173 -1.301)
			(size 0.35 2.5)
			(layers "B.Cu" "B.Mask")
			(net 21 "DQ2")
			(pinfunction "196")
			(pintype "passive")
		)
		(pad "197" smd rect
			(at 52.423 -1.301)
			(size 0.35 2.5)
			(layers "F.Cu" "F.Mask")
			(net 22 "CA1")
			(pinfunction "197")
			(pintype "passive")
		)
		(pad "198" smd rect
			(at 52.673 -1.301)
			(size 0.35 2.5)
			(layers "B.Cu" "B.Mask")
			(net 25 "DQ0")
			(pinfunction "198")
			(pintype "passive")
		)
		(pad "199" smd rect
			(at 52.923 -1.301)
			(size 0.35 2.5)
			(layers "F.Cu" "F.Mask")
			(net 27 "DQS_N")
			(pinfunction "199")
			(pintype "passive")
		)
		(pad "200" smd rect
			(at 53.173 -1.301)
			(size 0.35 2.5)
			(layers "B.Cu" "B.Mask")
			(net 1 "GND")
			(pinfunction "200")
			(pintype "passive")
		)
		(pad "201" smd rect
			(at 53.423 -1.301)
			(size 0.35 2.5)
			(layers "F.Cu" "F.Mask")
			(net 26 "DQS_P")
			(pinfunction "201")
			(pintype "passive")
		)
		(pad "202" smd rect
			(at 53.673 -1.301)
			(size 0.35 2.5)
			(layers "B.Cu" "B.Mask")
			(net 167 "unconnected-(J1-Pad202)")
			(pinfunction "202")
			(pintype "passive+no_connect")
		)
		(pad "203" smd rect
			(at 53.923 -1.301)
			(size 0.35 2.5)
			(layers "F.Cu" "F.Mask")
			(net 3 "RESET_N")
			(pinfunction "203")
			(pintype "passive")
		)
		(pad "204" smd rect
			(at 54.173 -1.301)
			(size 0.35 2.5)
			(layers "B.Cu" "B.Mask")
			(net 168 "unconnected-(J1-Pad204)")
			(pinfunction "204")
			(pintype "passive")
		)
		(pad "205" smd rect
			(at 54.423 -1.301)
			(size 0.35 2.5)
			(layers "F.Cu" "F.Mask")
			(net 54 "TEN")
			(pinfunction "205")
			(pintype "passive")
		)
		(pad "206" smd rect
			(at 54.673 -1.301)
			(size 0.35 2.5)
			(layers "B.Cu" "B.Mask")
			(net 55 "OTD_CA_A")
			(pinfunction "206")
			(pintype "passive")
		)
		(pad "207" smd rect
			(at 54.923 -1.301)
			(size 0.35 2.5)
			(layers "F.Cu" "F.Mask")
			(net 36 "LBDQS")
			(pinfunction "207")
			(pintype "passive")
		)
		(pad "208" smd rect
			(at 55.173 -1.301)
			(size 0.35 2.5)
			(layers "B.Cu" "B.Mask")
			(net 169 "unconnected-(J1-Pad208)")
			(pinfunction "208")
			(pintype "passive+no_connect")
		)
		(pad "209" smd rect
			(at 55.423 -1.301)
			(size 0.35 2.5)
			(layers "F.Cu" "F.Mask")
			(net 38 "LBDQ")
			(pinfunction "209")
			(pintype "passive")
		)
		(pad "210" smd rect
			(at 55.673 -1.301)
			(size 0.35 2.5)
			(layers "B.Cu" "B.Mask")
			(net 1 "GND")
			(pinfunction "210")
			(pintype "passive")
		)
		(pad "211" smd rect
			(at 55.923 -1.301)
			(size 0.35 2.5)
			(layers "F.Cu" "F.Mask")
			(net 1 "GND")
			(pinfunction "211")
			(pintype "passive")
		)
		(pad "212" smd rect
			(at 56.173 -1.301)
			(size 0.35 2.5)
			(layers "B.Cu" "B.Mask")
			(net 170 "unconnected-(J1-Pad212)")
			(pinfunction "212")
			(pintype "passive+no_connect")
		)
		(pad "213" smd rect
			(at 56.423 -1.301)
			(size 0.35 2.5)
			(layers "F.Cu" "F.Mask")
			(net 171 "unconnected-(J1-Pad213)")
			(pinfunction "213")
			(pintype "passive+no_connect")
		)
		(pad "214" smd rect
			(at 56.673 -1.301)
			(size 0.35 2.5)
			(layers "B.Cu" "B.Mask")
			(net 172 "unconnected-(J1-Pad214)")
			(pinfunction "214")
			(pintype "passive+no_connect")
		)
		(pad "215" smd rect
			(at 56.923 -1.301)
			(size 0.35 2.5)
			(layers "F.Cu" "F.Mask")
			(net 173 "unconnected-(J1-Pad215)")
			(pinfunction "215")
			(pintype "passive+no_connect")
		)
		(pad "216" smd rect
			(at 57.173 -1.301)
			(size 0.35 2.5)
			(layers "B.Cu" "B.Mask")
			(net 174 "unconnected-(J1-Pad216)")
			(pinfunction "216")
			(pintype "passive+no_connect")
		)
		(pad "217" smd rect
			(at 57.423 -1.301)
			(size 0.35 2.5)
			(layers "F.Cu" "F.Mask")
			(net 175 "unconnected-(J1-Pad217)")
			(pinfunction "217")
			(pintype "passive+no_connect")
		)
		(pad "218" smd rect
			(at 57.673 -1.301)
			(size 0.35 2.5)
			(layers "B.Cu" "B.Mask")
			(net 176 "unconnected-(J1-Pad218)")
			(pinfunction "218")
			(pintype "passive+no_connect")
		)
		(pad "219" smd rect
			(at 57.923 -1.301)
			(size 0.35 2.5)
			(layers "F.Cu" "F.Mask")
			(net 177 "unconnected-(J1-Pad219)")
			(pinfunction "219")
			(pintype "passive+no_connect")
		)
		(pad "220" smd rect
			(at 58.173 -1.301)
			(size 0.35 2.5)
			(layers "B.Cu" "B.Mask")
			(net 178 "unconnected-(J1-Pad220)")
			(pinfunction "220")
			(pintype "passive+no_connect")
		)
		(pad "221" smd rect
			(at 58.423 -1.301)
			(size 0.35 2.5)
			(layers "F.Cu" "F.Mask")
			(net 179 "unconnected-(J1-Pad221)")
			(pinfunction "221")
			(pintype "passive+no_connect")
		)
		(pad "222" smd rect
			(at 58.673 -1.301)
			(size 0.35 2.5)
			(layers "B.Cu" "B.Mask")
			(net 180 "unconnected-(J1-Pad222)")
			(pinfunction "222")
			(pintype "passive+no_connect")
		)
		(pad "223" smd rect
			(at 58.923 -1.301)
			(size 0.35 2.5)
			(layers "F.Cu" "F.Mask")
			(net 181 "unconnected-(J1-Pad223)")
			(pinfunction "223")
			(pintype "passive+no_connect")
		)
		(pad "224" smd rect
			(at 59.173 -1.301)
			(size 0.35 2.5)
			(layers "B.Cu" "B.Mask")
			(net 182 "unconnected-(J1-Pad224)")
			(pinfunction "224")
			(pintype "passive+no_connect")
		)
		(pad "225" smd rect
			(at 59.423 -1.301)
			(size 0.35 2.5)
			(layers "F.Cu" "F.Mask")
			(net 183 "unconnected-(J1-Pad225)")
			(pinfunction "225")
			(pintype "passive+no_connect")
		)
		(pad "226" smd rect
			(at 59.673 -1.301)
			(size 0.35 2.5)
			(layers "B.Cu" "B.Mask")
			(net 184 "unconnected-(J1-Pad226)")
			(pinfunction "226")
			(pintype "passive+no_connect")
		)
		(pad "227" smd rect
			(at 59.923 -1.301)
			(size 0.35 2.5)
			(layers "F.Cu" "F.Mask")
			(net 185 "unconnected-(J1-Pad227)")
			(pinfunction "227")
			(pintype "passive+no_connect")
		)
		(pad "228" smd rect
			(at 60.173 -1.301)
			(size 0.35 2.5)
			(layers "B.Cu" "B.Mask")
			(net 186 "unconnected-(J1-Pad228)")
			(pinfunction "228")
			(pintype "passive+no_connect")
		)
		(pad "229" smd rect
			(at 60.423 -1.301)
			(size 0.35 2.5)
			(layers "F.Cu" "F.Mask")
			(net 187 "unconnected-(J1-Pad229)")
			(pinfunction "229")
			(pintype "passive+no_connect")
		)
		(pad "230" smd rect
			(at 60.673 -1.301)
			(size 0.35 2.5)
			(layers "B.Cu" "B.Mask")
			(net 188 "unconnected-(J1-Pad230)")
			(pinfunction "230")
			(pintype "passive+no_connect")
		)
		(pad "231" smd rect
			(at 60.923 -1.301)
			(size 0.35 2.5)
			(layers "F.Cu" "F.Mask")
			(net 189 "unconnected-(J1-Pad231)")
			(pinfunction "231")
			(pintype "passive+no_connect")
		)
		(pad "232" smd rect
			(at 61.173 -1.301)
			(size 0.35 2.5)
			(layers "B.Cu" "B.Mask")
			(net 190 "unconnected-(J1-Pad232)")
			(pinfunction "232")
			(pintype "passive+no_connect")
		)
		(pad "233" smd rect
			(at 61.423 -1.301)
			(size 0.35 2.5)
			(layers "F.Cu" "F.Mask")
			(net 191 "unconnected-(J1-Pad233)")
			(pinfunction "233")
			(pintype "passive+no_connect")
		)
		(pad "234" smd rect
			(at 61.673 -1.301)
			(size 0.35 2.5)
			(layers "B.Cu" "B.Mask")
			(net 192 "unconnected-(J1-Pad234)")
			(pinfunction "234")
			(pintype "passive+no_connect")
		)
		(pad "235" smd rect
			(at 61.923 -1.301)
			(size 0.35 2.5)
			(layers "F.Cu" "F.Mask")
			(net 193 "unconnected-(J1-Pad235)")
			(pinfunction "235")
			(pintype "passive+no_connect")
		)
		(pad "236" smd rect
			(at 62.173 -1.301)
			(size 0.35 2.5)
			(layers "B.Cu" "B.Mask")
			(net 194 "unconnected-(J1-Pad236)")
			(pinfunction "236")
			(pintype "passive+no_connect")
		)
		(pad "237" smd rect
			(at 62.423 -1.301)
			(size 0.35 2.5)
			(layers "F.Cu" "F.Mask")
			(net 195 "unconnected-(J1-Pad237)")
			(pinfunction "237")
			(pintype "passive+no_connect")
		)
		(pad "238" smd rect
			(at 62.673 -1.301)
			(size 0.35 2.5)
			(layers "B.Cu" "B.Mask")
			(net 196 "unconnected-(J1-Pad238)")
			(pinfunction "238")
			(pintype "passive+no_connect")
		)
		(pad "239" smd rect
			(at 62.923 -1.301)
			(size 0.35 2.5)
			(layers "F.Cu" "F.Mask")
			(net 197 "unconnected-(J1-Pad239)")
			(pinfunction "239")
			(pintype "passive+no_connect")
		)
		(pad "240" smd rect
			(at 63.173 -1.301)
			(size 0.35 2.5)
			(layers "B.Cu" "B.Mask")
			(net 198 "unconnected-(J1-Pad240)")
			(pinfunction "240")
			(pintype "passive+no_connect")
		)
		(pad "241" smd rect
			(at 63.423 -1.301)
			(size 0.35 2.5)
			(layers "F.Cu" "F.Mask")
			(net 199 "unconnected-(J1-Pad241)")
			(pinfunction "241")
			(pintype "passive+no_connect")
		)
		(pad "242" smd rect
			(at 63.673 -1.301)
			(size 0.35 2.5)
			(layers "B.Cu" "B.Mask")
			(net 200 "unconnected-(J1-Pad242)")
			(pinfunction "242")
			(pintype "passive+no_connect")
		)
		(pad "243" smd rect
			(at 63.923 -1.301)
			(size 0.35 2.5)
			(layers "F.Cu" "F.Mask")
			(net 201 "unconnected-(J1-Pad243)")
			(pinfunction "243")
			(pintype "passive+no_connect")
		)
		(pad "244" smd rect
			(at 64.174 -1.301)
			(size 0.35 2.5)
			(layers "B.Cu" "B.Mask")
			(net 202 "unconnected-(J1-Pad244)")
			(pinfunction "244")
			(pintype "passive+no_connect")
		)
		(pad "245" smd rect
			(at 64.424 -1.301)
			(size 0.35 2.5)
			(layers "F.Cu" "F.Mask")
			(net 203 "unconnected-(J1-Pad245)")
			(pinfunction "245")
			(pintype "passive+no_connect")
		)
		(pad "246" smd rect
			(at 64.674 -1.301)
			(size 0.35 2.5)
			(layers "B.Cu" "B.Mask")
			(net 204 "unconnected-(J1-Pad246)")
			(pinfunction "246")
			(pintype "passive+no_connect")
		)
		(pad "247" smd rect
			(at 64.924 -1.301)
			(size 0.35 2.5)
			(layers "F.Cu" "F.Mask")
			(net 205 "unconnected-(J1-Pad247)")
			(pinfunction "247")
			(pintype "passive+no_connect")
		)
		(pad "248" smd rect
			(at 65.174 -1.301)
			(size 0.35 2.5)
			(layers "B.Cu" "B.Mask")
			(net 206 "unconnected-(J1-Pad248)")
			(pinfunction "248")
			(pintype "passive+no_connect")
		)
		(pad "249" smd rect
			(at 65.424 -1.301)
			(size 0.35 2.5)
			(layers "F.Cu" "F.Mask")
			(net 207 "unconnected-(J1-Pad249)")
			(pinfunction "249")
			(pintype "passive+no_connect")
		)
		(pad "250" smd rect
			(at 65.674 -1.301)
			(size 0.35 2.5)
			(layers "B.Cu" "B.Mask")
			(net 208 "unconnected-(J1-Pad250)")
			(pinfunction "250")
			(pintype "passive+no_connect")
		)
		(pad "251" smd rect
			(at 65.924 -1.301)
			(size 0.35 2.5)
			(layers "F.Cu" "F.Mask")
			(net 209 "unconnected-(J1-Pad251)")
			(pinfunction "251")
			(pintype "passive+no_connect")
		)
		(pad "252" smd rect
			(at 66.174 -1.301)
			(size 0.35 2.5)
			(layers "B.Cu" "B.Mask")
			(net 210 "unconnected-(J1-Pad252)")
			(pinfunction "252")
			(pintype "passive+no_connect")
		)
		(pad "253" smd rect
			(at 66.424 -1.301)
			(size 0.35 2.5)
			(layers "F.Cu" "F.Mask")
			(net 211 "unconnected-(J1-Pad253)")
			(pinfunction "253")
			(pintype "passive+no_connect")
		)
		(pad "254" smd rect
			(at 66.674 -1.301)
			(size 0.35 2.5)
			(layers "B.Cu" "B.Mask")
			(net 212 "unconnected-(J1-Pad254)")
			(pinfunction "254")
			(pintype "passive+no_connect")
		)
		(pad "255" smd rect
			(at 66.924 -1.301)
			(size 0.35 2.5)
			(layers "F.Cu" "F.Mask")
			(net 213 "unconnected-(J1-Pad255)")
			(pinfunction "255")
			(pintype "passive+no_connect")
		)
		(pad "256" smd rect
			(at 67.174 -1.301)
			(size 0.35 2.5)
			(layers "B.Cu" "B.Mask")
			(net 214 "unconnected-(J1-Pad256)")
			(pinfunction "256")
			(pintype "passive+no_connect")
		)
		(pad "257" smd rect
			(at 67.424 -1.301)
			(size 0.35 2.5)
			(layers "F.Cu" "F.Mask")
			(net 215 "unconnected-(J1-Pad257)")
			(pinfunction "257")
			(pintype "passive+no_connect")
		)
		(pad "258" smd rect
			(at 67.674 -1.301)
			(size 0.35 2.5)
			(layers "B.Cu" "B.Mask")
			(net 216 "unconnected-(J1-Pad258)")
			(pinfunction "258")
			(pintype "passive+no_connect")
		)
		(pad "259" smd rect
			(at 67.924 -1.301)
			(size 0.35 2.5)
			(layers "F.Cu" "F.Mask")
			(net 217 "unconnected-(J1-Pad259)")
			(pinfunction "259")
			(pintype "passive+no_connect")
		)
		(pad "260" smd rect
			(at 68.174 -1.301)
			(size 0.35 2.5)
			(layers "B.Cu" "B.Mask")
			(net 218 "unconnected-(J1-Pad260)")
			(pinfunction "260")
			(pintype "passive+no_connect")
		)
	)
	(footprint "antmicro-footprints:R_0402_1005Metric"
		(layer "F.Cu")
		(at 150.225 91.15 -90)
		(descr "Resistor SMD 0402")
		(tags "resistor SMD 0402")
		(property "Reference" "R5"
			(at 3.05 -0.385 270)
			(layer "F.SilkS")
			(effects
				(font
					(size 0.7 0.7)
					(thickness 0.15)
				)
				(justify left bottom)
			)
		)
		(property "Value" "R_1k_0402"
			(at 0 1.4 270)
			(layer "F.Fab")
			(hide yes)
			(effects
				(font
					(size 0.7 0.7)
					(thickness 0.15)
				)
				(justify left bottom)
			)
		)
		(property "Description" "1k resistor in 0402 package with 1% tolerance"
			(at 0 0 270)
			(layer "F.Fab")
			(hide yes)
			(effects
				(font
					(size 1.27 1.27)
					(thickness 0.15)
				)
			)
		)
		(property "Author" "Antmicro"
			(at 59.075 241.375 0)
			(layer "F.Fab")
			(hide yes)
			(effects
				(font
					(size 1 1)
					(thickness 0.15)
				)
			)
		)
		(property "License" "Apache-2.0"
			(at 59.075 241.375 0)
			(layer "F.Fab")
			(hide yes)
			(effects
				(font
					(size 1 1)
					(thickness 0.15)
				)
			)
		)
		(property "MPN" "CR0402-FX-1001GLF"
			(at 59.075 241.375 0)
			(layer "F.Fab")
			(hide yes)
			(effects
				(font
					(size 1 1)
					(thickness 0.15)
				)
			)
		)
		(property "Manufacturer" "Bourns"
			(at 59.075 241.375 0)
			(layer "F.Fab")
			(hide yes)
			(effects
				(font
					(size 1 1)
					(thickness 0.15)
				)
			)
		)
		(property "Tolerance" "1%"
			(at 59.075 241.375 0)
			(layer "F.Fab")
			(hide yes)
			(effects
				(font
					(size 1 1)
					(thickness 0.15)
				)
			)
		)
		(property "Val" "1k"
			(at 59.075 241.375 0)
			(layer "F.Fab")
			(hide yes)
			(effects
				(font
					(size 1 1)
					(thickness 0.15)
				)
			)
		)
		(sheetname "DDR5")
		(sheetfile "ddr5.kicad_sch")
		(attr smd)
		(fp_rect
			(start -0.925 -0.47)
			(end 0.925 0.47)
			(stroke
				(width 0.05)
				(type default)
			)
			(fill no)
			(layer "F.CrtYd")
		)
		(fp_rect
			(start -0.5 -0.25)
			(end 0.5 0.25)
			(stroke
				(width 0.15)
				(type solid)
			)
			(fill no)
			(layer "F.Fab")
		)
		(pad "1" smd roundrect
			(at -0.48 0 270)
			(size 0.59 0.64)
			(layers "F.Cu" "F.Mask" "F.Paste")
			(roundrect_rratio 0.25)
			(net 2 "VDDQ")
			(pintype "passive")
		)
		(pad "2" smd roundrect
			(at 0.48 0 270)
			(size 0.59 0.64)
			(layers "F.Cu" "F.Mask" "F.Paste")
			(roundrect_rratio 0.25)
			(net 60 "/DDR5/R_RESET_N")
			(pintype "passive")
		)
	)
	(footprint "antmicro-footprints:R_0402_1005Metric"
		(layer "F.Cu")
		(at 157.525 87.25 -90)
		(descr "Resistor SMD 0402")
		(tags "resistor SMD 0402")
		(property "Reference" "R6"
			(at 0.82 -1.325 270)
			(layer "F.SilkS")
			(effects
				(font
					(size 0.7 0.7)
					(thickness 0.15)
				)
				(justify left bottom)
			)
		)
		(property "Value" "R_240R_0402"
			(at 0 1.4 270)
			(layer "F.Fab")
			(hide yes)
			(effects
				(font
					(size 0.7 0.7)
					(thickness 0.15)
				)
				(justify left bottom)
			)
		)
		(property "Description" "240R resistor in 0402 package with 1% tolerance"
			(at 0 0 270)
			(layer "F.Fab")
			(hide yes)
			(effects
				(font
					(size 1.27 1.27)
					(thickness 0.15)
				)
			)
		)
		(property "Author" "Antmicro"
			(at 70.275 244.775 0)
			(layer "F.Fab")
			(hide yes)
			(effects
				(font
					(size 1 1)
					(thickness 0.15)
				)
			)
		)
		(property "License" "Apache-2.0"
			(at 70.275 244.775 0)
			(layer "F.Fab")
			(hide yes)
			(effects
				(font
					(size 1 1)
					(thickness 0.15)
				)
			)
		)
		(property "MPN" "CR0402-FX-2400GLF"
			(at 70.275 244.775 0)
			(layer "F.Fab")
			(hide yes)
			(effects
				(font
					(size 1 1)
					(thickness 0.15)
				)
			)
		)
		(property "Manufacturer" "Bourns"
			(at 70.275 244.775 0)
			(layer "F.Fab")
			(hide yes)
			(effects
				(font
					(size 1 1)
					(thickness 0.15)
				)
			)
		)
		(property "Tolerance" "1%"
			(at 70.275 244.775 0)
			(layer "F.Fab")
			(hide yes)
			(effects
				(font
					(size 1 1)
					(thickness 0.15)
				)
			)
		)
		(property "Val" "240R"
			(at 70.275 244.775 0)
			(layer "F.Fab")
			(hide yes)
			(effects
				(font
					(size 1 1)
					(thickness 0.15)
				)
			)
		)
		(sheetname "DDR5")
		(sheetfile "ddr5.kicad_sch")
		(attr smd)
		(fp_rect
			(start -0.925 -0.47)
			(end 0.925 0.47)
			(stroke
				(width 0.05)
				(type default)
			)
			(fill no)
			(layer "F.CrtYd")
		)
		(fp_rect
			(start -0.5 -0.25)
			(end 0.5 0.25)
			(stroke
				(width 0.15)
				(type solid)
			)
			(fill no)
			(layer "F.Fab")
		)
		(pad "1" smd roundrect
			(at -0.48 0 270)
			(size 0.59 0.64)
			(layers "F.Cu" "F.Mask" "F.Paste")
			(roundrect_rratio 0.25)
			(net 61 "/DDR5/ZQ")
			(pintype "passive")
		)
		(pad "2" smd roundrect
			(at 0.48 0 270)
			(size 0.59 0.64)
			(layers "F.Cu" "F.Mask" "F.Paste")
			(roundrect_rratio 0.25)
			(net 1 "GND")
			(pintype "passive")
		)
	)
	(footprint "antmicro-footprints:R_0402_1005Metric"
		(layer "F.Cu")
		(at 149.225 91.15 -90)
		(descr "Resistor SMD 0402")
		(tags "resistor SMD 0402")
		(property "Reference" "R7"
			(at 3.05 -0.385 270)
			(layer "F.SilkS")
			(effects
				(font
					(size 0.7 0.7)
					(thickness 0.15)
				)
				(justify left bottom)
			)
		)
		(property "Value" "R_0R_0402"
			(at 0 1.4 270)
			(layer "F.Fab")
			(hide yes)
			(effects
				(font
					(size 0.7 0.7)
					(thickness 0.15)
				)
				(justify left bottom)
			)
		)
		(property "Description" "0R resistor in 0402 package with unspecified tolerance"
			(at 0 0 270)
			(layer "F.Fab")
			(hide yes)
			(effects
				(font
					(size 1.27 1.27)
					(thickness 0.15)
				)
			)
		)
		(property "Author" "Antmicro"
			(at 58.075 240.375 0)
			(layer "F.Fab")
			(hide yes)
			(effects
				(font
					(size 1 1)
					(thickness 0.15)
				)
			)
		)
		(property "Current" "1A"
			(at 58.075 240.375 0)
			(layer "F.Fab")
			(hide yes)
			(effects
				(font
					(size 1 1)
					(thickness 0.15)
				)
			)
		)
		(property "License" "Apache-2.0"
			(at 58.075 240.375 0)
			(layer "F.Fab")
			(hide yes)
			(effects
				(font
					(size 1 1)
					(thickness 0.15)
				)
			)
		)
		(property "MPN" "ERJ2GE0R00X"
			(at 58.075 240.375 0)
			(layer "F.Fab")
			(hide yes)
			(effects
				(font
					(size 1 1)
					(thickness 0.15)
				)
			)
		)
		(property "Manufacturer" "Panasonic"
			(at 58.075 240.375 0)
			(layer "F.Fab")
			(hide yes)
			(effects
				(font
					(size 1 1)
					(thickness 0.15)
				)
			)
		)
		(property "Tolerance" ""
			(at 58.075 240.375 0)
			(layer "F.Fab")
			(hide yes)
			(effects
				(font
					(size 1 1)
					(thickness 0.15)
				)
			)
		)
		(property "Val" "0R"
			(at 58.075 240.375 0)
			(layer "F.Fab")
			(hide yes)
			(effects
				(font
					(size 1 1)
					(thickness 0.15)
				)
			)
		)
		(sheetname "DDR5")
		(sheetfile "ddr5.kicad_sch")
		(attr smd)
		(fp_rect
			(start -0.925 -0.47)
			(end 0.925 0.47)
			(stroke
				(width 0.05)
				(type default)
			)
			(fill no)
			(layer "F.CrtYd")
		)
		(fp_rect
			(start -0.5 -0.25)
			(end 0.5 0.25)
			(stroke
				(width 0.15)
				(type solid)
			)
			(fill no)
			(layer "F.Fab")
		)
		(pad "1" smd roundrect
			(at -0.48 0 270)
			(size 0.59 0.64)
			(layers "F.Cu" "F.Mask" "F.Paste")
			(roundrect_rratio 0.25)
			(net 60 "/DDR5/R_RESET_N")
			(pintype "passive")
		)
		(pad "2" smd roundrect
			(at 0.48 0 270)
			(size 0.59 0.64)
			(layers "F.Cu" "F.Mask" "F.Paste")
			(roundrect_rratio 0.25)
			(net 3 "RESET_N")
			(pintype "passive")
		)
	)
	(footprint "antmicro-footprints:R_0402_1005Metric"
		(layer "F.Cu")
		(at 157.525 89.185 -90)
		(descr "Resistor SMD 0402")
		(tags "resistor SMD 0402")
		(property "Reference" "R19"
			(at 1.115 -1.335 270)
			(layer "F.SilkS")
			(effects
				(font
					(size 0.7 0.7)
					(thickness 0.15)
				)
				(justify left bottom)
			)
		)
		(property "Value" "R_0R_0402"
			(at 0 1.4 270)
			(layer "F.Fab")
			(hide yes)
			(effects
				(font
					(size 0.7 0.7)
					(thickness 0.15)
				)
				(justify left bottom)
			)
		)
		(property "Description" "0R resistor in 0402 package with unspecified tolerance"
			(at 0 0 270)
			(layer "F.Fab")
			(hide yes)
			(effects
				(font
					(size 1.27 1.27)
					(thickness 0.15)
				)
			)
		)
		(property "Author" "Antmicro"
			(at 68.34 246.71 0)
			(layer "F.Fab")
			(hide yes)
			(effects
				(font
					(size 1 1)
					(thickness 0.15)
				)
			)
		)
		(property "Current" "1A"
			(at 68.34 246.71 0)
			(layer "F.Fab")
			(hide yes)
			(effects
				(font
					(size 1 1)
					(thickness 0.15)
				)
			)
		)
		(property "License" "Apache-2.0"
			(at 68.34 246.71 0)
			(layer "F.Fab")
			(hide yes)
			(effects
				(font
					(size 1 1)
					(thickness 0.15)
				)
			)
		)
		(property "MPN" "ERJ2GE0R00X"
			(at 68.34 246.71 0)
			(layer "F.Fab")
			(hide yes)
			(effects
				(font
					(size 1 1)
					(thickness 0.15)
				)
			)
		)
		(property "Manufacturer" "Panasonic"
			(at 68.34 246.71 0)
			(layer "F.Fab")
			(hide yes)
			(effects
				(font
					(size 1 1)
					(thickness 0.15)
				)
			)
		)
		(property "Tolerance" ""
			(at 68.34 246.71 0)
			(layer "F.Fab")
			(hide yes)
			(effects
				(font
					(size 1 1)
					(thickness 0.15)
				)
			)
		)
		(property "Val" "0R"
			(at 68.34 246.71 0)
			(layer "F.Fab")
			(hide yes)
			(effects
				(font
					(size 1 1)
					(thickness 0.15)
				)
			)
		)
		(sheetname "DDR5")
		(sheetfile "ddr5.kicad_sch")
		(attr smd)
		(fp_rect
			(start -0.925 -0.47)
			(end 0.925 0.47)
			(stroke
				(width 0.05)
				(type default)
			)
			(fill no)
			(layer "F.CrtYd")
		)
		(fp_rect
			(start -0.5 -0.25)
			(end 0.5 0.25)
			(stroke
				(width 0.15)
				(type solid)
			)
			(fill no)
			(layer "F.Fab")
		)
		(pad "1" smd roundrect
			(at -0.48 0 270)
			(size 0.59 0.64)
			(layers "F.Cu" "F.Mask" "F.Paste")
			(roundrect_rratio 0.25)
			(net 66 "/DDR5/R_LBDQS")
			(pintype "passive")
		)
		(pad "2" smd roundrect
			(at 0.48 0 270)
			(size 0.59 0.64)
			(layers "F.Cu" "F.Mask" "F.Paste")
			(roundrect_rratio 0.25)
			(net 36 "LBDQS")
			(pintype "passive")
		)
	)
	(footprint "antmicro-footprints:C_0201"
		(layer "F.Cu")
		(at 145 87.2 -90)
		(descr "Capacitor SMD 0201")
		(tags "capacitor SMD 0201")
		(property "Reference" "C24"
			(at 2.87 -0.24 90)
			(layer "F.SilkS")
			(effects
				(font
					(size 0.7 0.7)
					(thickness 0.15)
				)
				(justify right bottom)
			)
		)
		(property "Value" "C_100n_0201"
			(at 0 1.4 90)
			(layer "F.Fab")
			(hide yes)
			(effects
				(font
					(size 0.7 0.7)
					(thickness 0.15)
				)
				(justify right bottom)
			)
		)
		(property "Description" "SMD Multilayer Ceramic Capacitor, 0.1 µF, 6.3 V, 0201 [0603 Metric], ± 10%, X6S, CC Series"
			(at 0 0 270)
			(layer "F.Fab")
			(hide yes)
			(effects
				(font
					(size 1.27 1.27)
					(thickness 0.15)
				)
			)
		)
		(property "Author" "Antmicro"
			(at 57.8 232.2 0)
			(layer "F.Fab")
			(hide yes)
			(effects
				(font
					(size 1 1)
					(thickness 0.15)
				)
			)
		)
		(property "Dielectric" ""
			(at 57.8 232.2 0)
			(layer "F.Fab")
			(hide yes)
			(effects
				(font
					(size 1 1)
					(thickness 0.15)
				)
			)
		)
		(property "License" "Apache-2.0"
			(at 57.8 232.2 0)
			(layer "F.Fab")
			(hide yes)
			(effects
				(font
					(size 1 1)
					(thickness 0.15)
				)
			)
		)
		(property "MPN" "CC0201KRX6S5BB104"
			(at 57.8 232.2 0)
			(layer "F.Fab")
			(hide yes)
			(effects
				(font
					(size 1 1)
					(thickness 0.15)
				)
			)
		)
		(property "Manufacturer" "YAGEO"
			(at 57.8 232.2 0)
			(layer "F.Fab")
			(hide yes)
			(effects
				(font
					(size 1 1)
					(thickness 0.15)
				)
			)
		)
		(property "Public" "False"
			(at 57.8 232.2 0)
			(layer "F.Fab")
			(hide yes)
			(effects
				(font
					(size 1 1)
					(thickness 0.15)
				)
			)
		)
		(property "Val" "100n"
			(at 57.8 232.2 0)
			(layer "F.Fab")
			(hide yes)
			(effects
				(font
					(size 1 1)
					(thickness 0.15)
				)
			)
		)
		(property "Voltage" ""
			(at 57.8 232.2 0)
			(layer "F.Fab")
			(hide yes)
			(effects
				(font
					(size 1 1)
					(thickness 0.15)
				)
			)
		)
		(sheetname "DDR5")
		(sheetfile "ddr5.kicad_sch")
		(attr smd)
		(fp_rect
			(start -0.7 -0.35)
			(end 0.7 0.35)
			(stroke
				(width 0.05)
				(type default)
			)
			(fill no)
			(layer "F.CrtYd")
		)
		(fp_rect
			(start 0.3 0.15)
			(end -0.301 -0.149)
			(stroke
				(width 0.15)
				(type solid)
			)
			(fill no)
			(layer "F.Fab")
		)
		(pad "" smd roundrect
			(at -0.349 -0.002 270)
			(size 0.318 0.36)
			(layers "F.Paste")
			(roundrect_rratio 0.25)
		)
		(pad "" smd roundrect
			(at 0.341 -0.002 270)
			(size 0.318 0.36)
			(layers "F.Paste")
			(roundrect_rratio 0.25)
		)
		(pad "1" smd roundrect
			(at -0.321 -0.002 270)
			(size 0.46 0.4)
			(layers "F.Cu" "F.Mask")
			(roundrect_rratio 0.25)
			(net 19 "VPP")
			(pintype "passive")
		)
		(pad "2" smd roundrect
			(at 0.32 -0.002 270)
			(size 0.46 0.4)
			(layers "F.Cu" "F.Mask")
			(roundrect_rratio 0.25)
			(net 1 "GND")
			(pintype "passive")
		)
	)
	(footprint "antmicro-footprints:C_0201"
		(layer "F.Cu")
		(at 157.425 83.35 90)
		(descr "Capacitor SMD 0201")
		(tags "capacitor SMD 0201")
		(property "Reference" "C25"
			(at 0.59999 0.412957 90)
			(layer "F.SilkS")
			(effects
				(font
					(size 0.7 0.7)
					(thickness 0.15)
				)
				(justify left bottom)
			)
		)
		(property "Value" "C_100n_0201"
			(at 0 1.4 90)
			(layer "F.Fab")
			(hide yes)
			(effects
				(font
					(size 0.7 0.7)
					(thickness 0.15)
				)
				(justify left bottom)
			)
		)
		(property "Description" "SMD Multilayer Ceramic Capacitor, 0.1 µF, 6.3 V, 0201 [0603 Metric], ± 10%, X6S, CC Series"
			(at 0 0 90)
			(layer "F.Fab")
			(hide yes)
			(effects
				(font
					(size 1.27 1.27)
					(thickness 0.15)
				)
			)
		)
		(property "Author" "Antmicro"
			(at 240.775 -74.075 0)
			(layer "F.Fab")
			(hide yes)
			(effects
				(font
					(size 1 1)
					(thickness 0.15)
				)
			)
		)
		(property "Dielectric" ""
			(at 240.775 -74.075 0)
			(layer "F.Fab")
			(hide yes)
			(effects
				(font
					(size 1 1)
					(thickness 0.15)
				)
			)
		)
		(property "License" "Apache-2.0"
			(at 240.775 -74.075 0)
			(layer "F.Fab")
			(hide yes)
			(effects
				(font
					(size 1 1)
					(thickness 0.15)
				)
			)
		)
		(property "MPN" "CC0201KRX6S5BB104"
			(at 240.775 -74.075 0)
			(layer "F.Fab")
			(hide yes)
			(effects
				(font
					(size 1 1)
					(thickness 0.15)
				)
			)
		)
		(property "Manufacturer" "YAGEO"
			(at 240.775 -74.075 0)
			(layer "F.Fab")
			(hide yes)
			(effects
				(font
					(size 1 1)
					(thickness 0.15)
				)
			)
		)
		(property "Public" "False"
			(at 240.775 -74.075 0)
			(layer "F.Fab")
			(hide yes)
			(effects
				(font
					(size 1 1)
					(thickness 0.15)
				)
			)
		)
		(property "Val" "100n"
			(at 240.775 -74.075 0)
			(layer "F.Fab")
			(hide yes)
			(effects
				(font
					(size 1 1)
					(thickness 0.15)
				)
			)
		)
		(property "Voltage" ""
			(at 240.775 -74.075 0)
			(layer "F.Fab")
			(hide yes)
			(effects
				(font
					(size 1 1)
					(thickness 0.15)
				)
			)
		)
		(sheetname "DDR5")
		(sheetfile "ddr5.kicad_sch")
		(attr smd)
		(fp_rect
			(start -0.7 -0.35)
			(end 0.7 0.35)
			(stroke
				(width 0.05)
				(type default)
			)
			(fill no)
			(layer "F.CrtYd")
		)
		(fp_rect
			(start 0.3 0.15)
			(end -0.301 -0.149)
			(stroke
				(width 0.15)
				(type solid)
			)
			(fill no)
			(layer "F.Fab")
		)
		(pad "" smd roundrect
			(at -0.349 -0.002 90)
			(size 0.318 0.36)
			(layers "F.Paste")
			(roundrect_rratio 0.25)
		)
		(pad "" smd roundrect
			(at 0.341 -0.002 90)
			(size 0.318 0.36)
			(layers "F.Paste")
			(roundrect_rratio 0.25)
		)
		(pad "1" smd roundrect
			(at -0.321 -0.002 90)
			(size 0.46 0.4)
			(layers "F.Cu" "F.Mask")
			(roundrect_rratio 0.25)
			(net 19 "VPP")
			(pintype "passive")
		)
		(pad "2" smd roundrect
			(at 0.32 -0.002 90)
			(size 0.46 0.4)
			(layers "F.Cu" "F.Mask")
			(roundrect_rratio 0.25)
			(net 1 "GND")
			(pintype "passive")
		)
	)
	(footprint "antmicro-footprints:R_0402_1005Metric"
		(layer "F.Cu")
		(at 158.325 83.575 -90)
		(descr "Resistor SMD 0402")
		(tags "resistor SMD 0402")
		(property "Reference" "R18"
			(at -0.815 -0.425 270)
			(layer "F.SilkS")
			(effects
				(font
					(size 0.7 0.7)
					(thickness 0.15)
				)
				(justify left bottom)
			)
		)
		(property "Value" "R_0R_0402"
			(at 0 1.4 270)
			(layer "F.Fab")
			(hide yes)
			(effects
				(font
					(size 0.7 0.7)
					(thickness 0.15)
				)
				(justify left bottom)
			)
		)
		(property "Description" "0R resistor in 0402 package with unspecified tolerance"
			(at 0 0 270)
			(layer "F.Fab")
			(hide yes)
			(effects
				(font
					(size 1.27 1.27)
					(thickness 0.15)
				)
			)
		)
		(property "Author" "Antmicro"
			(at 74.75 241.9 0)
			(layer "F.Fab")
			(hide yes)
			(effects
				(font
					(size 1 1)
					(thickness 0.15)
				)
			)
		)
		(property "Current" "1A"
			(at 74.75 241.9 0)
			(layer "F.Fab")
			(hide yes)
			(effects
				(font
					(size 1 1)
					(thickness 0.15)
				)
			)
		)
		(property "License" "Apache-2.0"
			(at 74.75 241.9 0)
			(layer "F.Fab")
			(hide yes)
			(effects
				(font
					(size 1 1)
					(thickness 0.15)
				)
			)
		)
		(property "MPN" "ERJ2GE0R00X"
			(at 74.75 241.9 0)
			(layer "F.Fab")
			(hide yes)
			(effects
				(font
					(size 1 1)
					(thickness 0.15)
				)
			)
		)
		(property "Manufacturer" "Panasonic"
			(at 74.75 241.9 0)
			(layer "F.Fab")
			(hide yes)
			(effects
				(font
					(size 1 1)
					(thickness 0.15)
				)
			)
		)
		(property "Tolerance" ""
			(at 74.75 241.9 0)
			(layer "F.Fab")
			(hide yes)
			(effects
				(font
					(size 1 1)
					(thickness 0.15)
				)
			)
		)
		(property "Val" "0R"
			(at 74.75 241.9 0)
			(layer "F.Fab")
			(hide yes)
			(effects
				(font
					(size 1 1)
					(thickness 0.15)
				)
			)
		)
		(sheetname "DDR5")
		(sheetfile "ddr5.kicad_sch")
		(attr smd)
		(fp_rect
			(start -0.925 -0.47)
			(end 0.925 0.47)
			(stroke
				(width 0.05)
				(type default)
			)
			(fill no)
			(layer "F.CrtYd")
		)
		(fp_rect
			(start -0.5 -0.25)
			(end 0.5 0.25)
			(stroke
				(width 0.15)
				(type solid)
			)
			(fill no)
			(layer "F.Fab")
		)
		(pad "1" smd roundrect
			(at -0.48 0 270)
			(size 0.59 0.64)
			(layers "F.Cu" "F.Mask" "F.Paste")
			(roundrect_rratio 0.25)
			(net 65 "/DDR5/R_LBDQ")
			(pintype "passive")
		)
		(pad "2" smd roundrect
			(at 0.48 0 270)
			(size 0.59 0.64)
			(layers "F.Cu" "F.Mask" "F.Paste")
			(roundrect_rratio 0.25)
			(net 38 "LBDQ")
			(pintype "passive")
		)
	)
	(footprint "antmicro-footprints:BGA-82_11x9mm_Layout13x11_P0.8mm_DDR5_MO-210-AN"
		(locked yes)
		(layer "F.Cu")
		(at 151.225 85.25 -90)
		(property "Reference" "U1"
			(at -4.99 5.965 0)
			(layer "F.SilkS")
			(effects
				(font
					(size 0.7 0.7)
					(thickness 0.15)
				)
				(justify left bottom)
			)
		)
		(property "Value" "MT60B2G8HB-48B_A"
			(at -14.94 6.93 270)
			(layer "F.Fab")
			(hide yes)
			(effects
				(font
					(size 0.7 0.7)
					(thickness 0.15)
				)
				(justify left bottom)
			)
		)
		(property "Description" "DRAM, SDRAM, 16 Gbit, 2G x 8bit, FBGA, 82 Pins"
			(at 0 0 270)
			(layer "F.Fab")
			(hide yes)
			(effects
				(font
					(size 1.27 1.27)
					(thickness 0.15)
				)
			)
		)
		(property "Author" "Antmicro"
			(at 65.975 236.475 0)
			(layer "F.Fab")
			(hide yes)
			(effects
				(font
					(size 1 1)
					(thickness 0.15)
				)
			)
		)
		(property "License" "Apache-2.0"
			(at 65.975 236.475 0)
			(layer "F.Fab")
			(hide yes)
			(effects
				(font
					(size 1 1)
					(thickness 0.15)
				)
			)
		)
		(property "MPN" "MT60B2G8HB-48B:A"
			(at 65.975 236.475 0)
			(layer "F.Fab")
			(hide yes)
			(effects
				(font
					(size 1 1)
					(thickness 0.15)
				)
			)
		)
		(property "Manufacturer" "Micron Technology"
			(at 65.975 236.475 0)
			(layer "F.Fab")
			(hide yes)
			(effects
				(font
					(size 1 1)
					(thickness 0.15)
				)
			)
		)
		(sheetname "DDR5")
		(sheetfile "ddr5.kicad_sch")
		(attr smd)
		(fp_line
			(start -4.622 5.618)
			(end -4.622 2.87)
			(stroke
				(width 0.15)
				(type solid)
			)
			(layer "F.SilkS")
		)
		(fp_line
			(start -2.371 5.618)
			(end -4.622 5.618)
			(stroke
				(width 0.15)
				(type solid)
			)
			(layer "F.SilkS")
		)
		(fp_line
			(start 2.37 5.618)
			(end 4.62 5.618)
			(stroke
				(width 0.15)
				(type solid)
			)
			(layer "F.SilkS")
		)
		(fp_line
			(start 4.62 5.618)
			(end 4.62 2.87)
			(stroke
				(width 0.15)
				(type solid)
			)
			(layer "F.SilkS")
		)
		(fp_line
			(start -4.622 -4.901)
			(end -4.622 -2.871)
			(stroke
				(width 0.15)
				(type solid)
			)
			(layer "F.SilkS")
		)
		(fp_line
			(start -3.9 -5.62)
			(end -4.622 -4.901)
			(stroke
				(width 0.15)
				(type solid)
			)
			(layer "F.SilkS")
		)
		(fp_line
			(start -2.371 -5.62)
			(end -3.9 -5.62)
			(stroke
				(width 0.15)
				(type solid)
			)
			(layer "F.SilkS")
		)
		(fp_line
			(start 2.37 -5.62)
			(end 4.62 -5.62)
			(stroke
				(width 0.15)
				(type solid)
			)
			(layer "F.SilkS")
		)
		(fp_line
			(start 2.37 -5.62)
			(end 4.62 -5.62)
			(stroke
				(width 0.15)
				(type solid)
			)
			(layer "F.SilkS")
		)
		(fp_line
			(start 2.37 -5.62)
			(end 4.62 -5.62)
			(stroke
				(width 0.15)
				(type solid)
			)
			(layer "F.SilkS")
		)
		(fp_line
			(start 4.62 -5.62)
			(end 4.62 -2.871)
			(stroke
				(width 0.15)
				(type solid)
			)
			(layer "F.SilkS")
		)
		(fp_line
			(start 4.62 -5.62)
			(end 4.62 -2.871)
			(stroke
				(width 0.15)
				(type solid)
			)
			(layer "F.SilkS")
		)
		(fp_line
			(start 4.62 -5.62)
			(end 4.62 -2.871)
			(stroke
				(width 0.15)
				(type solid)
			)
			(layer "F.SilkS")
		)
		(fp_rect
			(start -4.75 -5.75)
			(end 4.75 5.75)
			(stroke
				(width 0.12)
				(type solid)
			)
			(fill no)
			(layer "F.CrtYd")
		)
		(fp_line
			(start -4.5 5.498)
			(end 4.498 5.498)
			(stroke
				(width 0.15)
				(type solid)
			)
			(layer "F.Fab")
		)
		(fp_line
			(start 4.498 5.498)
			(end 4.498 -5.5)
			(stroke
				(width 0.15)
				(type solid)
			)
			(layer "F.Fab")
		)
		(fp_line
			(start -4.5 -4.901)
			(end -4.5 5.498)
			(stroke
				(width 0.15)
				(type solid)
			)
			(layer "F.Fab")
		)
		(fp_line
			(start -3.9 -5.5)
			(end -4.5 -4.901)
			(stroke
				(width 0.15)
				(type solid)
			)
			(layer "F.Fab")
		)
		(fp_line
			(start 4.498 -5.5)
			(end -3.9 -5.5)
			(stroke
				(width 0.15)
				(type solid)
			)
			(layer "F.Fab")
		)
		(fp_text user "."
			(at -4.81 -5.705 270)
			(layer "F.SilkS")
			(effects
				(font
					(size 0.7 0.7)
					(thickness 0.15)
				)
			)
		)
		(pad "A1" smd circle
			(at -4 -4.8 270)
			(size 0.45 0.45)
			(layers "F.Cu" "F.Mask" "F.Paste")
			(net 219 "unconnected-(U1-DNU-PadA1)")
			(pinfunction "DNU")
			(pintype "no_connect")
		)
		(pad "A2" smd circle
			(at -3.202 -4.8 270)
			(size 0.45 0.45)
			(layers "F.Cu" "F.Mask" "F.Paste")
			(net 65 "/DDR5/R_LBDQ")
			(pinfunction "LBDQ")
			(pintype "input")
		)
		(pad "A3" smd circle
			(at -2.4 -4.8 270)
			(size 0.45 0.45)
			(layers "F.Cu" "F.Mask" "F.Paste")
			(net 1 "GND")
			(pinfunction "VSS")
			(pintype "passive")
		)
		(pad "A4" smd circle
			(at -1.601 -4.8 270)
			(size 0.45 0.45)
			(layers "F.Cu" "F.Mask" "F.Paste")
			(net 19 "VPP")
			(pinfunction "VPP")
			(pintype "power_in")
		)
		(pad "A8" smd circle
			(at 1.6 -4.8 270)
			(size 0.45 0.45)
			(layers "F.Cu" "F.Mask" "F.Paste")
			(net 61 "/DDR5/ZQ")
			(pinfunction "ZQ")
			(pintype "input")
		)
		(pad "A9" smd circle
			(at 2.398 -4.8 270)
			(size 0.45 0.45)
			(layers "F.Cu" "F.Mask" "F.Paste")
			(net 1 "GND")
			(pinfunction "VSS")
			(pintype "passive")
		)
		(pad "A10" smd circle
			(at 3.2 -4.8 270)
			(size 0.45 0.45)
			(layers "F.Cu" "F.Mask" "F.Paste")
			(net 66 "/DDR5/R_LBDQS")
			(pinfunction "LBDQS")
			(pintype "input")
		)
		(pad "A11" smd circle
			(at 3.999 -4.8 270)
			(size 0.45 0.45)
			(layers "F.Cu" "F.Mask" "F.Paste")
			(net 220 "unconnected-(U1-DNU-PadA11)")
			(pinfunction "DNU")
			(pintype "no_connect")
		)
		(pad "B2" smd circle
			(at -3.202 -4 270)
			(size 0.45 0.45)
			(layers "F.Cu" "F.Mask" "F.Paste")
			(net 18 "VDD")
			(pinfunction "VDD")
			(pintype "power_in")
		)
		(pad "B3" smd circle
			(at -2.4 -4 270)
			(size 0.45 0.45)
			(layers "F.Cu" "F.Mask" "F.Paste")
			(net 2 "VDDQ")
			(pinfunction "VDDQ")
			(pintype "power_in")
		)
		(pad "B4" smd circle
			(at -1.601 -4 270)
			(size 0.45 0.45)
			(layers "F.Cu" "F.Mask" "F.Paste")
			(net 21 "DQ2")
			(pinfunction "DQ2")
			(pintype "bidirectional")
		)
		(pad "B8" smd circle
			(at 1.6 -4 270)
			(size 0.45 0.45)
			(layers "F.Cu" "F.Mask" "F.Paste")
			(net 20 "DQ3")
			(pinfunction "DQ3")
			(pintype "bidirectional")
		)
		(pad "B9" smd circle
			(at 2.398 -4 270)
			(size 0.45 0.45)
			(layers "F.Cu" "F.Mask" "F.Paste")
			(net 2 "VDDQ")
			(pinfunction "VDDQ")
			(pintype "power_in")
		)
		(pad "B10" smd circle
			(at 3.2 -4 270)
			(size 0.45 0.45)
			(layers "F.Cu" "F.Mask" "F.Paste")
			(net 18 "VDD")
			(pinfunction "VDD")
			(pintype "power_in")
		)
		(pad "C2" smd circle
			(at -3.202 -3.202 270)
			(size 0.45 0.45)
			(layers "F.Cu" "F.Mask" "F.Paste")
			(net 1 "GND")
			(pinfunction "VSS")
			(pintype "passive")
		)
		(pad "C3" smd circle
			(at -2.4 -3.202 270)
			(size 0.45 0.45)
			(layers "F.Cu" "F.Mask" "F.Paste")
			(net 25 "DQ0")
			(pinfunction "DQ0")
			(pintype "bidirectional")
		)
		(pad "C4" smd circle
			(at -1.601 -3.202 270)
			(size 0.45 0.45)
			(layers "F.Cu" "F.Mask" "F.Paste")
			(net 26 "DQS_P")
			(pinfunction "DQS_T")
			(pintype "bidirectional")
		)
		(pad "C8" smd circle
			(at 1.6 -3.202 270)
			(size 0.45 0.45)
			(layers "F.Cu" "F.Mask" "F.Paste")
			(net 37 "TDQS_P")
			(pinfunction "TDQS_T")
			(pintype "output")
		)
		(pad "C9" smd circle
			(at 2.398 -3.202 270)
			(size 0.45 0.45)
			(layers "F.Cu" "F.Mask" "F.Paste")
			(net 23 "DQ1")
			(pinfunction "DQ1")
			(pintype "bidirectional")
		)
		(pad "C10" smd circle
			(at 3.2 -3.202 270)
			(size 0.45 0.45)
			(layers "F.Cu" "F.Mask" "F.Paste")
			(net 1 "GND")
			(pinfunction "VSS")
			(pintype "passive")
		)
		(pad "D2" smd circle
			(at -3.202 -2.4 270)
			(size 0.45 0.45)
			(layers "F.Cu" "F.Mask" "F.Paste")
			(net 2 "VDDQ")
			(pinfunction "VDDQ")
			(pintype "power_in")
		)
		(pad "D3" smd circle
			(at -2.4 -2.4 270)
			(size 0.45 0.45)
			(layers "F.Cu" "F.Mask" "F.Paste")
			(net 1 "GND")
			(pinfunction "VSS")
			(pintype "passive")
		)
		(pad "D4" smd circle
			(at -1.601 -2.4 270)
			(size 0.45 0.45)
			(layers "F.Cu" "F.Mask" "F.Paste")
			(net 27 "DQS_N")
			(pinfunction "DQS_C")
			(pintype "bidirectional")
		)
		(pad "D8" smd circle
			(at 1.6 -2.4 270)
			(size 0.45 0.45)
			(layers "F.Cu" "F.Mask" "F.Paste")
			(net 39 "TDQS_N")
			(pinfunction "TDQS_C")
			(pintype "output")
		)
		(pad "D9" smd circle
			(at 2.398 -2.4 270)
			(size 0.45 0.45)
			(layers "F.Cu" "F.Mask" "F.Paste")
			(net 1 "GND")
			(pinfunction "VSS")
			(pintype "passive")
		)
		(pad "D10" smd circle
			(at 3.2 -2.4 270)
			(size 0.45 0.45)
			(layers "F.Cu" "F.Mask" "F.Paste")
			(net 2 "VDDQ")
			(pinfunction "VDDQ")
			(pintype "power_in")
		)
		(pad "E2" smd circle
			(at -3.202 -1.601 270)
			(size 0.45 0.45)
			(layers "F.Cu" "F.Mask" "F.Paste")
			(net 18 "VDD")
			(pinfunction "VDD")
			(pintype "power_in")
		)
		(pad "E3" smd circle
			(at -2.4 -1.601 270)
			(size 0.45 0.45)
			(layers "F.Cu" "F.Mask" "F.Paste")
			(net 31 "DQ4")
			(pinfunction "DQ4")
			(pintype "bidirectional")
		)
		(pad "E4" smd circle
			(at -1.601 -1.601 270)
			(size 0.45 0.45)
			(layers "F.Cu" "F.Mask" "F.Paste")
			(net 29 "DQ6")
			(pinfunction "DQ6")
			(pintype "bidirectional")
		)
		(pad "E8" smd circle
			(at 1.6 -1.601 270)
			(size 0.45 0.45)
			(layers "F.Cu" "F.Mask" "F.Paste")
			(net 28 "DQ7")
			(pinfunction "DQ7")
			(pintype "bidirectional")
		)
		(pad "E9" smd circle
			(at 2.398 -1.601 270)
			(size 0.45 0.45)
			(layers "F.Cu" "F.Mask" "F.Paste")
			(net 30 "DQ5")
			(pinfunction "DQ5")
			(pintype "bidirectional")
		)
		(pad "E10" smd circle
			(at 3.2 -1.601 270)
			(size 0.45 0.45)
			(layers "F.Cu" "F.Mask" "F.Paste")
			(net 18 "VDD")
			(pinfunction "VDD")
			(pintype "power_in")
		)
		(pad "F2" smd circle
			(at -3.202 -0.804 270)
			(size 0.45 0.45)
			(layers "F.Cu" "F.Mask" "F.Paste")
			(net 1 "GND")
			(pinfunction "VSS")
			(pintype "passive")
		)
		(pad "F3" smd circle
			(at -2.4 -0.804 270)
			(size 0.45 0.45)
			(layers "F.Cu" "F.Mask" "F.Paste")
			(net 2 "VDDQ")
			(pinfunction "VDDQ")
			(pintype "power_in")
		)
		(pad "F4" smd circle
			(at -1.601 -0.804 270)
			(size 0.45 0.45)
			(layers "F.Cu" "F.Mask" "F.Paste")
			(net 1 "GND")
			(pinfunction "VSS")
			(pintype "passive")
		)
		(pad "F8" smd circle
			(at 1.6 -0.804 270)
			(size 0.45 0.45)
			(layers "F.Cu" "F.Mask" "F.Paste")
			(net 1 "GND")
			(pinfunction "VSS")
			(pintype "passive")
		)
		(pad "F9" smd circle
			(at 2.398 -0.804 270)
			(size 0.45 0.45)
			(layers "F.Cu" "F.Mask" "F.Paste")
			(net 2 "VDDQ")
			(pinfunction "VDDQ")
			(pintype "power_in")
		)
		(pad "F10" smd circle
			(at 3.2 -0.804 270)
			(size 0.45 0.45)
			(layers "F.Cu" "F.Mask" "F.Paste")
			(net 1 "GND")
			(pinfunction "VSS")
			(pintype "passive")
		)
		(pad "G2" smd circle
			(at -3.202 0 270)
			(size 0.45 0.45)
			(layers "F.Cu" "F.Mask" "F.Paste")
			(net 58 "/DDR5/R_ODT_CA_A")
			(pinfunction "CA_ODT")
			(pintype "input")
		)
		(pad "G3" smd circle
			(at -2.4 0 270)
			(size 0.45 0.45)
			(layers "F.Cu" "F.Mask" "F.Paste")
			(net 63 "/DDR5/R_MIR")
			(pinfunction "MIR")
			(pintype "input")
		)
		(pad "G4" smd circle
			(at -1.601 0 270)
			(size 0.45 0.45)
			(layers "F.Cu" "F.Mask" "F.Paste")
			(net 18 "VDD")
			(pinfunction "VDD")
			(pintype "power_in")
		)
		(pad "G8" smd circle
			(at 1.6 0 270)
			(size 0.45 0.45)
			(layers "F.Cu" "F.Mask" "F.Paste")
			(net 42 "CLK_P")
			(pinfunction "CK_T")
			(pintype "input")
		)
		(pad "G9" smd circle
			(at 2.398 0 270)
			(size 0.45 0.45)
			(layers "F.Cu" "F.Mask" "F.Paste")
			(net 2 "VDDQ")
			(pinfunction "VDDQ")
			(pintype "power_in")
		)
		(pad "G10" smd circle
			(at 3.2 0 270)
			(size 0.45 0.45)
			(layers "F.Cu" "F.Mask" "F.Paste")
			(net 64 "/DDR5/R_TEN")
			(pinfunction "TEN")
			(pintype "input")
		)
		(pad "H2" smd circle
			(at -3.202 0.8 270)
			(size 0.45 0.45)
			(layers "F.Cu" "F.Mask" "F.Paste")
			(net 59 "/DDR5/R_ALERT_N")
			(pinfunction "ALERT_N")
			(pintype "bidirectional")
		)
		(pad "H3" smd circle
			(at -2.4 0.8 270)
			(size 0.45 0.45)
			(layers "F.Cu" "F.Mask" "F.Paste")
			(net 1 "GND")
			(pinfunction "VSS")
			(pintype "passive")
		)
		(pad "H4" smd circle
			(at -1.601 0.8 270)
			(size 0.45 0.45)
			(layers "F.Cu" "F.Mask" "F.Paste")
			(net 17 "CS_N")
			(pinfunction "CS_N")
			(pintype "input")
		)
		(pad "H8" smd circle
			(at 1.6 0.8 270)
			(size 0.45 0.45)
			(layers "F.Cu" "F.Mask" "F.Paste")
			(net 44 "CLK_N")
			(pinfunction "CK_C")
			(pintype "input")
		)
		(pad "H9" smd circle
			(at 2.398 0.8 270)
			(size 0.45 0.45)
			(layers "F.Cu" "F.Mask" "F.Paste")
			(net 1 "GND")
			(pinfunction "VSS")
			(pintype "passive")
		)
		(pad "H10" smd circle
			(at 3.2 0.8 270)
			(size 0.45 0.45)
			(layers "F.Cu" "F.Mask" "F.Paste")
			(net 18 "VDD")
			(pinfunction "VDD")
			(pintype "power_in")
		)
		(pad "J2" smd circle
			(at -3.202 1.6 270)
			(size 0.45 0.45)
			(layers "F.Cu" "F.Mask" "F.Paste")
			(net 2 "VDDQ")
			(pinfunction "VDDQ")
			(pintype "power_in")
		)
		(pad "J3" smd circle
			(at -2.4 1.6 270)
			(size 0.45 0.45)
			(layers "F.Cu" "F.Mask" "F.Paste")
			(net 48 "CA4")
			(pinfunction "CA4")
			(pintype "bidirectional")
		)
		(pad "J4" smd circle
			(at -1.601 1.6 270)
			(size 0.45 0.45)
			(layers "F.Cu" "F.Mask" "F.Paste")
			(net 24 "CA0")
			(pinfunction "CA0")
			(pintype "bidirectional")
		)
		(pad "J8" smd circle
			(at 1.6 1.6 270)
			(size 0.45 0.45)
			(layers "F.Cu" "F.Mask" "F.Paste")
			(net 22 "CA1")
			(pinfunction "CA1")
			(pintype "bidirectional")
		)
		(pad "J9" smd circle
			(at 2.398 1.6 270)
			(size 0.45 0.45)
			(layers "F.Cu" "F.Mask" "F.Paste")
			(net 49 "CA5")
			(pinfunction "CA5")
			(pintype "bidirectional")
		)
		(pad "J10" smd circle
			(at 3.2 1.6 270)
			(size 0.45 0.45)
			(layers "F.Cu" "F.Mask" "F.Paste")
			(net 2 "VDDQ")
			(pinfunction "VDDQ")
			(pintype "power_in")
		)
		(pad "K2" smd circle
			(at -3.202 2.398 270)
			(size 0.45 0.45)
			(layers "F.Cu" "F.Mask" "F.Paste")
			(net 18 "VDD")
			(pinfunction "VDD")
			(pintype "power_in")
		)
		(pad "K3" smd circle
			(at -2.4 2.398 270)
			(size 0.45 0.45)
			(layers "F.Cu" "F.Mask" "F.Paste")
			(net 40 "CA6")
			(pinfunction "CA6")
			(pintype "bidirectional")
		)
		(pad "K4" smd circle
			(at -1.601 2.398 270)
			(size 0.45 0.45)
			(layers "F.Cu" "F.Mask" "F.Paste")
			(net 46 "CA2")
			(pinfunction "CA2")
			(pintype "bidirectional")
		)
		(pad "K8" smd circle
			(at 1.6 2.398 270)
			(size 0.45 0.45)
			(layers "F.Cu" "F.Mask" "F.Paste")
			(net 47 "CA3")
			(pinfunction "CA3")
			(pintype "bidirectional")
		)
		(pad "K9" smd circle
			(at 2.398 2.398 270)
			(size 0.45 0.45)
			(layers "F.Cu" "F.Mask" "F.Paste")
			(net 41 "CA7")
			(pinfunction "CA7")
			(pintype "bidirectional")
		)
		(pad "K10" smd circle
			(at 3.2 2.398 270)
			(size 0.45 0.45)
			(layers "F.Cu" "F.Mask" "F.Paste")
			(net 18 "VDD")
			(pinfunction "VDD")
			(pintype "power_in")
		)
		(pad "L2" smd circle
			(at -3.202 3.2 270)
			(size 0.45 0.45)
			(layers "F.Cu" "F.Mask" "F.Paste")
			(net 2 "VDDQ")
			(pinfunction "VDDQ")
			(pintype "power_in")
		)
		(pad "L3" smd circle
			(at -2.4 3.2 270)
			(size 0.45 0.45)
			(layers "F.Cu" "F.Mask" "F.Paste")
			(net 1 "GND")
			(pinfunction "VSS")
			(pintype "passive")
		)
		(pad "L4" smd circle
			(at -1.601 3.2 270)
			(size 0.45 0.45)
			(layers "F.Cu" "F.Mask" "F.Paste")
			(net 43 "CA8")
			(pinfunction "CA8")
			(pintype "bidirectional")
		)
		(pad "L8" smd circle
			(at 1.6 3.2 270)
			(size 0.45 0.45)
			(layers "F.Cu" "F.Mask" "F.Paste")
			(net 45 "CA9")
			(pinfunction "CA9")
			(pintype "bidirectional")
		)
		(pad "L9" smd circle
			(at 2.398 3.2 270)
			(size 0.45 0.45)
			(layers "F.Cu" "F.Mask" "F.Paste")
			(net 1 "GND")
			(pinfunction "VSS")
			(pintype "passive")
		)
		(pad "L10" smd circle
			(at 3.2 3.2 270)
			(size 0.45 0.45)
			(layers "F.Cu" "F.Mask" "F.Paste")
			(net 2 "VDDQ")
			(pinfunction "VDDQ")
			(pintype "power_in")
		)
		(pad "M2" smd circle
			(at -3.202 3.999 270)
			(size 0.45 0.45)
			(layers "F.Cu" "F.Mask" "F.Paste")
			(net 62 "/DDR5/R_CAI")
			(pinfunction "CAI")
			(pintype "input")
		)
		(pad "M3" smd circle
			(at -2.4 3.999 270)
			(size 0.45 0.45)
			(layers "F.Cu" "F.Mask" "F.Paste")
			(net 32 "CA10")
			(pinfunction "CA10")
			(pintype "bidirectional")
		)
		(pad "M4" smd circle
			(at -1.601 3.999 270)
			(size 0.45 0.45)
			(layers "F.Cu" "F.Mask" "F.Paste")
			(net 34 "CA12")
			(pinfunction "CA12")
			(pintype "bidirectional")
		)
		(pad "M8" smd circle
			(at 1.6 3.999 270)
			(size 0.45 0.45)
			(layers "F.Cu" "F.Mask" "F.Paste")
			(net 35 "CA13")
			(pinfunction "CA13")
			(pintype "bidirectional")
		)
		(pad "M9" smd circle
			(at 2.398 3.999 270)
			(size 0.45 0.45)
			(layers "F.Cu" "F.Mask" "F.Paste")
			(net 33 "CA11")
			(pinfunction "CA11")
			(pintype "bidirectional")
		)
		(pad "M10" smd circle
			(at 3.2 3.999 270)
			(size 0.45 0.45)
			(layers "F.Cu" "F.Mask" "F.Paste")
			(net 60 "/DDR5/R_RESET_N")
			(pinfunction "RESET_N")
			(pintype "input")
		)
		(pad "N1" smd circle
			(at -4 4.799 270)
			(size 0.45 0.45)
			(layers "F.Cu" "F.Mask" "F.Paste")
			(net 221 "unconnected-(U1-DNU-PadN1)")
			(pinfunction "DNU")
			(pintype "no_connect")
		)
		(pad "N2" smd circle
			(at -3.202 4.799 270)
			(size 0.45 0.45)
			(layers "F.Cu" "F.Mask" "F.Paste")
			(net 18 "VDD")
			(pinfunction "VDD")
			(pintype "power_in")
		)
		(pad "N3" smd circle
			(at -2.4 4.799 270)
			(size 0.45 0.45)
			(layers "F.Cu" "F.Mask" "F.Paste")
			(net 1 "GND")
			(pinfunction "VSS")
			(pintype "passive")
		)
		(pad "N4" smd circle
			(at -1.601 4.799 270)
			(size 0.45 0.45)
			(layers "F.Cu" "F.Mask" "F.Paste")
			(net 18 "VDD")
			(pinfunction "VDD")
			(pintype "power_in")
		)
		(pad "N8" smd circle
			(at 1.6 4.799 270)
			(size 0.45 0.45)
			(layers "F.Cu" "F.Mask" "F.Paste")
			(net 19 "VPP")
			(pinfunction "VPP")
			(pintype "power_in")
		)
		(pad "N9" smd circle
			(at 2.398 4.799 270)
			(size 0.45 0.45)
			(layers "F.Cu" "F.Mask" "F.Paste")
			(net 1 "GND")
			(pinfunction "VSS")
			(pintype "passive")
		)
		(pad "N10" smd circle
			(at 3.2 4.799 270)
			(size 0.45 0.45)
			(layers "F.Cu" "F.Mask" "F.Paste")
			(net 18 "VDD")
			(pinfunction "VDD")
			(pintype "power_in")
		)
		(pad "N11" smd circle
			(at 3.999 4.799 270)
			(size 0.45 0.45)
			(layers "F.Cu" "F.Mask" "F.Paste")
			(net 222 "unconnected-(U1-DNU-PadN11)")
			(pinfunction "DNU")
			(pintype "no_connect")
		)
	)
	(footprint "antmicro-footprints:R_0402_1005Metric"
		(layer "F.Cu")
		(at 151.225 91.15 -90)
		(descr "Resistor SMD 0402")
		(tags "resistor SMD 0402")
		(property "Reference" "R17"
			(at 3.05 -0.385 270)
			(layer "F.SilkS")
			(effects
				(font
					(size 0.7 0.7)
					(thickness 0.15)
				)
				(justify left bottom)
			)
		)
		(property "Value" "R_0R_0402"
			(at 0 1.4 270)
			(layer "F.Fab")
			(hide yes)
			(effects
				(font
					(size 0.7 0.7)
					(thickness 0.15)
				)
				(justify left bottom)
			)
		)
		(property "Description" "0R resistor in 0402 package with unspecified tolerance"
			(at 0 0 270)
			(layer "F.Fab")
			(hide yes)
			(effects
				(font
					(size 1.27 1.27)
					(thickness 0.15)
				)
			)
		)
		(property "Author" "Antmicro"
			(at 60.075 242.375 0)
			(layer "F.Fab")
			(hide yes)
			(effects
				(font
					(size 1 1)
					(thickness 0.15)
				)
			)
		)
		(property "Current" "1A"
			(at 60.075 242.375 0)
			(layer "F.Fab")
			(hide yes)
			(effects
				(font
					(size 1 1)
					(thickness 0.15)
				)
			)
		)
		(property "License" "Apache-2.0"
			(at 60.075 242.375 0)
			(layer "F.Fab")
			(hide yes)
			(effects
				(font
					(size 1 1)
					(thickness 0.15)
				)
			)
		)
		(property "MPN" "ERJ2GE0R00X"
			(at 60.075 242.375 0)
			(layer "F.Fab")
			(hide yes)
			(effects
				(font
					(size 1 1)
					(thickness 0.15)
				)
			)
		)
		(property "Manufacturer" "Panasonic"
			(at 60.075 242.375 0)
			(layer "F.Fab")
			(hide yes)
			(effects
				(font
					(size 1 1)
					(thickness 0.15)
				)
			)
		)
		(property "Tolerance" ""
			(at 60.075 242.375 0)
			(layer "F.Fab")
			(hide yes)
			(effects
				(font
					(size 1 1)
					(thickness 0.15)
				)
			)
		)
		(property "Val" "0R"
			(at 60.075 242.375 0)
			(layer "F.Fab")
			(hide yes)
			(effects
				(font
					(size 1 1)
					(thickness 0.15)
				)
			)
		)
		(sheetname "DDR5")
		(sheetfile "ddr5.kicad_sch")
		(attr smd)
		(fp_rect
			(start -0.925 -0.47)
			(end 0.925 0.47)
			(stroke
				(width 0.05)
				(type default)
			)
			(fill no)
			(layer "F.CrtYd")
		)
		(fp_rect
			(start -0.5 -0.25)
			(end 0.5 0.25)
			(stroke
				(width 0.15)
				(type solid)
			)
			(fill no)
			(layer "F.Fab")
		)
		(pad "1" smd roundrect
			(at -0.48 0 270)
			(size 0.59 0.64)
			(layers "F.Cu" "F.Mask" "F.Paste")
			(roundrect_rratio 0.25)
			(net 64 "/DDR5/R_TEN")
			(pintype "passive")
		)
		(pad "2" smd roundrect
			(at 0.48 0 270)
			(size 0.59 0.64)
			(layers "F.Cu" "F.Mask" "F.Paste")
			(roundrect_rratio 0.25)
			(net 54 "TEN")
			(pintype "passive")
		)
	)
	(footprint "antmicro-footprints:R_0402_1005Metric"
		(layer "B.Cu")
		(at 151.15 85)
		(descr "Resistor SMD 0402")
		(tags "resistor SMD 0402")
		(property "Reference" "R3"
			(at 2.38 0.4 180)
			(layer "B.SilkS")
			(effects
				(font
					(size 0.7 0.7)
					(thickness 0.15)
				)
				(justify left bottom mirror)
			)
		)
		(property "Value" "R_10k_0402"
			(at 0 -1.4 180)
			(layer "B.Fab")
			(hide yes)
			(effects
				(font
					(size 0.7 0.7)
					(thickness 0.15)
				)
				(justify left bottom mirror)
			)
		)
		(property "Description" "10k resistor in 0402 package with 1% tolerance"
			(at 0 0 0)
			(layer "F.Fab")
			(hide yes)
			(effects
				(font
					(size 1.27 1.27)
					(thickness 0.15)
				)
			)
		)
		(property "Author" "Antmicro"
			(at 0 0 0)
			(layer "B.Fab")
			(hide yes)
			(effects
				(font
					(size 1 1)
					(thickness 0.15)
				)
				(justify mirror)
			)
		)
		(property "License" "Apache-2.0"
			(at 0 0 0)
			(layer "B.Fab")
			(hide yes)
			(effects
				(font
					(size 1 1)
					(thickness 0.15)
				)
				(justify mirror)
			)
		)
		(property "MPN" "CR0402-FX-1002GLF"
			(at 0 0 0)
			(layer "B.Fab")
			(hide yes)
			(effects
				(font
					(size 1 1)
					(thickness 0.15)
				)
				(justify mirror)
			)
		)
		(property "Manufacturer" "Bourns"
			(at 0 0 0)
			(layer "B.Fab")
			(hide yes)
			(effects
				(font
					(size 1 1)
					(thickness 0.15)
				)
				(justify mirror)
			)
		)
		(property "Tolerance" "1%"
			(at 0 0 0)
			(layer "B.Fab")
			(hide yes)
			(effects
				(font
					(size 1 1)
					(thickness 0.15)
				)
				(justify mirror)
			)
		)
		(property "Val" "10k"
			(at 0 0 0)
			(layer "B.Fab")
			(hide yes)
			(effects
				(font
					(size 1 1)
					(thickness 0.15)
				)
				(justify mirror)
			)
		)
		(sheetname "DDR5")
		(sheetfile "ddr5.kicad_sch")
		(attr smd)
		(fp_rect
			(start -0.925 0.47)
			(end 0.925 -0.47)
			(stroke
				(width 0.05)
				(type default)
			)
			(fill no)
			(layer "B.CrtYd")
		)
		(fp_rect
			(start -0.5 0.25)
			(end 0.5 -0.25)
			(stroke
				(width 0.15)
				(type solid)
			)
			(fill no)
			(layer "B.Fab")
		)
		(pad "1" smd roundrect
			(at -0.48 0)
			(size 0.59 0.64)
			(layers "B.Cu" "B.Mask" "B.Paste")
			(roundrect_rratio 0.25)
			(net 17 "CS_N")
			(pintype "passive")
		)
		(pad "2" smd roundrect
			(at 0.48 0)
			(size 0.59 0.64)
			(layers "B.Cu" "B.Mask" "B.Paste")
			(roundrect_rratio 0.25)
			(net 1 "GND")
			(pintype "passive")
		)
	)
	(footprint "antmicro-footprints:R_0402_1005Metric"
		(layer "B.Cu")
		(at 156.9 84.6 180)
		(descr "Resistor SMD 0402")
		(tags "resistor SMD 0402")
		(property "Reference" "R1"
			(at -2.39 -0.31 0)
			(layer "B.SilkS")
			(effects
				(font
					(size 0.7 0.7)
					(thickness 0.15)
				)
				(justify left bottom mirror)
			)
		)
		(property "Value" "R_1k_0402"
			(at 0 -1.4 0)
			(layer "B.Fab")
			(hide yes)
			(effects
				(font
					(size 0.7 0.7)
					(thickness 0.15)
				)
				(justify left bottom mirror)
			)
		)
		(property "Description" "1k resistor in 0402 package with 1% tolerance"
			(at 0 0 180)
			(layer "F.Fab")
			(hide yes)
			(effects
				(font
					(size 1.27 1.27)
					(thickness 0.15)
				)
			)
		)
		(property "Author" "Antmicro"
			(at 313.8 169.2 0)
			(layer "B.Fab")
			(hide yes)
			(effects
				(font
					(size 1 1)
					(thickness 0.15)
				)
				(justify mirror)
			)
		)
		(property "License" "Apache-2.0"
			(at 313.8 169.2 0)
			(layer "B.Fab")
			(hide yes)
			(effects
				(font
					(size 1 1)
					(thickness 0.15)
				)
				(justify mirror)
			)
		)
		(property "MPN" "CR0402-FX-1001GLF"
			(at 313.8 169.2 0)
			(layer "B.Fab")
			(hide yes)
			(effects
				(font
					(size 1 1)
					(thickness 0.15)
				)
				(justify mirror)
			)
		)
		(property "Manufacturer" "Bourns"
			(at 313.8 169.2 0)
			(layer "B.Fab")
			(hide yes)
			(effects
				(font
					(size 1 1)
					(thickness 0.15)
				)
				(justify mirror)
			)
		)
		(property "Tolerance" "1%"
			(at 313.8 169.2 0)
			(layer "B.Fab")
			(hide yes)
			(effects
				(font
					(size 1 1)
					(thickness 0.15)
				)
				(justify mirror)
			)
		)
		(property "Val" "1k"
			(at 313.8 169.2 0)
			(layer "B.Fab")
			(hide yes)
			(effects
				(font
					(size 1 1)
					(thickness 0.15)
				)
				(justify mirror)
			)
		)
		(sheetname "DDR5")
		(sheetfile "ddr5.kicad_sch")
		(attr smd)
		(fp_rect
			(start -0.925 0.47)
			(end 0.925 -0.47)
			(stroke
				(width 0.05)
				(type default)
			)
			(fill no)
			(layer "B.CrtYd")
		)
		(fp_rect
			(start -0.5 0.25)
			(end 0.5 -0.25)
			(stroke
				(width 0.15)
				(type solid)
			)
			(fill no)
			(layer "B.Fab")
		)
		(pad "1" smd roundrect
			(at -0.48 0 180)
			(size 0.59 0.64)
			(layers "B.Cu" "B.Mask" "B.Paste")
			(roundrect_rratio 0.25)
			(net 2 "VDDQ")
			(pintype "passive")
		)
		(pad "2" smd roundrect
			(at 0.48 0 180)
			(size 0.59 0.64)
			(layers "B.Cu" "B.Mask" "B.Paste")
			(roundrect_rratio 0.25)
			(net 58 "/DDR5/R_ODT_CA_A")
			(pintype "passive")
		)
	)
	(footprint "antmicro-footprints:C_0201"
		(layer "B.Cu")
		(at 156.5 88.05)
		(descr "Capacitor SMD 0201")
		(tags "capacitor SMD 0201")
		(property "Reference" "C18"
			(at 2.86 0.31 180)
			(layer "B.SilkS")
			(effects
				(font
					(size 0.7 0.7)
					(thickness 0.15)
				)
				(justify left bottom mirror)
			)
		)
		(property "Value" "C_100n_0201"
			(at 0 -1.4 180)
			(layer "B.Fab")
			(hide yes)
			(effects
				(font
					(size 0.7 0.7)
					(thickness 0.15)
				)
				(justify left bottom mirror)
			)
		)
		(property "Description" "SMD Multilayer Ceramic Capacitor, 0.1 µF, 6.3 V, 0201 [0603 Metric], ± 10%, X6S, CC Series"
			(at 0 0 0)
			(layer "F.Fab")
			(hide yes)
			(effects
				(font
					(size 1.27 1.27)
					(thickness 0.15)
				)
			)
		)
		(property "Author" "Antmicro"
			(at 0 0 0)
			(layer "B.Fab")
			(hide yes)
			(effects
				(font
					(size 1 1)
					(thickness 0.15)
				)
				(justify mirror)
			)
		)
		(property "Dielectric" ""
			(at 0 0 0)
			(layer "B.Fab")
			(hide yes)
			(effects
				(font
					(size 1 1)
					(thickness 0.15)
				)
				(justify mirror)
			)
		)
		(property "License" "Apache-2.0"
			(at 0 0 0)
			(layer "B.Fab")
			(hide yes)
			(effects
				(font
					(size 1 1)
					(thickness 0.15)
				)
				(justify mirror)
			)
		)
		(property "MPN" "CC0201KRX6S5BB104"
			(at 0 0 0)
			(layer "B.Fab")
			(hide yes)
			(effects
				(font
					(size 1 1)
					(thickness 0.15)
				)
				(justify mirror)
			)
		)
		(property "Manufacturer" "YAGEO"
			(at 0 0 0)
			(layer "B.Fab")
			(hide yes)
			(effects
				(font
					(size 1 1)
					(thickness 0.15)
				)
				(justify mirror)
			)
		)
		(property "Public" "False"
			(at 0 0 0)
			(layer "B.Fab")
			(hide yes)
			(effects
				(font
					(size 1 1)
					(thickness 0.15)
				)
				(justify mirror)
			)
		)
		(property "Val" "100n"
			(at 0 0 0)
			(layer "B.Fab")
			(hide yes)
			(effects
				(font
					(size 1 1)
					(thickness 0.15)
				)
				(justify mirror)
			)
		)
		(property "Voltage" ""
			(at 0 0 0)
			(layer "B.Fab")
			(hide yes)
			(effects
				(font
					(size 1 1)
					(thickness 0.15)
				)
				(justify mirror)
			)
		)
		(sheetname "DDR5")
		(sheetfile "ddr5.kicad_sch")
		(attr smd)
		(fp_rect
			(start -0.7 0.35)
			(end 0.7 -0.35)
			(stroke
				(width 0.05)
				(type default)
			)
			(fill no)
			(layer "B.CrtYd")
		)
		(fp_rect
			(start 0.3 -0.15)
			(end -0.301 0.149)
			(stroke
				(width 0.15)
				(type solid)
			)
			(fill no)
			(layer "B.Fab")
		)
		(pad "" smd roundrect
			(at -0.349 0.002)
			(size 0.318 0.36)
			(layers "B.Paste")
			(roundrect_rratio 0.25)
		)
		(pad "" smd roundrect
			(at 0.341 0.002)
			(size 0.318 0.36)
			(layers "B.Paste")
			(roundrect_rratio 0.25)
		)
		(pad "1" smd roundrect
			(at -0.321 0.002)
			(size 0.46 0.4)
			(layers "B.Cu" "B.Mask")
			(roundrect_rratio 0.25)
			(net 2 "VDDQ")
			(pintype "passive")
		)
		(pad "2" smd roundrect
			(at 0.32 0.002)
			(size 0.46 0.4)
			(layers "B.Cu" "B.Mask")
			(roundrect_rratio 0.25)
			(net 1 "GND")
			(pintype "passive")
		)
	)
	(footprint "antmicro-footprints:C_0201"
		(layer "B.Cu")
		(at 153.6 80.425 90)
		(descr "Capacitor SMD 0201")
		(tags "capacitor SMD 0201")
		(property "Reference" "C13"
			(at 3.195 0.39 270)
			(layer "B.SilkS")
			(effects
				(font
					(size 0.7 0.7)
					(thickness 0.15)
				)
				(justify left bottom mirror)
			)
		)
		(property "Value" "C_100n_0201"
			(at 0 -1.4 270)
			(layer "B.Fab")
			(hide yes)
			(effects
				(font
					(size 0.7 0.7)
					(thickness 0.15)
				)
				(justify left bottom mirror)
			)
		)
		(property "Description" "SMD Multilayer Ceramic Capacitor, 0.1 µF, 6.3 V, 0201 [0603 Metric], ± 10%, X6S, CC Series"
			(at 0 0 90)
			(layer "F.Fab")
			(hide yes)
			(effects
				(font
					(size 1.27 1.27)
					(thickness 0.15)
				)
			)
		)
		(property "Author" "Antmicro"
			(at 234.025 -73.175 0)
			(layer "B.Fab")
			(hide yes)
			(effects
				(font
					(size 1 1)
					(thickness 0.15)
				)
				(justify mirror)
			)
		)
		(property "Dielectric" ""
			(at 234.025 -73.175 0)
			(layer "B.Fab")
			(hide yes)
			(effects
				(font
					(size 1 1)
					(thickness 0.15)
				)
				(justify mirror)
			)
		)
		(property "License" "Apache-2.0"
			(at 234.025 -73.175 0)
			(layer "B.Fab")
			(hide yes)
			(effects
				(font
					(size 1 1)
					(thickness 0.15)
				)
				(justify mirror)
			)
		)
		(property "MPN" "CC0201KRX6S5BB104"
			(at 234.025 -73.175 0)
			(layer "B.Fab")
			(hide yes)
			(effects
				(font
					(size 1 1)
					(thickness 0.15)
				)
				(justify mirror)
			)
		)
		(property "Manufacturer" "YAGEO"
			(at 234.025 -73.175 0)
			(layer "B.Fab")
			(hide yes)
			(effects
				(font
					(size 1 1)
					(thickness 0.15)
				)
				(justify mirror)
			)
		)
		(property "Public" "False"
			(at 234.025 -73.175 0)
			(layer "B.Fab")
			(hide yes)
			(effects
				(font
					(size 1 1)
					(thickness 0.15)
				)
				(justify mirror)
			)
		)
		(property "Val" "100n"
			(at 234.025 -73.175 0)
			(layer "B.Fab")
			(hide yes)
			(effects
				(font
					(size 1 1)
					(thickness 0.15)
				)
				(justify mirror)
			)
		)
		(property "Voltage" ""
			(at 234.025 -73.175 0)
			(layer "B.Fab")
			(hide yes)
			(effects
				(font
					(size 1 1)
					(thickness 0.15)
				)
				(justify mirror)
			)
		)
		(sheetname "DDR5")
		(sheetfile "ddr5.kicad_sch")
		(attr smd)
		(fp_rect
			(start -0.7 0.35)
			(end 0.7 -0.35)
			(stroke
				(width 0.05)
				(type default)
			)
			(fill no)
			(layer "B.CrtYd")
		)
		(fp_rect
			(start 0.3 -0.15)
			(end -0.301 0.149)
			(stroke
				(width 0.15)
				(type solid)
			)
			(fill no)
			(layer "B.Fab")
		)
		(pad "" smd roundrect
			(at -0.349 0.002 90)
			(size 0.318 0.36)
			(layers "B.Paste")
			(roundrect_rratio 0.25)
		)
		(pad "" smd roundrect
			(at 0.341 0.002 90)
			(size 0.318 0.36)
			(layers "B.Paste")
			(roundrect_rratio 0.25)
		)
		(pad "1" smd roundrect
			(at -0.321 0.002 90)
			(size 0.46 0.4)
			(layers "B.Cu" "B.Mask")
			(roundrect_rratio 0.25)
			(net 2 "VDDQ")
			(pintype "passive")
		)
		(pad "2" smd roundrect
			(at 0.32 0.002 90)
			(size 0.46 0.4)
			(layers "B.Cu" "B.Mask")
			(roundrect_rratio 0.25)
			(net 1 "GND")
			(pintype "passive")
		)
	)
	(footprint "antmicro-footprints:C_0201"
		(layer "B.Cu")
		(at 148.02 80.55 90)
		(descr "Capacitor SMD 0201")
		(tags "capacitor SMD 0201")
		(property "Reference" "C7"
			(at 2.95 0.32 270)
			(layer "B.SilkS")
			(effects
				(font
					(size 0.7 0.7)
					(thickness 0.15)
				)
				(justify left bottom mirror)
			)
		)
		(property "Value" "C_100n_0201"
			(at 0 -1.4 270)
			(layer "B.Fab")
			(hide yes)
			(effects
				(font
					(size 0.7 0.7)
					(thickness 0.15)
				)
				(justify left bottom mirror)
			)
		)
		(property "Description" "SMD Multilayer Ceramic Capacitor, 0.1 µF, 6.3 V, 0201 [0603 Metric], ± 10%, X6S, CC Series"
			(at 0 0 90)
			(layer "F.Fab")
			(hide yes)
			(effects
				(font
					(size 1.27 1.27)
					(thickness 0.15)
				)
			)
		)
		(property "Author" "Antmicro"
			(at 228.57 -67.47 0)
			(layer "B.Fab")
			(hide yes)
			(effects
				(font
					(size 1 1)
					(thickness 0.15)
				)
				(justify mirror)
			)
		)
		(property "Dielectric" ""
			(at 228.57 -67.47 0)
			(layer "B.Fab")
			(hide yes)
			(effects
				(font
					(size 1 1)
					(thickness 0.15)
				)
				(justify mirror)
			)
		)
		(property "License" "Apache-2.0"
			(at 228.57 -67.47 0)
			(layer "B.Fab")
			(hide yes)
			(effects
				(font
					(size 1 1)
					(thickness 0.15)
				)
				(justify mirror)
			)
		)
		(property "MPN" "CC0201KRX6S5BB104"
			(at 228.57 -67.47 0)
			(layer "B.Fab")
			(hide yes)
			(effects
				(font
					(size 1 1)
					(thickness 0.15)
				)
				(justify mirror)
			)
		)
		(property "Manufacturer" "YAGEO"
			(at 228.57 -67.47 0)
			(layer "B.Fab")
			(hide yes)
			(effects
				(font
					(size 1 1)
					(thickness 0.15)
				)
				(justify mirror)
			)
		)
		(property "Public" "False"
			(at 228.57 -67.47 0)
			(layer "B.Fab")
			(hide yes)
			(effects
				(font
					(size 1 1)
					(thickness 0.15)
				)
				(justify mirror)
			)
		)
		(property "Val" "100n"
			(at 228.57 -67.47 0)
			(layer "B.Fab")
			(hide yes)
			(effects
				(font
					(size 1 1)
					(thickness 0.15)
				)
				(justify mirror)
			)
		)
		(property "Voltage" ""
			(at 228.57 -67.47 0)
			(layer "B.Fab")
			(hide yes)
			(effects
				(font
					(size 1 1)
					(thickness 0.15)
				)
				(justify mirror)
			)
		)
		(sheetname "DDR5")
		(sheetfile "ddr5.kicad_sch")
		(attr smd)
		(fp_rect
			(start -0.7 0.35)
			(end 0.7 -0.35)
			(stroke
				(width 0.05)
				(type default)
			)
			(fill no)
			(layer "B.CrtYd")
		)
		(fp_rect
			(start 0.3 -0.15)
			(end -0.301 0.149)
			(stroke
				(width 0.15)
				(type solid)
			)
			(fill no)
			(layer "B.Fab")
		)
		(pad "" smd roundrect
			(at -0.349 0.002 90)
			(size 0.318 0.36)
			(layers "B.Paste")
			(roundrect_rratio 0.25)
		)
		(pad "" smd roundrect
			(at 0.341 0.002 90)
			(size 0.318 0.36)
			(layers "B.Paste")
			(roundrect_rratio 0.25)
		)
		(pad "1" smd roundrect
			(at -0.321 0.002 90)
			(size 0.46 0.4)
			(layers "B.Cu" "B.Mask")
			(roundrect_rratio 0.25)
			(net 2 "VDDQ")
			(pintype "passive")
		)
		(pad "2" smd roundrect
			(at 0.32 0.002 90)
			(size 0.46 0.4)
			(layers "B.Cu" "B.Mask")
			(roundrect_rratio 0.25)
			(net 1 "GND")
			(pintype "passive")
		)
	)
	(footprint "antmicro-footprints:C_0201"
		(layer "B.Cu")
		(at 156.5 88.85)
		(descr "Capacitor SMD 0201")
		(tags "capacitor SMD 0201")
		(property "Reference" "C3"
			(at 2.86 0.37 180)
			(layer "B.SilkS")
			(effects
				(font
					(size 0.7 0.7)
					(thickness 0.15)
				)
				(justify left bottom mirror)
			)
		)
		(property "Value" "C_100n_0201"
			(at 0 -1.4 180)
			(layer "B.Fab")
			(hide yes)
			(effects
				(font
					(size 0.7 0.7)
					(thickness 0.15)
				)
				(justify left bottom mirror)
			)
		)
		(property "Description" "SMD Multilayer Ceramic Capacitor, 0.1 µF, 6.3 V, 0201 [0603 Metric], ± 10%, X6S, CC Series"
			(at 0 0 0)
			(layer "F.Fab")
			(hide yes)
			(effects
				(font
					(size 1.27 1.27)
					(thickness 0.15)
				)
			)
		)
		(property "Author" "Antmicro"
			(at 0 0 0)
			(layer "B.Fab")
			(hide yes)
			(effects
				(font
					(size 1 1)
					(thickness 0.15)
				)
				(justify mirror)
			)
		)
		(property "Dielectric" ""
			(at 0 0 0)
			(layer "B.Fab")
			(hide yes)
			(effects
				(font
					(size 1 1)
					(thickness 0.15)
				)
				(justify mirror)
			)
		)
		(property "License" "Apache-2.0"
			(at 0 0 0)
			(layer "B.Fab")
			(hide yes)
			(effects
				(font
					(size 1 1)
					(thickness 0.15)
				)
				(justify mirror)
			)
		)
		(property "MPN" "CC0201KRX6S5BB104"
			(at 0 0 0)
			(layer "B.Fab")
			(hide yes)
			(effects
				(font
					(size 1 1)
					(thickness 0.15)
				)
				(justify mirror)
			)
		)
		(property "Manufacturer" "YAGEO"
			(at 0 0 0)
			(layer "B.Fab")
			(hide yes)
			(effects
				(font
					(size 1 1)
					(thickness 0.15)
				)
				(justify mirror)
			)
		)
		(property "Public" "False"
			(at 0 0 0)
			(layer "B.Fab")
			(hide yes)
			(effects
				(font
					(size 1 1)
					(thickness 0.15)
				)
				(justify mirror)
			)
		)
		(property "Val" "100n"
			(at 0 0 0)
			(layer "B.Fab")
			(hide yes)
			(effects
				(font
					(size 1 1)
					(thickness 0.15)
				)
				(justify mirror)
			)
		)
		(property "Voltage" ""
			(at 0 0 0)
			(layer "B.Fab")
			(hide yes)
			(effects
				(font
					(size 1 1)
					(thickness 0.15)
				)
				(justify mirror)
			)
		)
		(sheetname "DDR5")
		(sheetfile "ddr5.kicad_sch")
		(attr smd)
		(fp_rect
			(start -0.7 0.35)
			(end 0.7 -0.35)
			(stroke
				(width 0.05)
				(type default)
			)
			(fill no)
			(layer "B.CrtYd")
		)
		(fp_rect
			(start 0.3 -0.15)
			(end -0.301 0.149)
			(stroke
				(width 0.15)
				(type solid)
			)
			(fill no)
			(layer "B.Fab")
		)
		(pad "" smd roundrect
			(at -0.349 0.002)
			(size 0.318 0.36)
			(layers "B.Paste")
			(roundrect_rratio 0.25)
		)
		(pad "" smd roundrect
			(at 0.341 0.002)
			(size 0.318 0.36)
			(layers "B.Paste")
			(roundrect_rratio 0.25)
		)
		(pad "1" smd roundrect
			(at -0.321 0.002)
			(size 0.46 0.4)
			(layers "B.Cu" "B.Mask")
			(roundrect_rratio 0.25)
			(net 18 "VDD")
			(pintype "passive")
		)
		(pad "2" smd roundrect
			(at 0.32 0.002)
			(size 0.46 0.4)
			(layers "B.Cu" "B.Mask")
			(roundrect_rratio 0.25)
			(net 1 "GND")
			(pintype "passive")
		)
	)
	(footprint "antmicro-footprints:C_0201"
		(layer "B.Cu")
		(at 153.3 82.45)
		(descr "Capacitor SMD 0201")
		(tags "capacitor SMD 0201")
		(property "Reference" "C4"
			(at 0.78 -0.38 180)
			(layer "B.SilkS")
			(effects
				(font
					(size 0.7 0.7)
					(thickness 0.15)
				)
				(justify left bottom mirror)
			)
		)
		(property "Value" "C_100n_0201"
			(at 0 -1.4 180)
			(layer "B.Fab")
			(hide yes)
			(effects
				(font
					(size 0.7 0.7)
					(thickness 0.15)
				)
				(justify left bottom mirror)
			)
		)
		(property "Description" "SMD Multilayer Ceramic Capacitor, 0.1 µF, 6.3 V, 0201 [0603 Metric], ± 10%, X6S, CC Series"
			(at 0 0 0)
			(layer "F.Fab")
			(hide yes)
			(effects
				(font
					(size 1.27 1.27)
					(thickness 0.15)
				)
			)
		)
		(property "Author" "Antmicro"
			(at 0 0 0)
			(layer "B.Fab")
			(hide yes)
			(effects
				(font
					(size 1 1)
					(thickness 0.15)
				)
				(justify mirror)
			)
		)
		(property "Dielectric" ""
			(at 0 0 0)
			(layer "B.Fab")
			(hide yes)
			(effects
				(font
					(size 1 1)
					(thickness 0.15)
				)
				(justify mirror)
			)
		)
		(property "License" "Apache-2.0"
			(at 0 0 0)
			(layer "B.Fab")
			(hide yes)
			(effects
				(font
					(size 1 1)
					(thickness 0.15)
				)
				(justify mirror)
			)
		)
		(property "MPN" "CC0201KRX6S5BB104"
			(at 0 0 0)
			(layer "B.Fab")
			(hide yes)
			(effects
				(font
					(size 1 1)
					(thickness 0.15)
				)
				(justify mirror)
			)
		)
		(property "Manufacturer" "YAGEO"
			(at 0 0 0)
			(layer "B.Fab")
			(hide yes)
			(effects
				(font
					(size 1 1)
					(thickness 0.15)
				)
				(justify mirror)
			)
		)
		(property "Public" "False"
			(at 0 0 0)
			(layer "B.Fab")
			(hide yes)
			(effects
				(font
					(size 1 1)
					(thickness 0.15)
				)
				(justify mirror)
			)
		)
		(property "Val" "100n"
			(at 0 0 0)
			(layer "B.Fab")
			(hide yes)
			(effects
				(font
					(size 1 1)
					(thickness 0.15)
				)
				(justify mirror)
			)
		)
		(property "Voltage" ""
			(at 0 0 0)
			(layer "B.Fab")
			(hide yes)
			(effects
				(font
					(size 1 1)
					(thickness 0.15)
				)
				(justify mirror)
			)
		)
		(sheetname "DDR5")
		(sheetfile "ddr5.kicad_sch")
		(attr smd)
		(fp_rect
			(start -0.7 0.35)
			(end 0.7 -0.35)
			(stroke
				(width 0.05)
				(type default)
			)
			(fill no)
			(layer "B.CrtYd")
		)
		(fp_rect
			(start 0.3 -0.15)
			(end -0.301 0.149)
			(stroke
				(width 0.15)
				(type solid)
			)
			(fill no)
			(layer "B.Fab")
		)
		(pad "" smd roundrect
			(at -0.349 0.002)
			(size 0.318 0.36)
			(layers "B.Paste")
			(roundrect_rratio 0.25)
		)
		(pad "" smd roundrect
			(at 0.341 0.002)
			(size 0.318 0.36)
			(layers "B.Paste")
			(roundrect_rratio 0.25)
		)
		(pad "1" smd roundrect
			(at -0.321 0.002)
			(size 0.46 0.4)
			(layers "B.Cu" "B.Mask")
			(roundrect_rratio 0.25)
			(net 2 "VDDQ")
			(pintype "passive")
		)
		(pad "2" smd roundrect
			(at 0.32 0.002)
			(size 0.46 0.4)
			(layers "B.Cu" "B.Mask")
			(roundrect_rratio 0.25)
			(net 1 "GND")
			(pintype "passive")
		)
	)
	(footprint "antmicro-footprints:C_0201"
		(layer "B.Cu")
		(at 145.3 82.1 -90)
		(descr "Capacitor SMD 0201")
		(tags "capacitor SMD 0201")
		(property "Reference" "C6"
			(at -0.9 0.52 90)
			(layer "B.SilkS")
			(effects
				(font
					(size 0.7 0.7)
					(thickness 0.15)
				)
				(justify left bottom mirror)
			)
		)
		(property "Value" "C_100n_0201"
			(at 0 -1.4 90)
			(layer "B.Fab")
			(hide yes)
			(effects
				(font
					(size 0.7 0.7)
					(thickness 0.15)
				)
				(justify left bottom mirror)
			)
		)
		(property "Description" "SMD Multilayer Ceramic Capacitor, 0.1 µF, 6.3 V, 0201 [0603 Metric], ± 10%, X6S, CC Series"
			(at 0 0 270)
			(layer "F.Fab")
			(hide yes)
			(effects
				(font
					(size 1.27 1.27)
					(thickness 0.15)
				)
			)
		)
		(property "Author" "Antmicro"
			(at 63.2 227.4 0)
			(layer "B.Fab")
			(hide yes)
			(effects
				(font
					(size 1 1)
					(thickness 0.15)
				)
				(justify mirror)
			)
		)
		(property "Dielectric" ""
			(at 63.2 227.4 0)
			(layer "B.Fab")
			(hide yes)
			(effects
				(font
					(size 1 1)
					(thickness 0.15)
				)
				(justify mirror)
			)
		)
		(property "License" "Apache-2.0"
			(at 63.2 227.4 0)
			(layer "B.Fab")
			(hide yes)
			(effects
				(font
					(size 1 1)
					(thickness 0.15)
				)
				(justify mirror)
			)
		)
		(property "MPN" "CC0201KRX6S5BB104"
			(at 63.2 227.4 0)
			(layer "B.Fab")
			(hide yes)
			(effects
				(font
					(size 1 1)
					(thickness 0.15)
				)
				(justify mirror)
			)
		)
		(property "Manufacturer" "YAGEO"
			(at 63.2 227.4 0)
			(layer "B.Fab")
			(hide yes)
			(effects
				(font
					(size 1 1)
					(thickness 0.15)
				)
				(justify mirror)
			)
		)
		(property "Public" "False"
			(at 63.2 227.4 0)
			(layer "B.Fab")
			(hide yes)
			(effects
				(font
					(size 1 1)
					(thickness 0.15)
				)
				(justify mirror)
			)
		)
		(property "Val" "100n"
			(at 63.2 227.4 0)
			(layer "B.Fab")
			(hide yes)
			(effects
				(font
					(size 1 1)
					(thickness 0.15)
				)
				(justify mirror)
			)
		)
		(property "Voltage" ""
			(at 63.2 227.4 0)
			(layer "B.Fab")
			(hide yes)
			(effects
				(font
					(size 1 1)
					(thickness 0.15)
				)
				(justify mirror)
			)
		)
		(sheetname "DDR5")
		(sheetfile "ddr5.kicad_sch")
		(attr smd)
		(fp_rect
			(start -0.7 0.35)
			(end 0.7 -0.35)
			(stroke
				(width 0.05)
				(type default)
			)
			(fill no)
			(layer "B.CrtYd")
		)
		(fp_rect
			(start 0.3 -0.15)
			(end -0.301 0.149)
			(stroke
				(width 0.15)
				(type solid)
			)
			(fill no)
			(layer "B.Fab")
		)
		(pad "" smd roundrect
			(at -0.349 0.002 270)
			(size 0.318 0.36)
			(layers "B.Paste")
			(roundrect_rratio 0.25)
		)
		(pad "" smd roundrect
			(at 0.341 0.002 270)
			(size 0.318 0.36)
			(layers "B.Paste")
			(roundrect_rratio 0.25)
		)
		(pad "1" smd roundrect
			(at -0.321 0.002 270)
			(size 0.46 0.4)
			(layers "B.Cu" "B.Mask")
			(roundrect_rratio 0.25)
			(net 18 "VDD")
			(pintype "passive")
		)
		(pad "2" smd roundrect
			(at 0.32 0.002 270)
			(size 0.46 0.4)
			(layers "B.Cu" "B.Mask")
			(roundrect_rratio 0.25)
			(net 1 "GND")
			(pintype "passive")
		)
	)
	(footprint "antmicro-footprints:C_0201"
		(layer "B.Cu")
		(at 149.15 88.05 180)
		(descr "Capacitor SMD 0201")
		(tags "capacitor SMD 0201")
		(property "Reference" "C8"
			(at -0.85 -2.04 0)
			(layer "B.SilkS")
			(effects
				(font
					(size 0.7 0.7)
					(thickness 0.15)
				)
				(justify left bottom mirror)
			)
		)
		(property "Value" "C_100n_0201"
			(at 0 -1.4 0)
			(layer "B.Fab")
			(hide yes)
			(effects
				(font
					(size 0.7 0.7)
					(thickness 0.15)
				)
				(justify left bottom mirror)
			)
		)
		(property "Description" "SMD Multilayer Ceramic Capacitor, 0.1 µF, 6.3 V, 0201 [0603 Metric], ± 10%, X6S, CC Series"
			(at 0 0 180)
			(layer "F.Fab")
			(hide yes)
			(effects
				(font
					(size 1.27 1.27)
					(thickness 0.15)
				)
			)
		)
		(property "Author" "Antmicro"
			(at 298.3 176.1 0)
			(layer "B.Fab")
			(hide yes)
			(effects
				(font
					(size 1 1)
					(thickness 0.15)
				)
				(justify mirror)
			)
		)
		(property "Dielectric" ""
			(at 298.3 176.1 0)
			(layer "B.Fab")
			(hide yes)
			(effects
				(font
					(size 1 1)
					(thickness 0.15)
				)
				(justify mirror)
			)
		)
		(property "License" "Apache-2.0"
			(at 298.3 176.1 0)
			(layer "B.Fab")
			(hide yes)
			(effects
				(font
					(size 1 1)
					(thickness 0.15)
				)
				(justify mirror)
			)
		)
		(property "MPN" "CC0201KRX6S5BB104"
			(at 298.3 176.1 0)
			(layer "B.Fab")
			(hide yes)
			(effects
				(font
					(size 1 1)
					(thickness 0.15)
				)
				(justify mirror)
			)
		)
		(property "Manufacturer" "YAGEO"
			(at 298.3 176.1 0)
			(layer "B.Fab")
			(hide yes)
			(effects
				(font
					(size 1 1)
					(thickness 0.15)
				)
				(justify mirror)
			)
		)
		(property "Public" "False"
			(at 298.3 176.1 0)
			(layer "B.Fab")
			(hide yes)
			(effects
				(font
					(size 1 1)
					(thickness 0.15)
				)
				(justify mirror)
			)
		)
		(property "Val" "100n"
			(at 298.3 176.1 0)
			(layer "B.Fab")
			(hide yes)
			(effects
				(font
					(size 1 1)
					(thickness 0.15)
				)
				(justify mirror)
			)
		)
		(property "Voltage" ""
			(at 298.3 176.1 0)
			(layer "B.Fab")
			(hide yes)
			(effects
				(font
					(size 1 1)
					(thickness 0.15)
				)
				(justify mirror)
			)
		)
		(sheetname "DDR5")
		(sheetfile "ddr5.kicad_sch")
		(attr smd)
		(fp_rect
			(start -0.7 0.35)
			(end 0.7 -0.35)
			(stroke
				(width 0.05)
				(type default)
			)
			(fill no)
			(layer "B.CrtYd")
		)
		(fp_rect
			(start 0.3 -0.15)
			(end -0.301 0.149)
			(stroke
				(width 0.15)
				(type solid)
			)
			(fill no)
			(layer "B.Fab")
		)
		(pad "" smd roundrect
			(at -0.349 0.002 180)
			(size 0.318 0.36)
			(layers "B.Paste")
			(roundrect_rratio 0.25)
		)
		(pad "" smd roundrect
			(at 0.341 0.002 180)
			(size 0.318 0.36)
			(layers "B.Paste")
			(roundrect_rratio 0.25)
		)
		(pad "1" smd roundrect
			(at -0.321 0.002 180)
			(size 0.46 0.4)
			(layers "B.Cu" "B.Mask")
			(roundrect_rratio 0.25)
			(net 2 "VDDQ")
			(pintype "passive")
		)
		(pad "2" smd roundrect
			(at 0.32 0.002 180)
			(size 0.46 0.4)
			(layers "B.Cu" "B.Mask")
			(roundrect_rratio 0.25)
			(net 1 "GND")
			(pintype "passive")
		)
	)
	(footprint "antmicro-footprints:C_0201"
		(layer "B.Cu")
		(at 148.82 80.55 90)
		(descr "Capacitor SMD 0201")
		(tags "capacitor SMD 0201")
		(property "Reference" "C9"
			(at 2.95 0.385 270)
			(layer "B.SilkS")
			(effects
				(font
					(size 0.7 0.7)
					(thickness 0.15)
				)
				(justify left bottom mirror)
			)
		)
		(property "Value" "C_100n_0201"
			(at 0 -1.4 270)
			(layer "B.Fab")
			(hide yes)
			(effects
				(font
					(size 0.7 0.7)
					(thickness 0.15)
				)
				(justify left bottom mirror)
			)
		)
		(property "Description" "SMD Multilayer Ceramic Capacitor, 0.1 µF, 6.3 V, 0201 [0603 Metric], ± 10%, X6S, CC Series"
			(at 0 0 90)
			(layer "F.Fab")
			(hide yes)
			(effects
				(font
					(size 1.27 1.27)
					(thickness 0.15)
				)
			)
		)
		(property "Author" "Antmicro"
			(at 229.37 -68.27 0)
			(layer "B.Fab")
			(hide yes)
			(effects
				(font
					(size 1 1)
					(thickness 0.15)
				)
				(justify mirror)
			)
		)
		(property "Dielectric" ""
			(at 229.37 -68.27 0)
			(layer "B.Fab")
			(hide yes)
			(effects
				(font
					(size 1 1)
					(thickness 0.15)
				)
				(justify mirror)
			)
		)
		(property "License" "Apache-2.0"
			(at 229.37 -68.27 0)
			(layer "B.Fab")
			(hide yes)
			(effects
				(font
					(size 1 1)
					(thickness 0.15)
				)
				(justify mirror)
			)
		)
		(property "MPN" "CC0201KRX6S5BB104"
			(at 229.37 -68.27 0)
			(layer "B.Fab")
			(hide yes)
			(effects
				(font
					(size 1 1)
					(thickness 0.15)
				)
				(justify mirror)
			)
		)
		(property "Manufacturer" "YAGEO"
			(at 229.37 -68.27 0)
			(layer "B.Fab")
			(hide yes)
			(effects
				(font
					(size 1 1)
					(thickness 0.15)
				)
				(justify mirror)
			)
		)
		(property "Public" "False"
			(at 229.37 -68.27 0)
			(layer "B.Fab")
			(hide yes)
			(effects
				(font
					(size 1 1)
					(thickness 0.15)
				)
				(justify mirror)
			)
		)
		(property "Val" "100n"
			(at 229.37 -68.27 0)
			(layer "B.Fab")
			(hide yes)
			(effects
				(font
					(size 1 1)
					(thickness 0.15)
				)
				(justify mirror)
			)
		)
		(property "Voltage" ""
			(at 229.37 -68.27 0)
			(layer "B.Fab")
			(hide yes)
			(effects
				(font
					(size 1 1)
					(thickness 0.15)
				)
				(justify mirror)
			)
		)
		(sheetname "DDR5")
		(sheetfile "ddr5.kicad_sch")
		(attr smd)
		(fp_rect
			(start -0.7 0.35)
			(end 0.7 -0.35)
			(stroke
				(width 0.05)
				(type default)
			)
			(fill no)
			(layer "B.CrtYd")
		)
		(fp_rect
			(start 0.3 -0.15)
			(end -0.301 0.149)
			(stroke
				(width 0.15)
				(type solid)
			)
			(fill no)
			(layer "B.Fab")
		)
		(pad "" smd roundrect
			(at -0.349 0.002 90)
			(size 0.318 0.36)
			(layers "B.Paste")
			(roundrect_rratio 0.25)
		)
		(pad "" smd roundrect
			(at 0.341 0.002 90)
			(size 0.318 0.36)
			(layers "B.Paste")
			(roundrect_rratio 0.25)
		)
		(pad "1" smd roundrect
			(at -0.321 0.002 90)
			(size 0.46 0.4)
			(layers "B.Cu" "B.Mask")
			(roundrect_rratio 0.25)
			(net 18 "VDD")
			(pintype "passive")
		)
		(pad "2" smd roundrect
			(at 0.32 0.002 90)
			(size 0.46 0.4)
			(layers "B.Cu" "B.Mask")
			(roundrect_rratio 0.25)
			(net 1 "GND")
			(pintype "passive")
		)
	)
	(footprint "antmicro-footprints:C_0201"
		(layer "B.Cu")
		(at 145.3 83.6 90)
		(descr "Capacitor SMD 0201")
		(tags "capacitor SMD 0201")
		(property "Reference" "C26"
			(at 0.97 -0.53 270)
			(layer "B.SilkS")
			(effects
				(font
					(size 0.7 0.7)
					(thickness 0.15)
				)
				(justify left bottom mirror)
			)
		)
		(property "Value" "C_100n_0201"
			(at 0 -1.4 270)
			(layer "B.Fab")
			(hide yes)
			(effects
				(font
					(size 0.7 0.7)
					(thickness 0.15)
				)
				(justify left bottom mirror)
			)
		)
		(property "Description" "SMD Multilayer Ceramic Capacitor, 0.1 µF, 6.3 V, 0201 [0603 Metric], ± 10%, X6S, CC Series"
			(at 0 0 90)
			(layer "F.Fab")
			(hide yes)
			(effects
				(font
					(size 1.27 1.27)
					(thickness 0.15)
				)
			)
		)
		(property "Author" "Antmicro"
			(at 228.9 -61.7 0)
			(layer "B.Fab")
			(hide yes)
			(effects
				(font
					(size 1 1)
					(thickness 0.15)
				)
				(justify mirror)
			)
		)
		(property "Dielectric" ""
			(at 228.9 -61.7 0)
			(layer "B.Fab")
			(hide yes)
			(effects
				(font
					(size 1 1)
					(thickness 0.15)
				)
				(justify mirror)
			)
		)
		(property "License" "Apache-2.0"
			(at 228.9 -61.7 0)
			(layer "B.Fab")
			(hide yes)
			(effects
				(font
					(size 1 1)
					(thickness 0.15)
				)
				(justify mirror)
			)
		)
		(property "MPN" "CC0201KRX6S5BB104"
			(at 228.9 -61.7 0)
			(layer "B.Fab")
			(hide yes)
			(effects
				(font
					(size 1 1)
					(thickness 0.15)
				)
				(justify mirror)
			)
		)
		(property "Manufacturer" "YAGEO"
			(at 228.9 -61.7 0)
			(layer "B.Fab")
			(hide yes)
			(effects
				(font
					(size 1 1)
					(thickness 0.15)
				)
				(justify mirror)
			)
		)
		(property "Public" "False"
			(at 228.9 -61.7 0)
			(layer "B.Fab")
			(hide yes)
			(effects
				(font
					(size 1 1)
					(thickness 0.15)
				)
				(justify mirror)
			)
		)
		(property "Val" "100n"
			(at 228.9 -61.7 0)
			(layer "B.Fab")
			(hide yes)
			(effects
				(font
					(size 1 1)
					(thickness 0.15)
				)
				(justify mirror)
			)
		)
		(property "Voltage" ""
			(at 228.9 -61.7 0)
			(layer "B.Fab")
			(hide yes)
			(effects
				(font
					(size 1 1)
					(thickness 0.15)
				)
				(justify mirror)
			)
		)
		(sheetname "DDR5")
		(sheetfile "ddr5.kicad_sch")
		(attr smd)
		(fp_rect
			(start -0.7 0.35)
			(end 0.7 -0.35)
			(stroke
				(width 0.05)
				(type default)
			)
			(fill no)
			(layer "B.CrtYd")
		)
		(fp_rect
			(start 0.3 -0.15)
			(end -0.301 0.149)
			(stroke
				(width 0.15)
				(type solid)
			)
			(fill no)
			(layer "B.Fab")
		)
		(pad "" smd roundrect
			(at -0.349 0.002 90)
			(size 0.318 0.36)
			(layers "B.Paste")
			(roundrect_rratio 0.25)
		)
		(pad "" smd roundrect
			(at 0.341 0.002 90)
			(size 0.318 0.36)
			(layers "B.Paste")
			(roundrect_rratio 0.25)
		)
		(pad "1" smd roundrect
			(at -0.321 0.002 90)
			(size 0.46 0.4)
			(layers "B.Cu" "B.Mask")
			(roundrect_rratio 0.25)
			(net 18 "VDD")
			(pintype "passive")
		)
		(pad "2" smd roundrect
			(at 0.32 0.002 90)
			(size 0.46 0.4)
			(layers "B.Cu" "B.Mask")
			(roundrect_rratio 0.25)
			(net 1 "GND")
			(pintype "passive")
		)
	)
	(footprint "antmicro-footprints:C_0201"
		(layer "B.Cu")
		(at 152.425 88.025 180)
		(descr "Capacitor SMD 0201")
		(tags "capacitor SMD 0201")
		(property "Reference" "C10"
			(at -1.175 -2.07 0)
			(layer "B.SilkS")
			(effects
				(font
					(size 0.7 0.7)
					(thickness 0.15)
				)
				(justify left bottom mirror)
			)
		)
		(property "Value" "C_100n_0201"
			(at 0 -1.4 0)
			(layer "B.Fab")
			(hide yes)
			(effects
				(font
					(size 0.7 0.7)
					(thickness 0.15)
				)
				(justify left bottom mirror)
			)
		)
		(property "Description" "SMD Multilayer Ceramic Capacitor, 0.1 µF, 6.3 V, 0201 [0603 Metric], ± 10%, X6S, CC Series"
			(at 0 0 180)
			(layer "F.Fab")
			(hide yes)
			(effects
				(font
					(size 1.27 1.27)
					(thickness 0.15)
				)
			)
		)
		(property "Author" "Antmicro"
			(at 304.85 176.05 0)
			(layer "B.Fab")
			(hide yes)
			(effects
				(font
					(size 1 1)
					(thickness 0.15)
				)
				(justify mirror)
			)
		)
		(property "Dielectric" ""
			(at 304.85 176.05 0)
			(layer "B.Fab")
			(hide yes)
			(effects
				(font
					(size 1 1)
					(thickness 0.15)
				)
				(justify mirror)
			)
		)
		(property "License" "Apache-2.0"
			(at 304.85 176.05 0)
			(layer "B.Fab")
			(hide yes)
			(effects
				(font
					(size 1 1)
					(thickness 0.15)
				)
				(justify mirror)
			)
		)
		(property "MPN" "CC0201KRX6S5BB104"
			(at 304.85 176.05 0)
			(layer "B.Fab")
			(hide yes)
			(effects
				(font
					(size 1 1)
					(thickness 0.15)
				)
				(justify mirror)
			)
		)
		(property "Manufacturer" "YAGEO"
			(at 304.85 176.05 0)
			(layer "B.Fab")
			(hide yes)
			(effects
				(font
					(size 1 1)
					(thickness 0.15)
				)
				(justify mirror)
			)
		)
		(property "Public" "False"
			(at 304.85 176.05 0)
			(layer "B.Fab")
			(hide yes)
			(effects
				(font
					(size 1 1)
					(thickness 0.15)
				)
				(justify mirror)
			)
		)
		(property "Val" "100n"
			(at 304.85 176.05 0)
			(layer "B.Fab")
			(hide yes)
			(effects
				(font
					(size 1 1)
					(thickness 0.15)
				)
				(justify mirror)
			)
		)
		(property "Voltage" ""
			(at 304.85 176.05 0)
			(layer "B.Fab")
			(hide yes)
			(effects
				(font
					(size 1 1)
					(thickness 0.15)
				)
				(justify mirror)
			)
		)
		(sheetname "DDR5")
		(sheetfile "ddr5.kicad_sch")
		(attr smd)
		(fp_rect
			(start -0.7 0.35)
			(end 0.7 -0.35)
			(stroke
				(width 0.05)
				(type default)
			)
			(fill no)
			(layer "B.CrtYd")
		)
		(fp_rect
			(start 0.3 -0.15)
			(end -0.301 0.149)
			(stroke
				(width 0.15)
				(type solid)
			)
			(fill no)
			(layer "B.Fab")
		)
		(pad "" smd roundrect
			(at -0.349 0.002 180)
			(size 0.318 0.36)
			(layers "B.Paste")
			(roundrect_rratio 0.25)
		)
		(pad "" smd roundrect
			(at 0.341 0.002 180)
			(size 0.318 0.36)
			(layers "B.Paste")
			(roundrect_rratio 0.25)
		)
		(pad "1" smd roundrect
			(at -0.321 0.002 180)
			(size 0.46 0.4)
			(layers "B.Cu" "B.Mask")
			(roundrect_rratio 0.25)
			(net 2 "VDDQ")
			(pintype "passive")
		)
		(pad "2" smd roundrect
			(at 0.32 0.002 180)
			(size 0.46 0.4)
			(layers "B.Cu" "B.Mask")
			(roundrect_rratio 0.25)
			(net 1 "GND")
			(pintype "passive")
		)
	)
	(footprint "antmicro-footprints:C_0201"
		(layer "B.Cu")
		(at 149.625 80.55 90)
		(descr "Capacitor SMD 0201")
		(tags "capacitor SMD 0201")
		(property "Reference" "C11"
			(at 2.95 0.445 270)
			(layer "B.SilkS")
			(effects
				(font
					(size 0.7 0.7)
					(thickness 0.15)
				)
				(justify left bottom mirror)
			)
		)
		(property "Value" "C_100n_0201"
			(at 0 -1.4 270)
			(layer "B.Fab")
			(hide yes)
			(effects
				(font
					(size 0.7 0.7)
					(thickness 0.15)
				)
				(justify left bottom mirror)
			)
		)
		(property "Description" "SMD Multilayer Ceramic Capacitor, 0.1 µF, 6.3 V, 0201 [0603 Metric], ± 10%, X6S, CC Series"
			(at 0 0 90)
			(layer "F.Fab")
			(hide yes)
			(effects
				(font
					(size 1.27 1.27)
					(thickness 0.15)
				)
			)
		)
		(property "Author" "Antmicro"
			(at 230.175 -69.075 0)
			(layer "B.Fab")
			(hide yes)
			(effects
				(font
					(size 1 1)
					(thickness 0.15)
				)
				(justify mirror)
			)
		)
		(property "Dielectric" ""
			(at 230.175 -69.075 0)
			(layer "B.Fab")
			(hide yes)
			(effects
				(font
					(size 1 1)
					(thickness 0.15)
				)
				(justify mirror)
			)
		)
		(property "License" "Apache-2.0"
			(at 230.175 -69.075 0)
			(layer "B.Fab")
			(hide yes)
			(effects
				(font
					(size 1 1)
					(thickness 0.15)
				)
				(justify mirror)
			)
		)
		(property "MPN" "CC0201KRX6S5BB104"
			(at 230.175 -69.075 0)
			(layer "B.Fab")
			(hide yes)
			(effects
				(font
					(size 1 1)
					(thickness 0.15)
				)
				(justify mirror)
			)
		)
		(property "Manufacturer" "YAGEO"
			(at 230.175 -69.075 0)
			(layer "B.Fab")
			(hide yes)
			(effects
				(font
					(size 1 1)
					(thickness 0.15)
				)
				(justify mirror)
			)
		)
		(property "Public" "False"
			(at 230.175 -69.075 0)
			(layer "B.Fab")
			(hide yes)
			(effects
				(font
					(size 1 1)
					(thickness 0.15)
				)
				(justify mirror)
			)
		)
		(property "Val" "100n"
			(at 230.175 -69.075 0)
			(layer "B.Fab")
			(hide yes)
			(effects
				(font
					(size 1 1)
					(thickness 0.15)
				)
				(justify mirror)
			)
		)
		(property "Voltage" ""
			(at 230.175 -69.075 0)
			(layer "B.Fab")
			(hide yes)
			(effects
				(font
					(size 1 1)
					(thickness 0.15)
				)
				(justify mirror)
			)
		)
		(sheetname "DDR5")
		(sheetfile "ddr5.kicad_sch")
		(attr smd)
		(fp_rect
			(start -0.7 0.35)
			(end 0.7 -0.35)
			(stroke
				(width 0.05)
				(type default)
			)
			(fill no)
			(layer "B.CrtYd")
		)
		(fp_rect
			(start 0.3 -0.15)
			(end -0.301 0.149)
			(stroke
				(width 0.15)
				(type solid)
			)
			(fill no)
			(layer "B.Fab")
		)
		(pad "" smd roundrect
			(at -0.349 0.002 90)
			(size 0.318 0.36)
			(layers "B.Paste")
			(roundrect_rratio 0.25)
		)
		(pad "" smd roundrect
			(at 0.341 0.002 90)
			(size 0.318 0.36)
			(layers "B.Paste")
			(roundrect_rratio 0.25)
		)
		(pad "1" smd roundrect
			(at -0.321 0.002 90)
			(size 0.46 0.4)
			(layers "B.Cu" "B.Mask")
			(roundrect_rratio 0.25)
			(net 2 "VDDQ")
			(pintype "passive")
		)
		(pad "2" smd roundrect
			(at 0.32 0.002 90)
			(size 0.46 0.4)
			(layers "B.Cu" "B.Mask")
			(roundrect_rratio 0.25)
			(net 1 "GND")
			(pintype "passive")
		)
	)
	(footprint "antmicro-footprints:C_0201"
		(layer "B.Cu")
		(at 151.625 83.675)
		(descr "Capacitor SMD 0201")
		(tags "capacitor SMD 0201")
		(property "Reference" "C28"
			(at 2.755 0.445 180)
			(layer "B.SilkS")
			(effects
				(font
					(size 0.7 0.7)
					(thickness 0.15)
				)
				(justify left bottom mirror)
			)
		)
		(property "Value" "C_100n_0201"
			(at 0 -1.4 180)
			(layer "B.Fab")
			(hide yes)
			(effects
				(font
					(size 0.7 0.7)
					(thickness 0.15)
				)
				(justify left bottom mirror)
			)
		)
		(property "Description" "SMD Multilayer Ceramic Capacitor, 0.1 µF, 6.3 V, 0201 [0603 Metric], ± 10%, X6S, CC Series"
			(at 0 0 0)
			(layer "F.Fab")
			(hide yes)
			(effects
				(font
					(size 1.27 1.27)
					(thickness 0.15)
				)
			)
		)
		(property "Author" "Antmicro"
			(at 0 0 0)
			(layer "B.Fab")
			(hide yes)
			(effects
				(font
					(size 1 1)
					(thickness 0.15)
				)
				(justify mirror)
			)
		)
		(property "Dielectric" ""
			(at 0 0 0)
			(layer "B.Fab")
			(hide yes)
			(effects
				(font
					(size 1 1)
					(thickness 0.15)
				)
				(justify mirror)
			)
		)
		(property "License" "Apache-2.0"
			(at 0 0 0)
			(layer "B.Fab")
			(hide yes)
			(effects
				(font
					(size 1 1)
					(thickness 0.15)
				)
				(justify mirror)
			)
		)
		(property "MPN" "CC0201KRX6S5BB104"
			(at 0 0 0)
			(layer "B.Fab")
			(hide yes)
			(effects
				(font
					(size 1 1)
					(thickness 0.15)
				)
				(justify mirror)
			)
		)
		(property "Manufacturer" "YAGEO"
			(at 0 0 0)
			(layer "B.Fab")
			(hide yes)
			(effects
				(font
					(size 1 1)
					(thickness 0.15)
				)
				(justify mirror)
			)
		)
		(property "Public" "False"
			(at 0 0 0)
			(layer "B.Fab")
			(hide yes)
			(effects
				(font
					(size 1 1)
					(thickness 0.15)
				)
				(justify mirror)
			)
		)
		(property "Val" "100n"
			(at 0 0 0)
			(layer "B.Fab")
			(hide yes)
			(effects
				(font
					(size 1 1)
					(thickness 0.15)
				)
				(justify mirror)
			)
		)
		(property "Voltage" ""
			(at 0 0 0)
			(layer "B.Fab")
			(hide yes)
			(effects
				(font
					(size 1 1)
					(thickness 0.15)
				)
				(justify mirror)
			)
		)
		(sheetname "DDR5")
		(sheetfile "ddr5.kicad_sch")
		(attr smd)
		(fp_rect
			(start -0.7 0.35)
			(end 0.7 -0.35)
			(stroke
				(width 0.05)
				(type default)
			)
			(fill no)
			(layer "B.CrtYd")
		)
		(fp_rect
			(start 0.3 -0.15)
			(end -0.301 0.149)
			(stroke
				(width 0.15)
				(type solid)
			)
			(fill no)
			(layer "B.Fab")
		)
		(pad "" smd roundrect
			(at -0.349 0.002)
			(size 0.318 0.36)
			(layers "B.Paste")
			(roundrect_rratio 0.25)
		)
		(pad "" smd roundrect
			(at 0.341 0.002)
			(size 0.318 0.36)
			(layers "B.Paste")
			(roundrect_rratio 0.25)
		)
		(pad "1" smd roundrect
			(at -0.321 0.002)
			(size 0.46 0.4)
			(layers "B.Cu" "B.Mask")
			(roundrect_rratio 0.25)
			(net 18 "VDD")
			(pintype "passive")
		)
		(pad "2" smd roundrect
			(at 0.32 0.002)
			(size 0.46 0.4)
			(layers "B.Cu" "B.Mask")
			(roundrect_rratio 0.25)
			(net 1 "GND")
			(pintype "passive")
		)
	)
	(footprint "antmicro-footprints:C_0201"
		(layer "B.Cu")
		(at 149.15 88.85 180)
		(descr "Capacitor SMD 0201")
		(tags "capacitor SMD 0201")
		(property "Reference" "C12"
			(at -0.86 -2.13 0)
			(layer "B.SilkS")
			(effects
				(font
					(size 0.7 0.7)
					(thickness 0.15)
				)
				(justify left bottom mirror)
			)
		)
		(property "Value" "C_100n_0201"
			(at 0 -1.4 0)
			(layer "B.Fab")
			(hide yes)
			(effects
				(font
					(size 0.7 0.7)
					(thickness 0.15)
				)
				(justify left bottom mirror)
			)
		)
		(property "Description" "SMD Multilayer Ceramic Capacitor, 0.1 µF, 6.3 V, 0201 [0603 Metric], ± 10%, X6S, CC Series"
			(at 0 0 180)
			(layer "F.Fab")
			(hide yes)
			(effects
				(font
					(size 1.27 1.27)
					(thickness 0.15)
				)
			)
		)
		(property "Author" "Antmicro"
			(at 298.3 177.7 0)
			(layer "B.Fab")
			(hide yes)
			(effects
				(font
					(size 1 1)
					(thickness 0.15)
				)
				(justify mirror)
			)
		)
		(property "Dielectric" ""
			(at 298.3 177.7 0)
			(layer "B.Fab")
			(hide yes)
			(effects
				(font
					(size 1 1)
					(thickness 0.15)
				)
				(justify mirror)
			)
		)
		(property "License" "Apache-2.0"
			(at 298.3 177.7 0)
			(layer "B.Fab")
			(hide yes)
			(effects
				(font
					(size 1 1)
					(thickness 0.15)
				)
				(justify mirror)
			)
		)
		(property "MPN" "CC0201KRX6S5BB104"
			(at 298.3 177.7 0)
			(layer "B.Fab")
			(hide yes)
			(effects
				(font
					(size 1 1)
					(thickness 0.15)
				)
				(justify mirror)
			)
		)
		(property "Manufacturer" "YAGEO"
			(at 298.3 177.7 0)
			(layer "B.Fab")
			(hide yes)
			(effects
				(font
					(size 1 1)
					(thickness 0.15)
				)
				(justify mirror)
			)
		)
		(property "Public" "False"
			(at 298.3 177.7 0)
			(layer "B.Fab")
			(hide yes)
			(effects
				(font
					(size 1 1)
					(thickness 0.15)
				)
				(justify mirror)
			)
		)
		(property "Val" "100n"
			(at 298.3 177.7 0)
			(layer "B.Fab")
			(hide yes)
			(effects
				(font
					(size 1 1)
					(thickness 0.15)
				)
				(justify mirror)
			)
		)
		(property "Voltage" ""
			(at 298.3 177.7 0)
			(layer "B.Fab")
			(hide yes)
			(effects
				(font
					(size 1 1)
					(thickness 0.15)
				)
				(justify mirror)
			)
		)
		(sheetname "DDR5")
		(sheetfile "ddr5.kicad_sch")
		(attr smd)
		(fp_rect
			(start -0.7 0.35)
			(end 0.7 -0.35)
			(stroke
				(width 0.05)
				(type default)
			)
			(fill no)
			(layer "B.CrtYd")
		)
		(fp_rect
			(start 0.3 -0.15)
			(end -0.301 0.149)
			(stroke
				(width 0.15)
				(type solid)
			)
			(fill no)
			(layer "B.Fab")
		)
		(pad "" smd roundrect
			(at -0.349 0.002 180)
			(size 0.318 0.36)
			(layers "B.Paste")
			(roundrect_rratio 0.25)
		)
		(pad "" smd roundrect
			(at 0.341 0.002 180)
			(size 0.318 0.36)
			(layers "B.Paste")
			(roundrect_rratio 0.25)
		)
		(pad "1" smd roundrect
			(at -0.321 0.002 180)
			(size 0.46 0.4)
			(layers "B.Cu" "B.Mask")
			(roundrect_rratio 0.25)
			(net 18 "VDD")
			(pintype "passive")
		)
		(pad "2" smd roundrect
			(at 0.32 0.002 180)
			(size 0.46 0.4)
			(layers "B.Cu" "B.Mask")
			(roundrect_rratio 0.25)
			(net 1 "GND")
			(pintype "passive")
		)
	)
	(footprint "antmicro-footprints:C_0201"
		(layer "B.Cu")
		(at 145.32 88.06 90)
		(descr "Capacitor SMD 0201")
		(tags "capacitor SMD 0201")
		(property "Reference" "C15"
			(at -0.65 0.37 270)
			(layer "B.SilkS")
			(effects
				(font
					(size 0.7 0.7)
					(thickness 0.15)
				)
				(justify left bottom mirror)
			)
		)
		(property "Value" "C_100n_0201"
			(at 0 -1.4 270)
			(layer "B.Fab")
			(hide yes)
			(effects
				(font
					(size 0.7 0.7)
					(thickness 0.15)
				)
				(justify left bottom mirror)
			)
		)
		(property "Description" "SMD Multilayer Ceramic Capacitor, 0.1 µF, 6.3 V, 0201 [0603 Metric], ± 10%, X6S, CC Series"
			(at 0 0 90)
			(layer "F.Fab")
			(hide yes)
			(effects
				(font
					(size 1.27 1.27)
					(thickness 0.15)
				)
			)
		)
		(property "Author" "Antmicro"
			(at 233.38 -57.26 0)
			(layer "B.Fab")
			(hide yes)
			(effects
				(font
					(size 1 1)
					(thickness 0.15)
				)
				(justify mirror)
			)
		)
		(property "Dielectric" ""
			(at 233.38 -57.26 0)
			(layer "B.Fab")
			(hide yes)
			(effects
				(font
					(size 1 1)
					(thickness 0.15)
				)
				(justify mirror)
			)
		)
		(property "License" "Apache-2.0"
			(at 233.38 -57.26 0)
			(layer "B.Fab")
			(hide yes)
			(effects
				(font
					(size 1 1)
					(thickness 0.15)
				)
				(justify mirror)
			)
		)
		(property "MPN" "CC0201KRX6S5BB104"
			(at 233.38 -57.26 0)
			(layer "B.Fab")
			(hide yes)
			(effects
				(font
					(size 1 1)
					(thickness 0.15)
				)
				(justify mirror)
			)
		)
		(property "Manufacturer" "YAGEO"
			(at 233.38 -57.26 0)
			(layer "B.Fab")
			(hide yes)
			(effects
				(font
					(size 1 1)
					(thickness 0.15)
				)
				(justify mirror)
			)
		)
		(property "Public" "False"
			(at 233.38 -57.26 0)
			(layer "B.Fab")
			(hide yes)
			(effects
				(font
					(size 1 1)
					(thickness 0.15)
				)
				(justify mirror)
			)
		)
		(property "Val" "100n"
			(at 233.38 -57.26 0)
			(layer "B.Fab")
			(hide yes)
			(effects
				(font
					(size 1 1)
					(thickness 0.15)
				)
				(justify mirror)
			)
		)
		(property "Voltage" ""
			(at 233.38 -57.26 0)
			(layer "B.Fab")
			(hide yes)
			(effects
				(font
					(size 1 1)
					(thickness 0.15)
				)
				(justify mirror)
			)
		)
		(sheetname "DDR5")
		(sheetfile "ddr5.kicad_sch")
		(attr smd)
		(fp_rect
			(start -0.7 0.35)
			(end 0.7 -0.35)
			(stroke
				(width 0.05)
				(type default)
			)
			(fill no)
			(layer "B.CrtYd")
		)
		(fp_rect
			(start 0.3 -0.15)
			(end -0.301 0.149)
			(stroke
				(width 0.15)
				(type solid)
			)
			(fill no)
			(layer "B.Fab")
		)
		(pad "" smd roundrect
			(at -0.349 0.002 90)
			(size 0.318 0.36)
			(layers "B.Paste")
			(roundrect_rratio 0.25)
		)
		(pad "" smd roundrect
			(at 0.341 0.002 90)
			(size 0.318 0.36)
			(layers "B.Paste")
			(roundrect_rratio 0.25)
		)
		(pad "1" smd roundrect
			(at -0.321 0.002 90)
			(size 0.46 0.4)
			(layers "B.Cu" "B.Mask")
			(roundrect_rratio 0.25)
			(net 18 "VDD")
			(pintype "passive")
		)
		(pad "2" smd roundrect
			(at 0.32 0.002 90)
			(size 0.46 0.4)
			(layers "B.Cu" "B.Mask")
			(roundrect_rratio 0.25)
			(net 1 "GND")
			(pintype "passive")
		)
	)
	(footprint "antmicro-footprints:C_0201"
		(layer "B.Cu")
		(at 146.75 88.05 180)
		(descr "Capacitor SMD 0201")
		(tags "capacitor SMD 0201")
		(property "Reference" "C1"
			(at -0.78 0.56 0)
			(layer "B.SilkS")
			(effects
				(font
					(size 0.7 0.7)
					(thickness 0.15)
				)
				(justify left bottom mirror)
			)
		)
		(property "Value" "C_100n_0201"
			(at 0 -1.4 0)
			(layer "B.Fab")
			(hide yes)
			(effects
				(font
					(size 0.7 0.7)
					(thickness 0.15)
				)
				(justify left bottom mirror)
			)
		)
		(property "Description" "SMD Multilayer Ceramic Capacitor, 0.1 µF, 6.3 V, 0201 [0603 Metric], ± 10%, X6S, CC Series"
			(at 0 0 180)
			(layer "F.Fab")
			(hide yes)
			(effects
				(font
					(size 1.27 1.27)
					(thickness 0.15)
				)
			)
		)
		(property "Author" "Antmicro"
			(at 293.5 176.1 0)
			(layer "B.Fab")
			(hide yes)
			(effects
				(font
					(size 1 1)
					(thickness 0.15)
				)
				(justify mirror)
			)
		)
		(property "Dielectric" ""
			(at 293.5 176.1 0)
			(layer "B.Fab")
			(hide yes)
			(effects
				(font
					(size 1 1)
					(thickness 0.15)
				)
				(justify mirror)
			)
		)
		(property "License" "Apache-2.0"
			(at 293.5 176.1 0)
			(layer "B.Fab")
			(hide yes)
			(effects
				(font
					(size 1 1)
					(thickness 0.15)
				)
				(justify mirror)
			)
		)
		(property "MPN" "CC0201KRX6S5BB104"
			(at 293.5 176.1 0)
			(layer "B.Fab")
			(hide yes)
			(effects
				(font
					(size 1 1)
					(thickness 0.15)
				)
				(justify mirror)
			)
		)
		(property "Manufacturer" "YAGEO"
			(at 293.5 176.1 0)
			(layer "B.Fab")
			(hide yes)
			(effects
				(font
					(size 1 1)
					(thickness 0.15)
				)
				(justify mirror)
			)
		)
		(property "Public" "False"
			(at 293.5 176.1 0)
			(layer "B.Fab")
			(hide yes)
			(effects
				(font
					(size 1 1)
					(thickness 0.15)
				)
				(justify mirror)
			)
		)
		(property "Val" "100n"
			(at 293.5 176.1 0)
			(layer "B.Fab")
			(hide yes)
			(effects
				(font
					(size 1 1)
					(thickness 0.15)
				)
				(justify mirror)
			)
		)
		(property "Voltage" ""
			(at 293.5 176.1 0)
			(layer "B.Fab")
			(hide yes)
			(effects
				(font
					(size 1 1)
					(thickness 0.15)
				)
				(justify mirror)
			)
		)
		(sheetname "DDR5")
		(sheetfile "ddr5.kicad_sch")
		(attr smd)
		(fp_rect
			(start -0.7 0.35)
			(end 0.7 -0.35)
			(stroke
				(width 0.05)
				(type default)
			)
			(fill no)
			(layer "B.CrtYd")
		)
		(fp_rect
			(start 0.3 -0.15)
			(end -0.301 0.149)
			(stroke
				(width 0.15)
				(type solid)
			)
			(fill no)
			(layer "B.Fab")
		)
		(pad "" smd roundrect
			(at -0.349 0.002 180)
			(size 0.318 0.36)
			(layers "B.Paste")
			(roundrect_rratio 0.25)
		)
		(pad "" smd roundrect
			(at 0.341 0.002 180)
			(size 0.318 0.36)
			(layers "B.Paste")
			(roundrect_rratio 0.25)
		)
		(pad "1" smd roundrect
			(at -0.321 0.002 180)
			(size 0.46 0.4)
			(layers "B.Cu" "B.Mask")
			(roundrect_rratio 0.25)
			(net 2 "VDDQ")
			(pintype "passive")
		)
		(pad "2" smd roundrect
			(at 0.32 0.002 180)
			(size 0.46 0.4)
			(layers "B.Cu" "B.Mask")
			(roundrect_rratio 0.25)
			(net 1 "GND")
			(pintype "passive")
		)
	)
	(footprint "antmicro-footprints:R_0402_1005Metric"
		(layer "B.Cu")
		(at 143.2 88.2 -135)
		(descr "Resistor SMD 0402")
		(tags "resistor SMD 0402")
		(property "Reference" "R16"
			(at -1.025305 -1.294005 45)
			(layer "B.SilkS")
			(effects
				(font
					(size 0.7 0.7)
					(thickness 0.15)
				)
				(justify left bottom mirror)
			)
		)
		(property "Value" "R_0R_0402"
			(at 0 -1.399999 45)
			(layer "B.Fab")
			(hide yes)
			(effects
				(font
					(size 0.7 0.7)
					(thickness 0.15)
				)
				(justify left bottom mirror)
			)
		)
		(property "Description" "0R resistor in 0402 package with unspecified tolerance"
			(at 0 0 225)
			(layer "F.Fab")
			(hide yes)
			(effects
				(font
					(size 1.27 1.27)
					(thickness 0.15)
				)
			)
		)
		(property "Author" "Antmicro"
			(at 182.090873 251.824509 0)
			(layer "B.Fab")
			(hide yes)
			(effects
				(font
					(size 1 1)
					(thickness 0.15)
				)
				(justify mirror)
			)
		)
		(property "Current" "1A"
			(at 182.090873 251.824509 0)
			(layer "B.Fab")
			(hide yes)
			(effects
				(font
					(size 1 1)
					(thickness 0.15)
				)
				(justify mirror)
			)
		)
		(property "License" "Apache-2.0"
			(at 182.090873 251.824509 0)
			(layer "B.Fab")
			(hide yes)
			(effects
				(font
					(size 1 1)
					(thickness 0.15)
				)
				(justify mirror)
			)
		)
		(property "MPN" "ERJ2GE0R00X"
			(at 182.090873 251.824509 0)
			(layer "B.Fab")
			(hide yes)
			(effects
				(font
					(size 1 1)
					(thickness 0.15)
				)
				(justify mirror)
			)
		)
		(property "Manufacturer" "Panasonic"
			(at 182.090873 251.824509 0)
			(layer "B.Fab")
			(hide yes)
			(effects
				(font
					(size 1 1)
					(thickness 0.15)
				)
				(justify mirror)
			)
		)
		(property "Tolerance" ""
			(at 182.090873 251.824509 0)
			(layer "B.Fab")
			(hide yes)
			(effects
				(font
					(size 1 1)
					(thickness 0.15)
				)
				(justify mirror)
			)
		)
		(property "Val" "0R"
			(at 182.090873 251.824509 0)
			(layer "B.Fab")
			(hide yes)
			(effects
				(font
					(size 1 1)
					(thickness 0.15)
				)
				(justify mirror)
			)
		)
		(sheetname "DDR5")
		(sheetfile "ddr5.kicad_sch")
		(attr smd)
		(fp_poly
			(pts
				(xy -0.925 0.47) (xy 0.925 0.47) (xy 0.925 -0.47) (xy -0.925 -0.47)
			)
			(stroke
				(width 0.05)
				(type default)
			)
			(fill no)
			(layer "B.CrtYd")
		)
		(fp_poly
			(pts
				(xy -0.5 0.25) (xy 0.5 0.25) (xy 0.5 -0.25) (xy -0.5 -0.25)
			)
			(stroke
				(width 0.15)
				(type solid)
			)
			(fill no)
			(layer "B.Fab")
		)
		(pad "1" smd roundrect
			(at -0.48 0 225)
			(size 0.59 0.64)
			(layers "B.Cu" "B.Mask" "B.Paste")
			(roundrect_rratio 0.25)
			(net 63 "/DDR5/R_MIR")
			(pintype "passive")
		)
		(pad "2" smd roundrect
			(at 0.48 0 225)
			(size 0.59 0.64)
			(layers "B.Cu" "B.Mask" "B.Paste")
			(roundrect_rratio 0.25)
			(net 57 "MIR")
			(pintype "passive")
		)
	)
	(footprint "antmicro-footprints:C_0201"
		(layer "B.Cu")
		(at 155.2 80.425 90)
		(descr "Capacitor SMD 0201")
		(tags "capacitor SMD 0201")
		(property "Reference" "C30"
			(at 3.195 0.39 270)
			(layer "B.SilkS")
			(effects
				(font
					(size 0.7 0.7)
					(thickness 0.15)
				)
				(justify left bottom mirror)
			)
		)
		(property "Value" "C_100n_0201"
			(at 0 -1.4 270)
			(layer "B.Fab")
			(hide yes)
			(effects
				(font
					(size 0.7 0.7)
					(thickness 0.15)
				)
				(justify left bottom mirror)
			)
		)
		(property "Description" "SMD Multilayer Ceramic Capacitor, 0.1 µF, 6.3 V, 0201 [0603 Metric], ± 10%, X6S, CC Series"
			(at 0 0 90)
			(layer "F.Fab")
			(hide yes)
			(effects
				(font
					(size 1.27 1.27)
					(thickness 0.15)
				)
			)
		)
		(property "Author" "Antmicro"
			(at 235.625 -74.775 0)
			(layer "B.Fab")
			(hide yes)
			(effects
				(font
					(size 1 1)
					(thickness 0.15)
				)
				(justify mirror)
			)
		)
		(property "Dielectric" ""
			(at 235.625 -74.775 0)
			(layer "B.Fab")
			(hide yes)
			(effects
				(font
					(size 1 1)
					(thickness 0.15)
				)
				(justify mirror)
			)
		)
		(property "License" "Apache-2.0"
			(at 235.625 -74.775 0)
			(layer "B.Fab")
			(hide yes)
			(effects
				(font
					(size 1 1)
					(thickness 0.15)
				)
				(justify mirror)
			)
		)
		(property "MPN" "CC0201KRX6S5BB104"
			(at 235.625 -74.775 0)
			(layer "B.Fab")
			(hide yes)
			(effects
				(font
					(size 1 1)
					(thickness 0.15)
				)
				(justify mirror)
			)
		)
		(property "Manufacturer" "YAGEO"
			(at 235.625 -74.775 0)
			(layer "B.Fab")
			(hide yes)
			(effects
				(font
					(size 1 1)
					(thickness 0.15)
				)
				(justify mirror)
			)
		)
		(property "Public" "False"
			(at 235.625 -74.775 0)
			(layer "B.Fab")
			(hide yes)
			(effects
				(font
					(size 1 1)
					(thickness 0.15)
				)
				(justify mirror)
			)
		)
		(property "Val" "100n"
			(at 235.625 -74.775 0)
			(layer "B.Fab")
			(hide yes)
			(effects
				(font
					(size 1 1)
					(thickness 0.15)
				)
				(justify mirror)
			)
		)
		(property "Voltage" ""
			(at 235.625 -74.775 0)
			(layer "B.Fab")
			(hide yes)
			(effects
				(font
					(size 1 1)
					(thickness 0.15)
				)
				(justify mirror)
			)
		)
		(sheetname "DDR5")
		(sheetfile "ddr5.kicad_sch")
		(attr smd)
		(fp_rect
			(start -0.7 0.35)
			(end 0.7 -0.35)
			(stroke
				(width 0.05)
				(type default)
			)
			(fill no)
			(layer "B.CrtYd")
		)
		(fp_rect
			(start 0.3 -0.15)
			(end -0.301 0.149)
			(stroke
				(width 0.15)
				(type solid)
			)
			(fill no)
			(layer "B.Fab")
		)
		(pad "" smd roundrect
			(at -0.349 0.002 90)
			(size 0.318 0.36)
			(layers "B.Paste")
			(roundrect_rratio 0.25)
		)
		(pad "" smd roundrect
			(at 0.341 0.002 90)
			(size 0.318 0.36)
			(layers "B.Paste")
			(roundrect_rratio 0.25)
		)
		(pad "1" smd roundrect
			(at -0.321 0.002 90)
			(size 0.46 0.4)
			(layers "B.Cu" "B.Mask")
			(roundrect_rratio 0.25)
			(net 18 "VDD")
			(pintype "passive")
		)
		(pad "2" smd roundrect
			(at 0.32 0.002 90)
			(size 0.46 0.4)
			(layers "B.Cu" "B.Mask")
			(roundrect_rratio 0.25)
			(net 1 "GND")
			(pintype "passive")
		)
	)
	(footprint "antmicro-footprints:C_0201"
		(layer "B.Cu")
		(at 152.8 80.43 90)
		(descr "Capacitor SMD 0201")
		(tags "capacitor SMD 0201")
		(property "Reference" "C32"
			(at 3.21 0.32 270)
			(layer "B.SilkS")
			(effects
				(font
					(size 0.7 0.7)
					(thickness 0.15)
				)
				(justify left bottom mirror)
			)
		)
		(property "Value" "C_100n_0201"
			(at 0 -1.4 270)
			(layer "B.Fab")
			(hide yes)
			(effects
				(font
					(size 0.7 0.7)
					(thickness 0.15)
				)
				(justify left bottom mirror)
			)
		)
		(property "Description" "SMD Multilayer Ceramic Capacitor, 0.1 µF, 6.3 V, 0201 [0603 Metric], ± 10%, X6S, CC Series"
			(at 0 0 90)
			(layer "F.Fab")
			(hide yes)
			(effects
				(font
					(size 1.27 1.27)
					(thickness 0.15)
				)
			)
		)
		(property "Author" "Antmicro"
			(at 233.23 -72.37 0)
			(layer "B.Fab")
			(hide yes)
			(effects
				(font
					(size 1 1)
					(thickness 0.15)
				)
				(justify mirror)
			)
		)
		(property "Dielectric" ""
			(at 233.23 -72.37 0)
			(layer "B.Fab")
			(hide yes)
			(effects
				(font
					(size 1 1)
					(thickness 0.15)
				)
				(justify mirror)
			)
		)
		(property "License" "Apache-2.0"
			(at 233.23 -72.37 0)
			(layer "B.Fab")
			(hide yes)
			(effects
				(font
					(size 1 1)
					(thickness 0.15)
				)
				(justify mirror)
			)
		)
		(property "MPN" "CC0201KRX6S5BB104"
			(at 233.23 -72.37 0)
			(layer "B.Fab")
			(hide yes)
			(effects
				(font
					(size 1 1)
					(thickness 0.15)
				)
				(justify mirror)
			)
		)
		(property "Manufacturer" "YAGEO"
			(at 233.23 -72.37 0)
			(layer "B.Fab")
			(hide yes)
			(effects
				(font
					(size 1 1)
					(thickness 0.15)
				)
				(justify mirror)
			)
		)
		(property "Public" "False"
			(at 233.23 -72.37 0)
			(layer "B.Fab")
			(hide yes)
			(effects
				(font
					(size 1 1)
					(thickness 0.15)
				)
				(justify mirror)
			)
		)
		(property "Val" "100n"
			(at 233.23 -72.37 0)
			(layer "B.Fab")
			(hide yes)
			(effects
				(font
					(size 1 1)
					(thickness 0.15)
				)
				(justify mirror)
			)
		)
		(property "Voltage" ""
			(at 233.23 -72.37 0)
			(layer "B.Fab")
			(hide yes)
			(effects
				(font
					(size 1 1)
					(thickness 0.15)
				)
				(justify mirror)
			)
		)
		(sheetname "DDR5")
		(sheetfile "ddr5.kicad_sch")
		(attr smd)
		(fp_rect
			(start -0.7 0.35)
			(end 0.7 -0.35)
			(stroke
				(width 0.05)
				(type default)
			)
			(fill no)
			(layer "B.CrtYd")
		)
		(fp_rect
			(start 0.3 -0.15)
			(end -0.301 0.149)
			(stroke
				(width 0.15)
				(type solid)
			)
			(fill no)
			(layer "B.Fab")
		)
		(pad "" smd roundrect
			(at -0.349 0.002 90)
			(size 0.318 0.36)
			(layers "B.Paste")
			(roundrect_rratio 0.25)
		)
		(pad "" smd roundrect
			(at 0.341 0.002 90)
			(size 0.318 0.36)
			(layers "B.Paste")
			(roundrect_rratio 0.25)
		)
		(pad "1" smd roundrect
			(at -0.321 0.002 90)
			(size 0.46 0.4)
			(layers "B.Cu" "B.Mask")
			(roundrect_rratio 0.25)
			(net 18 "VDD")
			(pintype "passive")
		)
		(pad "2" smd roundrect
			(at 0.32 0.002 90)
			(size 0.46 0.4)
			(layers "B.Cu" "B.Mask")
			(roundrect_rratio 0.25)
			(net 1 "GND")
			(pintype "passive")
		)
	)
	(footprint "antmicro-footprints:R_0402_1005Metric"
		(layer "B.Cu")
		(at 142.4 87.4 -135)
		(descr "Resistor SMD 0402")
		(tags "resistor SMD 0402")
		(property "Reference" "R15"
			(at -1.067731 0.629325 45)
			(layer "B.SilkS")
			(effects
				(font
					(size 0.7 0.7)
					(thickness 0.15)
				)
				(justify left bottom mirror)
			)
		)
		(property "Value" "R_0R_0402"
			(at 0 -1.399999 45)
			(layer "B.Fab")
			(hide yes)
			(effects
				(font
					(size 0.7 0.7)
					(thickness 0.15)
				)
				(justify left bottom mirror)
			)
		)
		(property "Description" "0R resistor in 0402 package with unspecified tolerance"
			(at 0 0 225)
			(layer "F.Fab")
			(hide yes)
			(effects
				(font
					(size 1.27 1.27)
					(thickness 0.15)
				)
			)
		)
		(property "Author" "Antmicro"
			(at 181.290873 249.893138 0)
			(layer "B.Fab")
			(hide yes)
			(effects
				(font
					(size 1 1)
					(thickness 0.15)
				)
				(justify mirror)
			)
		)
		(property "Current" "1A"
			(at 181.290873 249.893138 0)
			(layer "B.Fab")
			(hide yes)
			(effects
				(font
					(size 1 1)
					(thickness 0.15)
				)
				(justify mirror)
			)
		)
		(property "License" "Apache-2.0"
			(at 181.290873 249.893138 0)
			(layer "B.Fab")
			(hide yes)
			(effects
				(font
					(size 1 1)
					(thickness 0.15)
				)
				(justify mirror)
			)
		)
		(property "MPN" "ERJ2GE0R00X"
			(at 181.290873 249.893138 0)
			(layer "B.Fab")
			(hide yes)
			(effects
				(font
					(size 1 1)
					(thickness 0.15)
				)
				(justify mirror)
			)
		)
		(property "Manufacturer" "Panasonic"
			(at 181.290873 249.893138 0)
			(layer "B.Fab")
			(hide yes)
			(effects
				(font
					(size 1 1)
					(thickness 0.15)
				)
				(justify mirror)
			)
		)
		(property "Tolerance" ""
			(at 181.290873 249.893138 0)
			(layer "B.Fab")
			(hide yes)
			(effects
				(font
					(size 1 1)
					(thickness 0.15)
				)
				(justify mirror)
			)
		)
		(property "Val" "0R"
			(at 181.290873 249.893138 0)
			(layer "B.Fab")
			(hide yes)
			(effects
				(font
					(size 1 1)
					(thickness 0.15)
				)
				(justify mirror)
			)
		)
		(sheetname "DDR5")
		(sheetfile "ddr5.kicad_sch")
		(attr smd)
		(fp_poly
			(pts
				(xy -0.925 0.47) (xy 0.925 0.47) (xy 0.925 -0.47) (xy -0.925 -0.47)
			)
			(stroke
				(width 0.05)
				(type default)
			)
			(fill no)
			(layer "B.CrtYd")
		)
		(fp_poly
			(pts
				(xy -0.5 0.25) (xy 0.5 0.25) (xy 0.5 -0.25) (xy -0.5 -0.25)
			)
			(stroke
				(width 0.15)
				(type solid)
			)
			(fill no)
			(layer "B.Fab")
		)
		(pad "1" smd roundrect
			(at -0.48 0 225)
			(size 0.59 0.64)
			(layers "B.Cu" "B.Mask" "B.Paste")
			(roundrect_rratio 0.25)
			(net 62 "/DDR5/R_CAI")
			(pintype "passive")
		)
		(pad "2" smd roundrect
			(at 0.48 0 225)
			(size 0.59 0.64)
			(layers "B.Cu" "B.Mask" "B.Paste")
			(roundrect_rratio 0.25)
			(net 56 "CAI")
			(pintype "passive")
		)
	)
	(footprint "antmicro-footprints:C_0201"
		(layer "B.Cu")
		(at 150.8 86.86 180)
		(descr "Capacitor SMD 0201")
		(tags "capacitor SMD 0201")
		(property "Reference" "C14"
			(at -1.1 -2.045 0)
			(layer "B.SilkS")
			(effects
				(font
					(size 0.7 0.7)
					(thickness 0.15)
				)
				(justify left bottom mirror)
			)
		)
		(property "Value" "C_100n_0201"
			(at 0 -1.4 0)
			(layer "B.Fab")
			(hide yes)
			(effects
				(font
					(size 0.7 0.7)
					(thickness 0.15)
				)
				(justify left bottom mirror)
			)
		)
		(property "Description" "SMD Multilayer Ceramic Capacitor, 0.1 µF, 6.3 V, 0201 [0603 Metric], ± 10%, X6S, CC Series"
			(at 0 0 180)
			(layer "F.Fab")
			(hide yes)
			(effects
				(font
					(size 1.27 1.27)
					(thickness 0.15)
				)
			)
		)
		(property "Author" "Antmicro"
			(at 301.6 173.72 0)
			(layer "B.Fab")
			(hide yes)
			(effects
				(font
					(size 1 1)
					(thickness 0.15)
				)
				(justify mirror)
			)
		)
		(property "Dielectric" ""
			(at 301.6 173.72 0)
			(layer "B.Fab")
			(hide yes)
			(effects
				(font
					(size 1 1)
					(thickness 0.15)
				)
				(justify mirror)
			)
		)
		(property "License" "Apache-2.0"
			(at 301.6 173.72 0)
			(layer "B.Fab")
			(hide yes)
			(effects
				(font
					(size 1 1)
					(thickness 0.15)
				)
				(justify mirror)
			)
		)
		(property "MPN" "CC0201KRX6S5BB104"
			(at 301.6 173.72 0)
			(layer "B.Fab")
			(hide yes)
			(effects
				(font
					(size 1 1)
					(thickness 0.15)
				)
				(justify mirror)
			)
		)
		(property "Manufacturer" "YAGEO"
			(at 301.6 173.72 0)
			(layer "B.Fab")
			(hide yes)
			(effects
				(font
					(size 1 1)
					(thickness 0.15)
				)
				(justify mirror)
			)
		)
		(property "Public" "False"
			(at 301.6 173.72 0)
			(layer "B.Fab")
			(hide yes)
			(effects
				(font
					(size 1 1)
					(thickness 0.15)
				)
				(justify mirror)
			)
		)
		(property "Val" "100n"
			(at 301.6 173.72 0)
			(layer "B.Fab")
			(hide yes)
			(effects
				(font
					(size 1 1)
					(thickness 0.15)
				)
				(justify mirror)
			)
		)
		(property "Voltage" ""
			(at 301.6 173.72 0)
			(layer "B.Fab")
			(hide yes)
			(effects
				(font
					(size 1 1)
					(thickness 0.15)
				)
				(justify mirror)
			)
		)
		(sheetname "DDR5")
		(sheetfile "ddr5.kicad_sch")
		(attr smd)
		(fp_rect
			(start -0.7 0.35)
			(end 0.7 -0.35)
			(stroke
				(width 0.05)
				(type default)
			)
			(fill no)
			(layer "B.CrtYd")
		)
		(fp_rect
			(start 0.3 -0.15)
			(end -0.301 0.149)
			(stroke
				(width 0.15)
				(type solid)
			)
			(fill no)
			(layer "B.Fab")
		)
		(pad "" smd roundrect
			(at -0.349 0.002 180)
			(size 0.318 0.36)
			(layers "B.Paste")
			(roundrect_rratio 0.25)
		)
		(pad "" smd roundrect
			(at 0.341 0.002 180)
			(size 0.318 0.36)
			(layers "B.Paste")
			(roundrect_rratio 0.25)
		)
		(pad "1" smd roundrect
			(at -0.321 0.002 180)
			(size 0.46 0.4)
			(layers "B.Cu" "B.Mask")
			(roundrect_rratio 0.25)
			(net 2 "VDDQ")
			(pintype "passive")
		)
		(pad "2" smd roundrect
			(at 0.32 0.002 180)
			(size 0.46 0.4)
			(layers "B.Cu" "B.Mask")
			(roundrect_rratio 0.25)
			(net 1 "GND")
			(pintype "passive")
		)
	)
	(footprint "antmicro-footprints:R_0402_1005Metric"
		(layer "B.Cu")
		(at 144.3 86.3 -135)
		(descr "Resistor SMD 0402")
		(tags "resistor SMD 0402")
		(property "Reference" "R4"
			(at -0.707107 0.565685 45)
			(layer "B.SilkS")
			(effects
				(font
					(size 0.7 0.7)
					(thickness 0.15)
				)
				(justify left bottom mirror)
			)
		)
		(property "Value" "R_0R_0402"
			(at 0 -1.399999 45)
			(layer "B.Fab")
			(hide yes)
			(effects
				(font
					(size 0.7 0.7)
					(thickness 0.15)
				)
				(justify left bottom mirror)
			)
		)
		(property "Description" "0R resistor in 0402 package with unspecified tolerance"
			(at 0 0 225)
			(layer "F.Fab")
			(hide yes)
			(effects
				(font
					(size 1.27 1.27)
					(thickness 0.15)
				)
			)
		)
		(property "Author" "Antmicro"
			(at 185.312193 249.358824 0)
			(layer "B.Fab")
			(hide yes)
			(effects
				(font
					(size 1 1)
					(thickness 0.15)
				)
				(justify mirror)
			)
		)
		(property "Current" "1A"
			(at 185.312193 249.358824 0)
			(layer "B.Fab")
			(hide yes)
			(effects
				(font
					(size 1 1)
					(thickness 0.15)
				)
				(justify mirror)
			)
		)
		(property "License" "Apache-2.0"
			(at 185.312193 249.358824 0)
			(layer "B.Fab")
			(hide yes)
			(effects
				(font
					(size 1 1)
					(thickness 0.15)
				)
				(justify mirror)
			)
		)
		(property "MPN" "ERJ2GE0R00X"
			(at 185.312193 249.358824 0)
			(layer "B.Fab")
			(hide yes)
			(effects
				(font
					(size 1 1)
					(thickness 0.15)
				)
				(justify mirror)
			)
		)
		(property "Manufacturer" "Panasonic"
			(at 185.312193 249.358824 0)
			(layer "B.Fab")
			(hide yes)
			(effects
				(font
					(size 1 1)
					(thickness 0.15)
				)
				(justify mirror)
			)
		)
		(property "Tolerance" ""
			(at 185.312193 249.358824 0)
			(layer "B.Fab")
			(hide yes)
			(effects
				(font
					(size 1 1)
					(thickness 0.15)
				)
				(justify mirror)
			)
		)
		(property "Val" "0R"
			(at 185.312193 249.358824 0)
			(layer "B.Fab")
			(hide yes)
			(effects
				(font
					(size 1 1)
					(thickness 0.15)
				)
				(justify mirror)
			)
		)
		(sheetname "DDR5")
		(sheetfile "ddr5.kicad_sch")
		(attr smd)
		(fp_poly
			(pts
				(xy -0.925 0.47) (xy 0.925 0.47) (xy 0.925 -0.47) (xy -0.925 -0.47)
			)
			(stroke
				(width 0.05)
				(type default)
			)
			(fill no)
			(layer "B.CrtYd")
		)
		(fp_poly
			(pts
				(xy -0.5 0.25) (xy 0.5 0.25) (xy 0.5 -0.25) (xy -0.5 -0.25)
			)
			(stroke
				(width 0.15)
				(type solid)
			)
			(fill no)
			(layer "B.Fab")
		)
		(pad "1" smd roundrect
			(at -0.48 0 225)
			(size 0.59 0.64)
			(layers "B.Cu" "B.Mask" "B.Paste")
			(roundrect_rratio 0.25)
			(net 59 "/DDR5/R_ALERT_N")
			(pintype "passive")
		)
		(pad "2" smd roundrect
			(at 0.48 0 225)
			(size 0.59 0.64)
			(layers "B.Cu" "B.Mask" "B.Paste")
			(roundrect_rratio 0.25)
			(net 53 "ALERT_N")
			(pintype "passive")
		)
	)
	(footprint "antmicro-footprints:C_0201"
		(layer "B.Cu")
		(at 152.425 88.85 180)
		(descr "Capacitor SMD 0201")
		(tags "capacitor SMD 0201")
		(property "Reference" "C23"
			(at -1.175 -2.12 0)
			(layer "B.SilkS")
			(effects
				(font
					(size 0.7 0.7)
					(thickness 0.15)
				)
				(justify left bottom mirror)
			)
		)
		(property "Value" "C_100n_0201"
			(at 0 -1.4 0)
			(layer "B.Fab")
			(hide yes)
			(effects
				(font
					(size 0.7 0.7)
					(thickness 0.15)
				)
				(justify left bottom mirror)
			)
		)
		(property "Description" "SMD Multilayer Ceramic Capacitor, 0.1 µF, 6.3 V, 0201 [0603 Metric], ± 10%, X6S, CC Series"
			(at 0 0 180)
			(layer "F.Fab")
			(hide yes)
			(effects
				(font
					(size 1.27 1.27)
					(thickness 0.15)
				)
			)
		)
		(property "Author" "Antmicro"
			(at 304.85 177.7 0)
			(layer "B.Fab")
			(hide yes)
			(effects
				(font
					(size 1 1)
					(thickness 0.15)
				)
				(justify mirror)
			)
		)
		(property "Dielectric" ""
			(at 304.85 177.7 0)
			(layer "B.Fab")
			(hide yes)
			(effects
				(font
					(size 1 1)
					(thickness 0.15)
				)
				(justify mirror)
			)
		)
		(property "License" "Apache-2.0"
			(at 304.85 177.7 0)
			(layer "B.Fab")
			(hide yes)
			(effects
				(font
					(size 1 1)
					(thickness 0.15)
				)
				(justify mirror)
			)
		)
		(property "MPN" "CC0201KRX6S5BB104"
			(at 304.85 177.7 0)
			(layer "B.Fab")
			(hide yes)
			(effects
				(font
					(size 1 1)
					(thickness 0.15)
				)
				(justify mirror)
			)
		)
		(property "Manufacturer" "YAGEO"
			(at 304.85 177.7 0)
			(layer "B.Fab")
			(hide yes)
			(effects
				(font
					(size 1 1)
					(thickness 0.15)
				)
				(justify mirror)
			)
		)
		(property "Public" "False"
			(at 304.85 177.7 0)
			(layer "B.Fab")
			(hide yes)
			(effects
				(font
					(size 1 1)
					(thickness 0.15)
				)
				(justify mirror)
			)
		)
		(property "Val" "100n"
			(at 304.85 177.7 0)
			(layer "B.Fab")
			(hide yes)
			(effects
				(font
					(size 1 1)
					(thickness 0.15)
				)
				(justify mirror)
			)
		)
		(property "Voltage" ""
			(at 304.85 177.7 0)
			(layer "B.Fab")
			(hide yes)
			(effects
				(font
					(size 1 1)
					(thickness 0.15)
				)
				(justify mirror)
			)
		)
		(sheetname "DDR5")
		(sheetfile "ddr5.kicad_sch")
		(attr smd)
		(fp_rect
			(start -0.7 0.35)
			(end 0.7 -0.35)
			(stroke
				(width 0.05)
				(type default)
			)
			(fill no)
			(layer "B.CrtYd")
		)
		(fp_rect
			(start 0.3 -0.15)
			(end -0.301 0.149)
			(stroke
				(width 0.15)
				(type solid)
			)
			(fill no)
			(layer "B.Fab")
		)
		(pad "" smd roundrect
			(at -0.349 0.002 180)
			(size 0.318 0.36)
			(layers "B.Paste")
			(roundrect_rratio 0.25)
		)
		(pad "" smd roundrect
			(at 0.341 0.002 180)
			(size 0.318 0.36)
			(layers "B.Paste")
			(roundrect_rratio 0.25)
		)
		(pad "1" smd roundrect
			(at -0.321 0.002 180)
			(size 0.46 0.4)
			(layers "B.Cu" "B.Mask")
			(roundrect_rratio 0.25)
			(net 18 "VDD")
			(pintype "passive")
		)
		(pad "2" smd roundrect
			(at 0.32 0.002 180)
			(size 0.46 0.4)
			(layers "B.Cu" "B.Mask")
			(roundrect_rratio 0.25)
			(net 1 "GND")
			(pintype "passive")
		)
	)
	(footprint "antmicro-footprints:R_0402_1005Metric"
		(layer "B.Cu")
		(at 156.9 85.6)
		(descr "Resistor SMD 0402")
		(tags "resistor SMD 0402")
		(property "Reference" "R2"
			(at 2.4 0.33 180)
			(layer "B.SilkS")
			(effects
				(font
					(size 0.7 0.7)
					(thickness 0.15)
				)
				(justify left bottom mirror)
			)
		)
		(property "Value" "R_0R_0402"
			(at 0 -1.4 180)
			(layer "B.Fab")
			(hide yes)
			(effects
				(font
					(size 0.7 0.7)
					(thickness 0.15)
				)
				(justify left bottom mirror)
			)
		)
		(property "Description" "0R resistor in 0402 package with unspecified tolerance"
			(at 0 0 0)
			(layer "F.Fab")
			(hide yes)
			(effects
				(font
					(size 1.27 1.27)
					(thickness 0.15)
				)
			)
		)
		(property "Author" "Antmicro"
			(at 0 0 0)
			(layer "B.Fab")
			(hide yes)
			(effects
				(font
					(size 1 1)
					(thickness 0.15)
				)
				(justify mirror)
			)
		)
		(property "Current" "1A"
			(at 0 0 0)
			(layer "B.Fab")
			(hide yes)
			(effects
				(font
					(size 1 1)
					(thickness 0.15)
				)
				(justify mirror)
			)
		)
		(property "License" "Apache-2.0"
			(at 0 0 0)
			(layer "B.Fab")
			(hide yes)
			(effects
				(font
					(size 1 1)
					(thickness 0.15)
				)
				(justify mirror)
			)
		)
		(property "MPN" "ERJ2GE0R00X"
			(at 0 0 0)
			(layer "B.Fab")
			(hide yes)
			(effects
				(font
					(size 1 1)
					(thickness 0.15)
				)
				(justify mirror)
			)
		)
		(property "Manufacturer" "Panasonic"
			(at 0 0 0)
			(layer "B.Fab")
			(hide yes)
			(effects
				(font
					(size 1 1)
					(thickness 0.15)
				)
				(justify mirror)
			)
		)
		(property "Tolerance" ""
			(at 0 0 0)
			(layer "B.Fab")
			(hide yes)
			(effects
				(font
					(size 1 1)
					(thickness 0.15)
				)
				(justify mirror)
			)
		)
		(property "Val" "0R"
			(at 0 0 0)
			(layer "B.Fab")
			(hide yes)
			(effects
				(font
					(size 1 1)
					(thickness 0.15)
				)
				(justify mirror)
			)
		)
		(sheetname "DDR5")
		(sheetfile "ddr5.kicad_sch")
		(attr smd)
		(fp_rect
			(start -0.925 0.47)
			(end 0.925 -0.47)
			(stroke
				(width 0.05)
				(type default)
			)
			(fill no)
			(layer "B.CrtYd")
		)
		(fp_rect
			(start -0.5 0.25)
			(end 0.5 -0.25)
			(stroke
				(width 0.15)
				(type solid)
			)
			(fill no)
			(layer "B.Fab")
		)
		(pad "1" smd roundrect
			(at -0.48 0)
			(size 0.59 0.64)
			(layers "B.Cu" "B.Mask" "B.Paste")
			(roundrect_rratio 0.25)
			(net 58 "/DDR5/R_ODT_CA_A")
			(pintype "passive")
		)
		(pad "2" smd roundrect
			(at 0.48 0)
			(size 0.59 0.64)
			(layers "B.Cu" "B.Mask" "B.Paste")
			(roundrect_rratio 0.25)
			(net 55 "OTD_CA_A")
			(pintype "passive")
		)
	)
	(footprint "antmicro-footprints:C_0201"
		(layer "B.Cu")
		(at 154.75 82.45 180)
		(descr "Capacitor SMD 0201")
		(tags "capacitor SMD 0201")
		(property "Reference" "C5"
			(at -0.83 0.39 0)
			(layer "B.SilkS")
			(effects
				(font
					(size 0.7 0.7)
					(thickness 0.15)
				)
				(justify left bottom mirror)
			)
		)
		(property "Value" "C_100n_0201"
			(at 0 -1.4 0)
			(layer "B.Fab")
			(hide yes)
			(effects
				(font
					(size 0.7 0.7)
					(thickness 0.15)
				)
				(justify left bottom mirror)
			)
		)
		(property "Description" "SMD Multilayer Ceramic Capacitor, 0.1 µF, 6.3 V, 0201 [0603 Metric], ± 10%, X6S, CC Series"
			(at 0 0 180)
			(layer "F.Fab")
			(hide yes)
			(effects
				(font
					(size 1.27 1.27)
					(thickness 0.15)
				)
			)
		)
		(property "Author" "Antmicro"
			(at 309.5 164.9 0)
			(layer "B.Fab")
			(hide yes)
			(effects
				(font
					(size 1 1)
					(thickness 0.15)
				)
				(justify mirror)
			)
		)
		(property "Dielectric" ""
			(at 309.5 164.9 0)
			(layer "B.Fab")
			(hide yes)
			(effects
				(font
					(size 1 1)
					(thickness 0.15)
				)
				(justify mirror)
			)
		)
		(property "License" "Apache-2.0"
			(at 309.5 164.9 0)
			(layer "B.Fab")
			(hide yes)
			(effects
				(font
					(size 1 1)
					(thickness 0.15)
				)
				(justify mirror)
			)
		)
		(property "MPN" "CC0201KRX6S5BB104"
			(at 309.5 164.9 0)
			(layer "B.Fab")
			(hide yes)
			(effects
				(font
					(size 1 1)
					(thickness 0.15)
				)
				(justify mirror)
			)
		)
		(property "Manufacturer" "YAGEO"
			(at 309.5 164.9 0)
			(layer "B.Fab")
			(hide yes)
			(effects
				(font
					(size 1 1)
					(thickness 0.15)
				)
				(justify mirror)
			)
		)
		(property "Public" "False"
			(at 309.5 164.9 0)
			(layer "B.Fab")
			(hide yes)
			(effects
				(font
					(size 1 1)
					(thickness 0.15)
				)
				(justify mirror)
			)
		)
		(property "Val" "100n"
			(at 309.5 164.9 0)
			(layer "B.Fab")
			(hide yes)
			(effects
				(font
					(size 1 1)
					(thickness 0.15)
				)
				(justify mirror)
			)
		)
		(property "Voltage" ""
			(at 309.5 164.9 0)
			(layer "B.Fab")
			(hide yes)
			(effects
				(font
					(size 1 1)
					(thickness 0.15)
				)
				(justify mirror)
			)
		)
		(sheetname "DDR5")
		(sheetfile "ddr5.kicad_sch")
		(attr smd)
		(fp_rect
			(start -0.7 0.35)
			(end 0.7 -0.35)
			(stroke
				(width 0.05)
				(type default)
			)
			(fill no)
			(layer "B.CrtYd")
		)
		(fp_rect
			(start 0.3 -0.15)
			(end -0.301 0.149)
			(stroke
				(width 0.15)
				(type solid)
			)
			(fill no)
			(layer "B.Fab")
		)
		(pad "" smd roundrect
			(at -0.349 0.002 180)
			(size 0.318 0.36)
			(layers "B.Paste")
			(roundrect_rratio 0.25)
		)
		(pad "" smd roundrect
			(at 0.341 0.002 180)
			(size 0.318 0.36)
			(layers "B.Paste")
			(roundrect_rratio 0.25)
		)
		(pad "1" smd roundrect
			(at -0.321 0.002 180)
			(size 0.46 0.4)
			(layers "B.Cu" "B.Mask")
			(roundrect_rratio 0.25)
			(net 2 "VDDQ")
			(pintype "passive")
		)
		(pad "2" smd roundrect
			(at 0.32 0.002 180)
			(size 0.46 0.4)
			(layers "B.Cu" "B.Mask")
			(roundrect_rratio 0.25)
			(net 1 "GND")
			(pintype "passive")
		)
	)
	(footprint "antmicro-footprints:C_0201"
		(layer "B.Cu")
		(at 150.825 87.625 180)
		(descr "Capacitor SMD 0201")
		(tags "capacitor SMD 0201")
		(property "Reference" "C2"
			(at -0.675 -2.205 0)
			(layer "B.SilkS")
			(effects
				(font
					(size 0.7 0.7)
					(thickness 0.15)
				)
				(justify left bottom mirror)
			)
		)
		(property "Value" "C_100n_0201"
			(at 0 -1.4 0)
			(layer "B.Fab")
			(hide yes)
			(effects
				(font
					(size 0.7 0.7)
					(thickness 0.15)
				)
				(justify left bottom mirror)
			)
		)
		(property "Description" "SMD Multilayer Ceramic Capacitor, 0.1 µF, 6.3 V, 0201 [0603 Metric], ± 10%, X6S, CC Series"
			(at 0 0 180)
			(layer "F.Fab")
			(hide yes)
			(effects
				(font
					(size 1.27 1.27)
					(thickness 0.15)
				)
			)
		)
		(property "Author" "Antmicro"
			(at 301.65 175.25 0)
			(layer "B.Fab")
			(hide yes)
			(effects
				(font
					(size 1 1)
					(thickness 0.15)
				)
				(justify mirror)
			)
		)
		(property "Dielectric" ""
			(at 301.65 175.25 0)
			(layer "B.Fab")
			(hide yes)
			(effects
				(font
					(size 1 1)
					(thickness 0.15)
				)
				(justify mirror)
			)
		)
		(property "License" "Apache-2.0"
			(at 301.65 175.25 0)
			(layer "B.Fab")
			(hide yes)
			(effects
				(font
					(size 1 1)
					(thickness 0.15)
				)
				(justify mirror)
			)
		)
		(property "MPN" "CC0201KRX6S5BB104"
			(at 301.65 175.25 0)
			(layer "B.Fab")
			(hide yes)
			(effects
				(font
					(size 1 1)
					(thickness 0.15)
				)
				(justify mirror)
			)
		)
		(property "Manufacturer" "YAGEO"
			(at 301.65 175.25 0)
			(layer "B.Fab")
			(hide yes)
			(effects
				(font
					(size 1 1)
					(thickness 0.15)
				)
				(justify mirror)
			)
		)
		(property "Public" "False"
			(at 301.65 175.25 0)
			(layer "B.Fab")
			(hide yes)
			(effects
				(font
					(size 1 1)
					(thickness 0.15)
				)
				(justify mirror)
			)
		)
		(property "Val" "100n"
			(at 301.65 175.25 0)
			(layer "B.Fab")
			(hide yes)
			(effects
				(font
					(size 1 1)
					(thickness 0.15)
				)
				(justify mirror)
			)
		)
		(property "Voltage" ""
			(at 301.65 175.25 0)
			(layer "B.Fab")
			(hide yes)
			(effects
				(font
					(size 1 1)
					(thickness 0.15)
				)
				(justify mirror)
			)
		)
		(sheetname "DDR5")
		(sheetfile "ddr5.kicad_sch")
		(attr smd)
		(fp_rect
			(start -0.7 0.35)
			(end 0.7 -0.35)
			(stroke
				(width 0.05)
				(type default)
			)
			(fill no)
			(layer "B.CrtYd")
		)
		(fp_rect
			(start 0.3 -0.15)
			(end -0.301 0.149)
			(stroke
				(width 0.15)
				(type solid)
			)
			(fill no)
			(layer "B.Fab")
		)
		(pad "" smd roundrect
			(at -0.349 0.002 180)
			(size 0.318 0.36)
			(layers "B.Paste")
			(roundrect_rratio 0.25)
		)
		(pad "" smd roundrect
			(at 0.341 0.002 180)
			(size 0.318 0.36)
			(layers "B.Paste")
			(roundrect_rratio 0.25)
		)
		(pad "1" smd roundrect
			(at -0.321 0.002 180)
			(size 0.46 0.4)
			(layers "B.Cu" "B.Mask")
			(roundrect_rratio 0.25)
			(net 2 "VDDQ")
			(pintype "passive")
		)
		(pad "2" smd roundrect
			(at 0.32 0.002 180)
			(size 0.46 0.4)
			(layers "B.Cu" "B.Mask")
			(roundrect_rratio 0.25)
			(net 1 "GND")
			(pintype "passive")
		)
	)
	(gr_arc
		(start 101.75 81.35)
		(mid 101.559619 81.809619)
		(end 101.1 82)
		(stroke
			(width 0.12)
			(type solid)
		)
		(layer "Edge.Cuts")
	)
	(gr_arc
		(start 168.5 82)
		(mid 168.040381 81.809619)
		(end 167.85 81.35)
		(stroke
			(width 0.12)
			(type solid)
		)
		(layer "Edge.Cuts")
	)
	(gr_line
		(start 169.6 78)
		(end 168.5 78)
		(stroke
			(width 0.12)
			(type solid)
		)
		(layer "Edge.Cuts")
	)
	(gr_line
		(start 167.85 81.35)
		(end 167.85 78.65)
		(stroke
			(width 0.12)
			(type solid)
		)
		(layer "Edge.Cuts")
	)
	(gr_line
		(start 168.5 82)
		(end 169.6 82)
		(stroke
			(width 0.12)
			(type solid)
		)
		(layer "Edge.Cuts")
	)
	(gr_line
		(start 141.3 70)
		(end 168.851561 70)
		(stroke
			(width 0.12)
			(type solid)
		)
		(layer "Edge.Cuts")
	)
	(gr_line
		(start 100.75 70)
		(end 135.3 70)
		(stroke
			(width 0.12)
			(type solid)
		)
		(layer "Edge.Cuts")
	)
	(gr_line
		(start 101.75 81.35)
		(end 101.75 78.65)
		(stroke
			(width 0.12)
			(type solid)
		)
		(layer "Edge.Cuts")
	)
	(gr_line
		(start 141.3 75)
		(end 141.3 70)
		(stroke
			(width 0.12)
			(type solid)
		)
		(layer "Edge.Cuts")
	)
	(gr_line
		(start 100 96)
		(end 100 82)
		(stroke
			(width 0.12)
			(type solid)
		)
		(layer "Edge.Cuts")
	)
	(gr_line
		(start 101.1 78)
		(end 100 78)
		(stroke
			(width 0.12)
			(type solid)
		)
		(layer "Edge.Cuts")
	)
	(gr_arc
		(start 141.3 75)
		(mid 138.3 78)
		(end 135.3 75)
		(stroke
			(width 0.12)
			(type solid)
		)
		(layer "Edge.Cuts")
	)
	(gr_line
		(start 169.6 78)
		(end 169.600002 70.75)
		(stroke
			(width 0.12)
			(type solid)
		)
		(layer "Edge.Cuts")
	)
	(gr_line
		(start 100 78)
		(end 100 70.75)
		(stroke
			(width 0.12)
			(type solid)
		)
		(layer "Edge.Cuts")
	)
	(gr_line
		(start 100 82)
		(end 101.1 82)
		(stroke
			(width 0.12)
			(type solid)
		)
		(layer "Edge.Cuts")
	)
	(gr_line
		(start 135.3 75)
		(end 135.3 70)
		(stroke
			(width 0.12)
			(type solid)
		)
		(layer "Edge.Cuts")
	)
	(gr_arc
		(start 100 70.75)
		(mid 100.21967 70.21967)
		(end 100.75 70)
		(stroke
			(width 0.12)
			(type solid)
		)
		(layer "Edge.Cuts")
	)
	(gr_arc
		(start 168.851561 70)
		(mid 169.380883 70.220221)
		(end 169.600002 70.75)
		(stroke
			(width 0.12)
			(type solid)
		)
		(layer "Edge.Cuts")
	)
	(gr_line
		(start 169.6 96)
		(end 169.6 82)
		(stroke
			(width 0.12)
			(type solid)
		)
		(layer "Edge.Cuts")
	)
	(gr_arc
		(start 101.1 78)
		(mid 101.559619 78.190381)
		(end 101.75 78.65)
		(stroke
			(width 0.12)
			(type solid)
		)
		(layer "Edge.Cuts")
	)
	(gr_arc
		(start 167.85 78.65)
		(mid 168.040381 78.190381)
		(end 168.5 78)
		(stroke
			(width 0.12)
			(type solid)
		)
		(layer "Edge.Cuts")
	)
	(gr_text "DDR5 Testbed\nRev. ${REVISION}  05/2024\n"
		(at 108.525 78.2 0)
		(layer "F.Cu")
		(effects
			(font
				(size 0.85 0.85)
				(thickness 0.18)
			)
			(justify left)
		)
	)
	(segment
		(start 112.925 98.65)
		(end 112.925 97.1)
		(width 0.2)
		(layer "F.Cu")
		(net 1)
	)
	(segment
		(start 113.425 98.65)
		(end 113.425 97.2)
		(width 0.2)
		(layer "F.Cu")
		(net 1)
	)
	(segment
		(start 113.675 96.95)
		(end 113.675 96.45)
		(width 0.2)
		(layer "F.Cu")
		(net 1)
	)
	(segment
		(start 113.425 97.2)
		(end 113.675 96.95)
		(width 0.2)
		(layer "F.Cu")
		(net 1)
	)
	(segment
		(start 112.925 97.1)
		(end 113.175 96.85)
		(width 0.2)
		(layer "F.Cu")
		(net 1)
	)
	(segment
		(start 101.925 98.7)
		(end 101.925 97.15)
		(width 0.2)
		(layer "F.Cu")
		(net 1)
	)
	(segment
		(start 103.675 97)
		(end 103.675 96.5)
		(width 0.2)
		(layer "F.Cu")
		(net 1)
	)
	(segment
		(start 156.025 82.85)
		(end 155.625 83.25)
		(width 0.2)
		(layer "F.Cu")
		(net 1)
	)
	(segment
		(start 153.625 87.65)
		(end 153.225 87.25)
		(width 0.2)
		(layer "F.Cu")
		(net 1)
	)
	(segment
		(start 101.925 97.15)
		(end 102.175 96.9)
		(width 0.2)
		(layer "F.Cu")
		(net 1)
	)
	(segment
		(start 104.925 97.2)
		(end 105.175 96.95)
		(width 0.2)
		(layer "F.Cu")
		(net 1)
	)
	(segment
		(start 127.441666 71.466666)
		(end 127.425 71.45)
		(width 0.2)
		(layer "F.Cu")
		(net 1)
	)
	(segment
		(start 150.425 87.65)
		(end 150.025 87.25)
		(width 0.2)
		(layer "F.Cu")
		(net 1)
	)
	(segment
		(start 109.925 98.65)
		(end 109.925 97.1)
		(width 0.2)
		(layer "F.Cu")
		(net 1)
	)
	(segment
		(start 110.425 98.65)
		(end 110.425 97.2)
		(width 0.2)
		(layer "F.Cu")
		(net 1)
	)
	(segment
		(start 110.925 98.65)
		(end 110.925 97.1)
		(width 0.2)
		(layer "F.Cu")
		(net 1)
	)
	(segment
		(start 109.675 96.95)
		(end 109.675 96.45)
		(width 0.2)
		(layer "F.Cu")
		(net 1)
	)
	(segment
		(start 111.675 96.95)
		(end 111.675 96.45)
		(width 0.2)
		(layer "F.Cu")
		(net 1)
	)
	(segment
		(start 146.425 82.85)
		(end 145.825 82.85)
		(width 0.2)
		(layer "F.Cu")
		(net 1)
	)
	(segment
		(start 102.925 97.15)
		(end 103.175 96.9)
		(width 0.2)
		(layer "F.Cu")
		(net 1)
	)
	(segment
		(start 102.675 96.5)
		(end 102.675 97.1)
		(width 0.2)
		(layer "F.Cu")
		(net 1)
	)
	(segment
		(start 131.145 81.845)
		(end 131.15 81.85)
		(width 0.2)
		(layer "F.Cu")
		(net 1)
	)
	(segment
		(start 148.025 82.85)
		(end 147.625 82.45)
		(width 0.2)
		(layer "F.Cu")
		(net 1)
	)
	(segment
		(start 106.975 97.15)
		(end 107.225 96.9)
		(width 0.2)
		(layer "F.Cu")
		(net 1)
	)
	(segment
		(start 110.675 96.95)
		(end 110.675 96.45)
		(width 0.2)
		(layer "F.Cu")
		(net 1)
	)
	(segment
		(start 131.075 72.15)
		(end 131.075 71.475)
		(width 0.2)
		(layer "F.Cu")
		(net 1)
	)
	(segment
		(start 106.475 98.7)
		(end 106.475 97.25)
		(width 0.2)
		(layer "F.Cu")
		(net 1)
	)
	(segment
		(start 112.675 96.95)
		(end 112.675 96.45)
		(width 0.2)
		(layer "F.Cu")
		(net 1)
	)
	(segment
		(start 123.245 81.545)
		(end 123.245 80.88)
		(width 0.2)
		(layer "F.Cu")
		(net 1)
	)
	(segment
		(start 156.025 87.65)
		(end 155.625 87.25)
		(width 0.2)
		(layer "F.Cu")
		(net 1)
	)
	(segment
		(start 110.925 97.1)
		(end 111.175 96.85)
		(width 0.2)
		(layer "F.Cu")
		(net 1)
	)
	(segment
		(start 155.925 98.7)
		(end 155.925 96.9)
		(width 0.2)
		(layer "F.Cu")
		(net 1)
	)
	(segment
		(start 157.425 83.03)
		(end 156.205 83.03)
		(width 0.2)
		(layer "F.Cu")
		(net 1)
	)
	(segment
		(start 104.425 97.3)
		(end 104.675 97.05)
		(width 0.2)
		(layer "F.Cu")
		(net 1)
	)
	(segment
		(start 150.426514 82.85)
		(end 150.8241 82.452414)
		(width 0.2)
		(layer "F.Cu")
		(net 1)
	)
	(segment
		(start 107.475 97.25)
		(end 107.725 97)
		(width 0.2)
		(layer "F.Cu")
		(net 1)
	)
	(segment
		(start 104.675 97.05)
		(end 104.675 96.55)
		(width 0.2)
		(layer "F.Cu")
		(net 1)
	)
	(segment
		(start 153.625 82.85)
		(end 154.025 83.25)
		(width 0.2)
		(layer "F.Cu")
		(net 1)
	)
	(segment
		(start 152.025 83.65)
		(end 152.025 84.21)
		(width 0.2)
		(layer "F.Cu")
		(net 1)
	)
	(segment
		(start 109.425 97.2)
		(end 109.675 96.95)
		(width 0.2)
		(layer "F.Cu")
		(net 1)
	)
	(segment
		(start 153.625 87.65)
		(end 154.425 88.45)
		(width 0.2)
		(layer "F.Cu")
		(net 1)
	)
	(segment
		(start 107.725 97)
		(end 107.725 96.5)
		(width 0.2)
		(layer "F.Cu")
		(net 1)
	)
	(segment
		(start 125.625 72.15)
		(end 125.625 71.45)
		(width 0.2)
		(layer "F.Cu")
		(net 1)
	)
	(segment
		(start 108.425 98.7)
		(end 108.425 97.25)
		(width 0.2)
		(layer "F.Cu")
		(net 1)
	)
	(segment
		(start 112.425 97.2)
		(end 112.675 96.95)
		(width 0.2)
		(layer "F.Cu")
		(net 1)
	)
	(segment
		(start 105.925 98.75)
		(end 105.925 97.2)
		(width 0.2)
		(layer "F.Cu")
		(net 1)
	)
	(segment
		(start 102.925 98.7)
		(end 102.925 97.15)
		(width 0.2)
		(layer "F.Cu")
		(net 1)
	)
	(segment
		(start 151.925 98.7)
		(end 151.925 96.75)
		(width 0.2)
		(layer "F.Cu")
		(net 1)
	)
	(segment
		(start 111.425 97.2)
		(end 111.675 96.95)
		(width 0.2)
		(layer "F.Cu")
		(net 1)
	)
	(segment
		(start 145.85 87.65)
		(end 145.13 87.65)
		(width 0.2)
		(layer "F.Cu")
		(net 1)
	)
	(segment
		(start 156.205 83.03)
		(end 156.025 82.85)
		(width 0.2)
		(layer "F.Cu")
		(net 1)
	)
	(segment
		(start 128.025 91.15)
		(end 128.975 91.15)
		(width 0.2)
		(layer "F.Cu")
		(net 1)
	)
	(segment
		(start 107.975 98.7)
		(end 107.975 97.15)
		(width 0.2)
		(layer "F.Cu")
		(net 1)
	)
	(segment
		(start 130.725 90.2)
		(end 130.725 88.8992)
		(width 0.2)
		(layer "F.Cu")
		(net 1)
	)
	(segment
		(start 104.925 98.75)
		(end 104.925 97.2)
		(width 0.2)
		(layer "F.Cu")
		(net 1)
	)
	(segment
		(start 111.925 98.65)
		(end 111.925 97.1)
		(width 0.2)
		(layer "F.Cu")
		(net 1)
	)
	(segment
		(start 111.425 98.65)
		(end 111.425 97.2)
		(width 0.2)
		(layer "F.Cu")
		(net 1)
	)
	(segment
		(start 104.425 98.75)
		(end 104.425 97.3)
		(width 0.2)
		(layer "F.Cu")
		(net 1)
	)
	(segment
		(start 152.025 88.45)
		(end 151.625 88.05)
		(width 0.2)
		(layer "F.Cu")
		(net 1)
	)
	(segment
		(start 150.425 82.85)
		(end 150.426514 82.85)
		(width 0.2)
		(layer "F.Cu")
		(net 1)
	)
	(segment
		(start 147.425 98.7)
		(end 147.425 96.75)
		(width 0.2)
		(layer "F.Cu")
		(net 1)
	)
	(segment
		(start 105.425 98.75)
		(end 105.425 97.3)
		(width 0.2)
		(layer "F.Cu")
		(net 1)
	)
	(segment
		(start 103.925 98.7)
		(end 103.925 97.15)
		(width 0.2)
		(layer "F.Cu")
		(net 1)
	)
	(segment
		(start 102.425 98.7)
		(end 102.425 97.35)
		(width 0.2)
		(layer "F.Cu")
		(net 1)
	)
	(segment
		(start 130.725 88.8992)
		(end 131.125 88.4992)
		(width 0.2)
		(layer "F.Cu")
		(net 1)
	)
	(segment
		(start 130.725 90.2)
		(end 130.725 90.9)
		(width 0.2)
		(layer "F.Cu")
		(net 1)
	)
	(segment
		(start 154.425 82.05)
		(end 154.425 81.475)
		(width 0.2)
		(layer "F.Cu")
		(net 1)
	)
	(segment
		(start 132.875 83.55)
		(end 133.775 83.55)
		(width 0.2)
		(layer "F.Cu")
		(net 1)
	)
	(segment
		(start 106.475 97.25)
		(end 106.725 97)
		(width 0.2)
		(layer "F.Cu")
		(net 1)
	)
	(segment
		(start 122.27501 87.94999)
		(end 122.275 87.95)
		(width 0.2)
		(layer "F.Cu")
		(net 1)
	)
	(segment
		(start 123.245 80.88)
		(end 123.275 80.85)
		(width 0.2)
		(layer "F.Cu")
		(net 1)
	)
	(segment
		(start 122.27501 87.175)
		(end 122.27501 87.94999)
		(width 0.2)
		(layer "F.Cu")
		(net 1)
	)
	(segment
		(start 112.425 98.65)
		(end 112.425 97.2)
		(width 0.2)
		(layer "F.Cu")
		(net 1)
	)
	(segment
		(start 109.425 98.65)
		(end 109.425 97.2)
		(width 0.2)
		(layer "F.Cu")
		(net 1)
	)
	(segment
		(start 152.025 82.05)
		(end 152.025 81.475)
		(width 0.145)
		(layer "F.Cu")
		(net 1)
	)
	(segment
		(start 152.025 86.85)
		(end 152.025 86.828156)
		(width 0.2)
		(layer "F.Cu")
		(net 1)
	)
	(segment
		(start 109.925 97.1)
		(end 110.175 96.85)
		(width 0.2)
		(layer "F.Cu")
		(net 1)
	)
	(segment
		(start 145.13 87.65)
		(end 145 87.52)
		(width 0.2)
		(layer "F.Cu")
		(net 1)
	)
	(segment
		(start 143.425 98.7)
		(end 143.425 96.75)
		(width 0.2)
		(layer "F.Cu")
		(net 1)
	)
	(segment
		(start 108.675 97)
		(end 108.675 96.5)
		(width 0.2)
		(layer "F.Cu")
		(net 1)
	)
	(segment
		(start 129.258332 71.483332)
		(end 129.25 71.475)
		(width 0.2)
		(layer "F.Cu")
		(net 1)
	)
	(segment
		(start 107.975 97.15)
		(end 108.225 96.9)
		(width 0.2)
		(layer "F.Cu")
		(net 1)
	)
	(segment
		(start 103.925 97.15)
		(end 104.175 96.9)
		(width 0.2)
		(layer "F.Cu")
		(net 1)
	)
	(segment
		(start 106.975 98.7)
		(end 106.975 97.15)
		(width 0.2)
		(layer "F.Cu")
		(net 1)
	)
	(segment
		(start 157.525 87.735)
		(end 156.11 87.735)
		(width 0.2)
		(layer "F.Cu")
		(net 1)
	)
	(segment
		(start 103.425 98.7)
		(end 103.425 97.25)
		(width 0.2)
		(layer "F.Cu")
		(net 1)
	)
	(segment
		(start 103.425 97.25)
		(end 103.675 97)
		(width 0.2)
		(layer "F.Cu")
		(net 1)
	)
	(segment
		(start 155.925 96.9)
		(end 155.75 96.725)
		(width 0.2)
		(layer "F.Cu")
		(net 1)
	)
	(segment
		(start 108.925 97.15)
		(end 109.175 96.9)
		(width 0.2)
		(layer "F.Cu")
		(net 1)
	)
	(segment
		(start 106.725 97)
		(end 106.725 96.5)
		(width 0.2)
		(layer "F.Cu")
		(net 1)
	)
	(segment
		(start 108.925 98.7)
		(end 108.925 97.15)
		(width 0.2)
		(layer "F.Cu")
		(net 1)
	)
	(segment
		(start 148.025 87.65)
		(end 147.625 87.25)
		(width 0.2)
		(layer "F.Cu")
		(net 1)
	)
	(segment
		(start 107.475 98.7)
		(end 107.475 97.25)
		(width 0.2)
		(layer "F.Cu")
		(net 1)
	)
	(segment
		(start 156.11 87.735)
		(end 156.025 87.65)
		(width 0.2)
		(layer "F.Cu")
		(net 1)
	)
	(segment
		(start 105.925 97.2)
		(end 106.175 96.95)
		(width 0.2)
		(layer "F.Cu")
		(net 1)
	)
	(segment
		(start 105.425 97.3)
		(end 105.675 97.05)
		(width 0.2)
		(layer "F.Cu")
		(net 1)
	)
	(segment
		(start 111.925 97.1)
		(end 112.175 96.85)
		(width 0.2)
		(layer "F.Cu")
		(net 1)
	)
	(segment
		(start 101.675 97)
		(end 101.675 96.5)
		(width 0.2)
		(layer "F.Cu")
		(net 1)
	)
	(segment
		(start 101.425 98.7)
		(end 101.425 97.25)
		(width 0.2)
		(layer "F.Cu")
		(net 1)
	)
	(segment
		(start 105.675 97.05)
		(end 105.675 96.55)
		(width 0.2)
		(layer "F.Cu")
		(net 1)
	)
	(segment
		(start 101.425 97.25)
		(end 101.675 97)
		(width 0.2)
		(layer "F.Cu")
		(net 1)
	)
	(segment
		(start 129.258332 72.15)
		(end 129.258332 71.483332)
		(width 0.2)
		(layer "F.Cu")
		(net 1)
	)
	(segment
		(start 127.441666 72.15)
		(end 127.441666 71.466666)
		(width 0.2)
		(layer "F.Cu")
		(net 1)
	)
	(segment
		(start 102.675 97.1)
		(end 102.425 97.35)
		(width 0.2)
		(layer "F.Cu")
		(net 1)
	)
	(segment
		(start 110.425 97.2)
		(end 110.675 96.95)
		(width 0.2)
		(layer "F.Cu")
		(net 1)
	)
	(segment
		(start 132.955 91.13)
		(end 132.975 91.15)
		(width 0.2)
		(layer "F.Cu")
		(net 1)
	)
	(segment
		(start 108.425 97.25)
		(end 108.675 97)
		(width 0.2)
		(layer "F.Cu")
		(net 1)
	)
	(segment
		(start 131.145 81.15)
		(end 131.145 81.845)
		(width 0.2)
		(layer "F.Cu")
		(net 1)
	)
	(segment
		(start 152.025 86.828156)
		(end 151.63685 86.440006)
		(width 0.2)
		(layer "F.Cu")
		(net 1)
	)
	(segment
		(start 145.85 87.65)
		(end 146.425 87.65)
		(width 0.2)
		(layer "F.Cu")
		(net 1)
	)
	(segment
		(start 130.725 90.9)
		(end 130.775 90.95)
		(width 0.2)
		(layer "F.Cu")
		(net 1)
	)
	(segment
		(start 132.175 91.13)
		(end 132.955 91.13)
		(width 0.2)
		(layer "F.Cu")
		(net 1)
	)
	(segment
		(start 134.175 84.715)
		(end 134.175 83.95)
		(width 0.2)
		(layer "F.Cu")
		(net 1)
	)
	(via
		(at 113.175 96.85)
		(size 0.45)
		(drill 0.15)
		(layers "F.Cu" "B.Cu")
		(net 1)
	)
	(via
		(at 113.675 96.45)
		(size 0.45)
		(drill 0.15)
		(layers "F.Cu" "B.Cu")
		(net 1)
	)
	(via
		(at 152.025 84.21)
		(size 0.45)
		(drill 0.15)
		(layers "F.Cu" "B.Cu")
		(net 1)
	)
	(via
		(at 141.675 96.75)
		(size 0.45)
		(drill 0.15)
		(layers "F.Cu" "B.Cu")
		(net 1)
	)
	(via
		(at 150.025 87.25)
		(size 0.45)
		(drill 0.15)
		(layers "F.Cu" "B.Cu")
		(net 1)
	)
	(via
		(at 154.025 83.25)
		(size 0.45)
		(drill 0.15)
		(layers "F.Cu" "B.Cu")
		(net 1)
	)
	(via
		(at 153.8 96.5)
		(size 0.45)
		(drill 0.15)
		(layers "F.Cu" "B.Cu")
		(net 1)
	)
	(via
		(at 132.975 91.15)
		(size 0.45)
		(drill 0.15)
		(layers "F.Cu" "B.Cu")
		(net 1)
	)
	(via
		(at 134.175 83.95)
		(size 0.45)
		(drill 0.15)
		(layers "F.Cu" "B.Cu")
		(net 1)
	)
	(via
		(at 108.225 96.9)
		(size 0.45)
		(drill 0.15)
		(layers "F.Cu" "B.Cu")
		(net 1)
	)
	(via
		(at 103.675 96.5)
		(size 0.45)
		(drill 0.15)
		(layers "F.Cu" "B.Cu")
		(net 1)
	)
	(via
		(at 145.85 87.65)
		(size 0.45)
		(drill 0.15)
		(layers "F.Cu" "B.Cu")
		(net 1)
	)
	(via
		(at 149.175 96.75)
		(size 0.45)
		(drill 0.15)
		(layers "F.Cu" "B.Cu")
		(net 1)
	)
	(via
		(at 105.675 96.55)
		(size 0.45)
		(drill 0.15)
		(layers "F.Cu" "B.Cu")
		(net 1)
	)
	(via
		(at 106.725 96.5)
		(size 0.45)
		(drill 0.15)
		(layers "F.Cu" "B.Cu")
		(net 1)
	)
	(via
		(at 101.675 96.5)
		(size 0.45)
		(drill 0.15)
		(layers "F.Cu" "B.Cu")
		(net 1)
	)
	(via
		(at 110.175 96.85)
		(size 0.45)
		(drill 0.15)
		(layers "F.Cu" "B.Cu")
		(net 1)
	)
	(via
		(at 131.15 81.85)
		(size 0.45)
		(drill 0.15)
		(layers "F.Cu" "B.Cu")
		(net 1)
	)
	(via
		(at 151.63685 86.440006)
		(size 0.45)
		(drill 0.15)
		(layers "F.Cu" "B.Cu")
		(net 1)
	)
	(via
		(at 123.275 80.85)
		(size 0.45)
		(drill 0.15)
		(layers "F.Cu" "B.Cu")
		(net 1)
	)
	(via
		(at 109.175 96.9)
		(size 0.45)
		(drill 0.15)
		(layers "F.Cu" "B.Cu")
		(net 1)
	)
	(via
		(at 125.625 71.45)
		(size 0.45)
		(drill 0.15)
		(layers "F.Cu" "B.Cu")
		(net 1)
	)
	(via
		(at 109.675 96.45)
		(size 0.45)
		(drill 0.15)
		(layers "F.Cu" "B.Cu")
		(net 1)
	)
	(via
		(at 148.82 79.67)
		(size 0.45)
		(drill 0.15)
		(layers "F.Cu" "B.Cu")
		(net 1)
	)
	(via
		(at 150.8241 82.452414)
		(size 0.45)
		(drill 0.15)
		(layers "F.Cu" "B.Cu")
		(net 1)
	)
	(via
		(at 122.275 87.95)
		(size 0.45)
		(drill 0.15)
		(layers "F.Cu" "B.Cu")
		(net 1)
	)
	(via
		(at 104.675 96.55)
		(size 0.45)
		(drill 0.15)
		(layers "F.Cu" "B.Cu")
		(net 1)
	)
	(via
		(at 107.725 96.5)
		(size 0.45)
		(drill 0.15)
		(layers "F.Cu" "B.Cu")
		(net 1)
	)
	(via
		(at 152.025 81.475)
		(size 0.45)
		(drill 0.15)
		(layers "F.Cu" "B.Cu")
		(net 1)
	)
	(via
		(at 143.425 96.75)
		(size 0.45)
		(drill 0.15)
		(layers "F.Cu" "B.Cu")
		(net 1)
	)
	(via
		(at 103.175 96.9)
		(size 0.45)
		(drill 0.15)
		(layers "F.Cu" "B.Cu")
		(net 1)
	)
	(via
		(at 131.075 71.475)
		(size 0.45)
		(drill 0.15)
		(layers "F.Cu" "B.Cu")
		(net 1)
	)
	(via
		(at 154.425 81.475)
		(size 0.45)
		(drill 0.15)
		(layers "F.Cu" "B.Cu")
		(net 1)
	)
	(via
		(at 155.2 79.54)
		(size 0.45)
		(drill 0.15)
		(layers "F.Cu" "B.Cu")
		(net 1)
	)
	(via
		(at 151.625 88.05)
		(size 0.45)
		(drill 0.15)
		(layers "F.Cu" "B.Cu")
		(net 1)
	)
	(via
		(at 145.175 96.75)
		(size 0.45)
		(drill 0.15)
		(layers "F.Cu" "B.Cu")
		(net 1)
	)
	(via
		(at 110.675 96.45)
		(size 0.45)
		(drill 0.15)
		(layers "F.Cu" "B.Cu")
		(net 1)
	)
	(via
		(at 148.02 79.67)
		(size 0.45)
		(drill 0.15)
		(layers "F.Cu" "B.Cu")
		(net 1)
	)
	(via
		(at 149.62 79.67)
		(size 0.45)
		(drill 0.15)
		(layers "F.Cu" "B.Cu")
		(net 1)
	)
	(via
		(at 145.825 82.85)
		(size 0.45)
		(drill 0.15)
		(layers "F.Cu" "B.Cu")
		(net 1)
	)
	(via
		(at 111.175 96.85)
		(size 0.45)
		(drill 0.15)
		(layers "F.Cu" "B.Cu")
		(net 1)
	)
	(via
		(at 151.925 96.75)
		(size 0.45)
		(drill 0.15)
		(layers "F.Cu" "B.Cu")
		(net 1)
	)
	(via
		(at 152.8 79.55)
		(size 0.45)
		(drill 0.15)
		(layers "F.Cu" "B.Cu")
		(net 1)
	)
	(via
		(at 107.225 96.9)
		(size 0.45)
		(drill 0.15)
		(layers "F.Cu" "B.Cu")
		(net 1)
	)
	(via
		(at 127.425 71.45)
		(size 0.45)
		(drill 0.15)
		(layers "F.Cu" "B.Cu")
		(net 1)
	)
	(via
		(at 153.225 87.25)
		(size 0.45)
		(drill 0.15)
		(layers "F.Cu" "B.Cu")
		(net 1)
	)
	(via
		(at 129.25 71.475)
		(size 0.45)
		(drill 0.15)
		(layers "F.Cu" "B.Cu")
		(net 1)
	)
	(via
		(at 147.625 87.25)
		(size 0.45)
		(drill 0.15)
		(layers "F.Cu" "B.Cu")
		(net 1)
	)
	(via
		(at 102.175 96.9)
		(size 0.45)
		(drill 0.15)
		(layers "F.Cu" "B.Cu")
		(net 1)
	)
	(via
		(at 106.175 96.95)
		(size 0.45)
		(drill 0.15)
		(layers "F.Cu" "B.Cu")
		(net 1)
	)
	(via
		(at 155.625 87.25)
		(size 0.45)
		(drill 0.15)
		(layers "F.Cu" "B.Cu")
		(net 1)
	)
	(via
		(at 147.625 82.45)
		(size 0.45)
		(drill 0.15)
		(layers "F.Cu" "B.Cu")
		(net 1)
	)
	(via
		(at 112.675 96.45)
		(size 0.45)
		(drill 0.15)
		(layers "F.Cu" "B.Cu")
		(net 1)
	)
	(via
		(at 102.675 96.5)
		(size 0.45)
		(drill 0.15)
		(layers "F.Cu" "B.Cu")
		(net 1)
	)
	(via
		(at 133.775 83.55)
		(size 0.45)
		(drill 0.15)
		(layers "F.Cu" "B.Cu")
		(net 1)
	)
	(via
		(at 111.675 96.45)
		(size 0.45)
		(drill 0.15)
		(layers "F.Cu" "B.Cu")
		(net 1)
	)
	(via
		(at 128.975 91.15)
		(size 0.45)
		(drill 0.15)
		(layers "F.Cu" "B.Cu")
		(net 1)
	)
	(via
		(at 104.175 96.9)
		(size 0.45)
		(drill 0.15)
		(layers "F.Cu" "B.Cu")
		(net 1)
	)
	(via
		(at 155.625 83.25)
		(size 0.45)
		(drill 0.15)
		(layers "F.Cu" "B.Cu")
		(net 1)
	)
	(via
		(at 112.175 96.85)
		(size 0.45)
		(drill 0.15)
		(layers "F.Cu" "B.Cu")
		(net 1)
	)
	(via
		(at 147.425 96.75)
		(size 0.45)
		(drill 0.15)
		(layers "F.Cu" "B.Cu")
		(net 1)
	)
	(via
		(at 105.175 96.95)
		(size 0.45)
		(drill 0.15)
		(layers "F.Cu" "B.Cu")
		(net 1)
	)
	(via
		(at 108.675 96.5)
		(size 0.45)
		(drill 0.15)
		(layers "F.Cu" "B.Cu")
		(net 1)
	)
	(via
		(at 153.6 79.54)
		(size 0.45)
		(drill 0.15)
		(layers "F.Cu" "B.Cu")
		(net 1)
	)
	(via
		(at 155.75 96.725)
		(size 0.45)
		(drill 0.15)
		(layers "F.Cu" "B.Cu")
		(net 1)
	)
	(via
		(at 130.775 90.95)
		(size 0.45)
		(drill 0.15)
		(layers "F.Cu" "B.Cu")
		(net 1)
	)
	(segment
		(start 113.175 98.65)
		(end 113.175 96.85)
		(width 0.2)
		(layer "B.Cu")
		(net 1)
	)
	(segment
		(start 113.675 98.65)
		(end 113.675 96.45)
		(width 0.2)
		(layer "B.Cu")
		(net 1)
	)
	(segment
		(start 151.65 88.025)
		(end 151.625 88.05)
		(width 0.2)
		(layer "B.Cu")
		(net 1)
	)
	(segment
		(start 149.625 79.675)
		(end 149.62 79.67)
		(width 0.2)
		(layer "B.Cu")
		(net 1)
	)
	(segment
		(start 145.85 87.65)
		(end 146.28 87.65)
		(width 0.145)
		(layer "B.Cu")
		(net 1)
	)
	(segment
		(start 103.175 98.7)
		(end 103.175 96.9)
		(width 0.2)
		(layer "B.Cu")
		(net 1)
	)
	(segment
		(start 153.6 80.105)
		(end 153.6 79.54)
		(width 0.2)
		(layer "B.Cu")
		(net 1)
	)
	(segment
		(start 111.175 98.65)
		(end 111.175 96.85)
		(width 0.2)
		(layer "B.Cu")
		(net 1)
	)
	(segment
		(start 152.025 84.61)
		(end 151.635 85)
		(width 0.2)
		(layer "B.Cu")
		(net 1)
	)
	(segment
		(start 145.175 98.2)
		(end 145.175 96.75)
		(width 0.1016)
		(layer "B.Cu")
		(net 1)
	)
	(segment
		(start 155.675 96.8)
		(end 155.75 96.725)
		(width 0.2)
		(layer "B.Cu")
		(net 1)
	)
	(segment
		(start 156.82 88.85)
		(end 156.82 88.05)
		(width 0.2)
		(layer "B.Cu")
		(net 1)
	)
	(segment
		(start 145.3 82.42)
		(end 145.395 82.42)
		(width 0.2)
		(layer "B.Cu")
		(net 1)
	)
	(segment
		(start 150.505 87.625)
		(end 150.4 87.625)
		(width 0.2)
		(layer "B.Cu")
		(net 1)
	)
	(segment
		(start 149.175 98.7)
		(end 149.175 96.75)
		(width 0.2)
		(layer "B.Cu")
		(net 1)
	)
	(segment
		(start 104.175 98.7)
		(end 104.175 96.9)
		(width 0.2)
		(layer "B.Cu")
		(net 1)
	)
	(segment
		(start 110.175 98.65)
		(end 110.175 96.85)
		(width 0.2)
		(layer "B.Cu")
		(net 1)
	)
	(segment
		(start 153.175 98.7)
		(end 153.175 97.125)
		(width 0.2)
		(layer "B.Cu")
		(net 1)
	)
	(segment
		(start 105.675 98.75)
		(end 105.675 96.55)
		(width 0.2)
		(layer "B.Cu")
		(net 1)
	)
	(segment
		(start 156.22 87.25)
		(end 155.625 87.25)
		(width 0.2)
		(layer "B.Cu")
		(net 1)
	)
	(segment
		(start 154.43 82.45)
		(end 154.43 81.48)
		(width 0.2)
		(layer "B.Cu")
		(net 1)
	)
	(segment
		(start 102.675 98.7)
		(end 102.675 96.5)
		(width 0.2)
		(layer "B.Cu")
		(net 1)
	)
	(segment
		(start 109.175 98.7)
		(end 109.175 96.9)
		(width 0.2)
		(layer "B.Cu")
		(net 1)
	)
	(segment
		(start 111.675 98.65)
		(end 111.675 96.45)
		(width 0.2)
		(layer "B.Cu")
		(net 1)
	)
	(segment
		(start 145.3 83.28)
		(end 145.395 83.28)
		(width 0.2)
		(layer "B.Cu")
		(net 1)
	)
	(segment
		(start 107.225 98.7)
		(end 107.225 96.9)
		(width 0.2)
		(layer "B.Cu")
		(net 1)
	)
	(segment
		(start 148.425 88.05)
		(end 147.625 87.25)
		(width 0.2)
		(layer "B.Cu")
		(net 1)
	)
	(segment
		(start 106.725 98.7)
		(end 106.725 96.5)
		(width 0.2)
		(layer "B.Cu")
		(net 1)
	)
	(segment
		(start 151.945 84.13)
		(end 152.025 84.21)
		(width 0.2)
		(layer "B.Cu")
		(net 1)
	)
	(segment
		(start 112.175 98.65)
		(end 112.175 96.85)
		(width 0.2)
		(layer "B.Cu")
		(net 1)
	)
	(segment
		(start 152.025 84.21)
		(end 152.025 84.61)
		(width 0.2)
		(layer "B.Cu")
		(net 1)
	)
	(segment
		(start 109.675 98.65)
		(end 109.675 96.45)
		(width 0.2)
		(layer "B.Cu")
		(net 1)
	)
	(segment
		(start 112.675 98.65)
		(end 112.675 96.45)
		(width 0.2)
		(layer "B.Cu")
		(net 1)
	)
	(segment
		(start 150.4 87.625)
		(end 150.025 87.25)
		(width 0.2)
		(layer "B.Cu")
		(net 1)
	)
	(segment
		(start 155.2 80.105)
		(end 155.2 79.54)
		(width 0.2)
		(layer "B.Cu")
		(net 1)
	)
	(segment
		(start 145.41 87.65)
		(end 145.32 87.74)
		(width 0.145)
		(layer "B.Cu")
		(net 1)
	)
	(segment
		(start 152.105 88.025)
		(end 151.65 88.025)
		(width 0.2)
		(layer "B.Cu")
		(net 1)
	)
	(segment
		(start 154.43 81.48)
		(end 154.425 81.475)
		(width 0.2)
		(layer "B.Cu")
		(net 1)
	)
	(segment
		(start 141.675 96.75)
		(end 141.675 97.135046)
		(width 0.2)
		(layer "B.Cu")
		(net 1)
	)
	(segment
		(start 108.675 98.7)
		(end 108.675 96.5)
		(width 0.2)
		(layer "B.Cu")
		(net 1)
	)
	(segment
		(start 145.175 98.7)
		(end 145.175 98.2)
		(width 0.2)
		(layer "B.Cu")
		(net 1)
	)
	(segment
		(start 145.395 82.42)
		(end 145.825 82.85)
		(width 0.2)
		(layer "B.Cu")
		(net 1)
	)
	(segment
		(start 141.675 97.135046)
		(end 141.675 98.7)
		(width 0.2)
		(layer "B.Cu")
		(net 1)
	)
	(segment
		(start 150.4 86.875)
		(end 150.025 87.25)
		(width 0.2)
		(layer "B.Cu")
		(net 1)
	)
	(segment
		(start 150.48 86.875)
		(end 150.4 86.875)
		(width 0.2)
		(layer "B.Cu")
		(net 1)
	)
	(segment
		(start 156.82 87.85)
		(end 156.22 87.25)
		(width 0.2)
		(layer "B.Cu")
		(net 1)
	)
	(segment
		(start 106.175 98.75)
		(end 106.175 96.95)
		(width 0.2)
		(layer "B.Cu")
		(net 1)
	)
	(segment
		(start 155.675 98.7)
		(end 155.675 96.8)
		(width 0.2)
		(layer "B.Cu")
		(net 1)
	)
	(segment
		(start 149.625 80.23)
		(end 149.625 79.675)
		(width 0.2)
		(layer "B.Cu")
		(net 1)
	)
	(segment
		(start 101.675 98.7)
		(end 101.675 96.5)
		(width 0.2)
		(layer "B.Cu")
		(net 1)
	)
	(segment
		(start 103.675 98.7)
		(end 103.675 96.5)
		(width 0.2)
		(layer "B.Cu")
		(net 1)
	)
	(segment
		(start 156.82 88.05)
		(end 156.82 87.85)
		(width 0.2)
		(layer "B.Cu")
		(net 1)
	)
	(segment
		(start 151.945 83.675)
		(end 151.945 84.13)
		(width 0.2)
		(layer "B.Cu")
		(net 1)
	)
	(segment
		(start 108.225 98.7)
		(end 108.225 96.9)
		(width 0.2)
		(layer "B.Cu")
		(net 1)
	)
	(segment
		(start 148.02 80.23)
		(end 148.02 79.67)
		(width 0.2)
		(layer "B.Cu")
		(net 1)
	)
	(segment
		(start 110.675 98.65)
		(end 110.675 96.45)
		(width 0.2)
		(layer "B.Cu")
		(net 1)
	)
	(segment
		(start 148.83 88.85)
		(end 148.83 88.05)
		(width 0.2)
		(layer "B.Cu")
		(net 1)
	)
	(segment
		(start 146.28 87.65)
		(end 146.43 87.8)
		(width 0.145)
		(layer "B.Cu")
		(net 1)
	)
	(segment
		(start 148.82 80.23)
		(end 148.82 79.67)
		(width 0.2)
		(layer "B.Cu")
		(net 1)
	)
	(segment
		(start 152.105 88.85)
		(end 152.105 88.025)
		(width 0.2)
		(layer "B.Cu")
		(net 1)
	)
	(segment
		(start 146.43 87.8)
		(end 146.43 88.05)
		(width 0.145)
		(layer "B.Cu")
		(net 1)
	)
	(segment
		(start 107.725 98.7)
		(end 107.725 96.5)
		(width 0.2)
		(layer "B.Cu")
		(net 1)
	)
	(segment
		(start 148.83 88.05)
		(end 148.425 88.05)
		(width 0.2)
		(layer "B.Cu")
		(net 1)
	)
	(segment
		(start 105.175 98.75)
		(end 105.175 96.95)
		(width 0.2)
		(layer "B.Cu")
		(net 1)
	)
	(segment
		(start 145.85 87.65)
		(end 145.41 87.65)
		(width 0.145)
		(layer "B.Cu")
		(net 1)
	)
	(segment
		(start 152.8 80.11)
		(end 152.8 79.55)
		(width 0.2)
		(layer "B.Cu")
		(net 1)
	)
	(segment
		(start 104.675 98.75)
		(end 104.675 96.55)
		(width 0.2)
		(layer "B.Cu")
		(net 1)
	)
	(segment
		(start 145.395 83.28)
		(end 145.825 82.85)
		(width 0.2)
		(layer "B.Cu")
		(net 1)
	)
	(segment
		(start 153.62 82.45)
		(end 154.43 82.45)
		(width 0.2)
		(layer "B.Cu")
		(net 1)
	)
	(segment
		(start 145.175 98.7)
		(end 145.175 96.75)
		(width 0.2)
		(layer "B.Cu")
		(net 1)
	)
	(segment
		(start 102.175 98.7)
		(end 102.175 96.9)
		(width 0.2)
		(layer "B.Cu")
		(net 1)
	)
	(segment
		(start 153.8 96.5)
		(end 153.175 97.125)
		(width 0.2)
		(layer "B.Cu")
		(net 1)
	)
	(segment
		(start 149.625 88.45)
		(end 150.025 88.05)
		(width 0.2)
		(layer "F.Cu")
		(net 2)
	)
	(segment
		(start 155.625 82.45)
		(end 155.225 82.85)
		(width 0.2)
		(layer "F.Cu")
		(net 2)
	)
	(segment
		(start 148.025 88.45)
		(end 147.625 88.05)
		(width 0.2)
		(layer "F.Cu")
		(net 2)
	)
	(segment
		(start 153.625 88.45)
		(end 153.225 88.05)
		(width 0.2)
		(layer "F.Cu")
		(net 2)
	)
	(segment
		(start 151.225 87.65)
		(end 151.625 87.25)
		(width 0.2)
		(layer "F.Cu")
		(net 2)
	)
	(segment
		(start 148.025 82.05)
		(end 148.025 81.45)
		(width 0.2)
		(layer "F.Cu")
		(net 2)
	)
	(segment
		(start 152.425 82.45)
		(end 152.025 82.85)
		(width 0.2)
		(layer "F.Cu")
		(net 2)
	)
	(segment
		(start 150.225 90.665)
		(end 150.225 90.05)
		(width 0.2)
		(layer "F.Cu")
		(net 2)
	)
	(segment
		(start 153.625 82.05)
		(end 153.625 81.45)
		(width 0.2)
		(layer "F.Cu")
		(net 2)
	)
	(segment
		(start 152.025 87.65)
		(end 151.625 87.25)
		(width 0.2)
		(layer "F.Cu")
		(net 2)
	)
	(segment
		(start 149.625 82.05)
		(end 149.625 81.45)
		(width 0.2)
		(layer "F.Cu")
		(net 2)
	)
	(segment
		(start 155.225 87.65)
		(end 155.625 88.05)
		(width 0.2)
		(layer "F.Cu")
		(net 2)
	)
	(via
		(at 150.025 88.05)
		(size 0.45)
		(drill 0.15)
		(layers "F.Cu" "B.Cu")
		(net 2)
	)
	(via
		(at 151.625 87.25)
		(size 0.45)
		(drill 0.15)
		(layers "F.Cu" "B.Cu")
		(net 2)
	)
	(via
		(at 148.025 81.45)
		(size 0.45)
		(drill 0.15)
		(layers "F.Cu" "B.Cu")
		(net 2)
	)
	(via
		(at 150.225 90.05)
		(size 0.45)
		(drill 0.15)
		(layers "F.Cu" "B.Cu")
		(net 2)
	)
	(via
		(at 149.625 81.45)
		(size 0.45)
		(drill 0.15)
		(layers "F.Cu" "B.Cu")
		(net 2)
	)
	(via
		(at 140.7 89.5)
		(size 0.45)
		(drill 0.15)
		(layers "F.Cu" "B.Cu")
		(net 2)
	)
	(via
		(at 152.425 82.45)
		(size 0.45)
		(drill 0.15)
		(layers "F.Cu" "B.Cu")
		(net 2)
	)
	(via
		(at 153.225 88.05)
		(size 0.45)
		(drill 0.15)
		(layers "F.Cu" "B.Cu")
		(net 2)
	)
	(via
		(at 140.1 88.9)
		(size 0.45)
		(drill 0.15)
		(layers "F.Cu" "B.Cu")
		(net 2)
	)
	(via
		(at 155.625 88.05)
		(size 0.45)
		(drill 0.15)
		(layers "F.Cu" "B.Cu")
		(net 2)
	)
	(via
		(at 147.625 88.05)
		(size 0.45)
		(drill 0.15)
		(layers "F.Cu" "B.Cu")
		(net 2)
	)
	(via
		(at 155.625 82.45)
		(size 0.45)
		(drill 0.15)
		(layers "F.Cu" "B.Cu")
		(net 2)
	)
	(via
		(at 153.625 81.45)
		(size 0.45)
		(drill 0.15)
		(layers "F.Cu" "B.Cu")
		(net 2)
	)
	(via
		(at 140.1 89.5)
		(size 0.45)
		(drill 0.15)
		(layers "F.Cu" "B.Cu")
		(net 2)
	)
	(via
		(at 140.7 88.9)
		(size 0.45)
		(drill 0.15)
		(layers "F.Cu" "B.Cu")
		(net 2)
	)
	(segment
		(start 153.2 88.025)
		(end 153.225 88.05)
		(width 0.2)
		(layer "B.Cu")
		(net 2)
	)
	(segment
		(start 147.07 88.05)
		(end 147.625 88.05)
		(width 0.2)
		(layer "B.Cu")
		(net 2)
	)
	(segment
		(start 151.12 86.875)
		(end 151.25 86.875)
		(width 0.2)
		(layer "B.Cu")
		(net 2)
	)
	(segment
		(start 157.385 84.6)
		(end 157.385 82.985)
		(width 0.145)
		(layer "B.Cu")
		(net 2)
	)
	(segment
		(start 157.385 82.985)
		(end 156.85 82.45)
		(width 0.145)
		(layer "B.Cu")
		(net 2)
	)
	(segment
		(start 149.625 81.45)
		(end 149.625 80.87)
		(width 0.2)
		(layer "B.Cu")
		(net 2)
	)
	(segment
		(start 155.625 82.45)
		(end 155.07 82.45)
		(width 0.2)
		(layer "B.Cu")
		(net 2)
	)
	(segment
		(start 151.25 86.875)
		(end 151.625 87.25)
		(width 0.2)
		(layer "B.Cu")
		(net 2)
	)
	(segment
		(start 156.18 88.05)
		(end 155.625 88.05)
		(width 0.2)
		(layer "B.Cu")
		(net 2)
	)
	(segment
		(start 151.145 87.625)
		(end 151.25 87.625)
		(width 0.2)
		(layer "B.Cu")
		(net 2)
	)
	(segment
		(start 149.47 88.05)
		(end 150.025 88.05)
		(width 0.2)
		(layer "B.Cu")
		(net 2)
	)
	(segment
		(start 156.85 82.45)
		(end 155.625 82.45)
		(width 0.145)
		(layer "B.Cu")
		(net 2)
	)
	(segment
		(start 148.025 80.875)
		(end 148.02 80.87)
		(width 0.2)
		(layer "B.Cu")
		(net 2)
	)
	(segment
		(start 153.625 80.77)
		(end 153.6 80.745)
		(width 0.2)
		(layer "B.Cu")
		(net 2)
	)
	(segment
		(start 152.98 82.45)
		(end 152.425 82.45)
		(width 0.2)
		(layer "B.Cu")
		(net 2)
	)
	(segment
		(start 151.25 87.625)
		(end 151.625 87.25)
		(width 0.2)
		(layer "B.Cu")
		(net 2)
	)
	(segment
		(start 153.625 81.45)
		(end 153.625 80.77)
		(width 0.2)
		(layer "B.Cu")
		(net 2)
	)
	(segment
		(start 152.745 88.025)
		(end 153.2 88.025)
		(width 0.2)
		(layer "B.Cu")
		(net 2)
	)
	(segment
		(start 148.025 81.45)
		(end 148.025 80.875)
		(width 0.2)
		(layer "B.Cu")
		(net 2)
	)
	(segment
		(start 153.925 98.7)
		(end 153.925 97.073202)
		(width 0.145)
		(layer "F.Cu")
		(net 3)
	)
	(segment
		(start 149.8 92.4)
		(end 149.4 92.4)
		(width 0.145)
		(layer "F.Cu")
		(net 3)
	)
	(segment
		(start 149.225 92.225)
		(end 149.225 91.635)
		(width 0.145)
		(layer "F.Cu")
		(net 3)
	)
	(segment
		(start 149.4 92.4)
		(end 149.225 92.225)
		(width 0.145)
		(layer "F.Cu")
		(net 3)
	)
	(segment
		(start 154.199101 95.799101)
		(end 153.8 95.4)
		(width 0.145)
		(layer "F.Cu")
		(net 3)
	)
	(segment
		(start 153.8 95.4)
		(end 152.4 95.4)
		(width 0.145)
		(layer "F.Cu")
		(net 3)
	)
	(segment
		(start 150 93)
		(end 150 92.6)
		(width 0.145)
		(layer "F.Cu")
		(net 3)
	)
	(segment
		(start 152.4 95.4)
		(end 150 93)
		(width 0.145)
		(layer "F.Cu")
		(net 3)
	)
	(segment
		(start 150 92.6)
		(end 149.8 92.4)
		(width 0.145)
		(layer "F.Cu")
		(net 3)
	)
	(segment
		(start 154.199101 96.799101)
		(end 154.199101 95.799101)
		(width 0.145)
		(layer "F.Cu")
		(net 3)
	)
	(segment
		(start 153.925 97.073202)
		(end 154.199101 96.799101)
		(width 0.145)
		(layer "F.Cu")
		(net 3)
	)
	(segment
		(start 125.625 73.65)
		(end 125.625 75.465)
		(width 0.2)
		(layer "F.Cu")
		(net 4)
	)
	(segment
		(start 127.441666 75.465)
		(end 127.441666 73.65)
		(width 0.2)
		(layer "F.Cu")
		(net 5)
	)
	(segment
		(start 129.258332 73.65)
		(end 129.258332 75.465)
		(width 0.2)
		(layer "F.Cu")
		(net 6)
	)
	(segment
		(start 131.075 75.465)
		(end 131.075 73.65)
		(width 0.2)
		(layer "F.Cu")
		(net 7)
	)
	(segment
		(start 125.625 77.855)
		(end 125.625 76.435)
		(width 0.2)
		(layer "F.Cu")
		(net 8)
	)
	(segment
		(start 124.105 82.105)
		(end 124.105 79.375)
		(width 0.2)
		(layer "F.Cu")
		(net 8)
	)
	(segment
		(start 124.105 83.58)
		(end 124.105 82.105)
		(width 0.2)
		(layer "F.Cu")
		(net 8)
	)
	(segment
		(start 124.105 79.375)
		(end 125.625 77.855)
		(width 0.2)
		(layer "F.Cu")
		(net 8)
	)
	(segment
		(start 123.11 84.575)
		(end 124.105 83.58)
		(width 0.2)
		(layer "F.Cu")
		(net 8)
	)
	(segment
		(start 122.27501 84.575)
		(end 123.11 84.575)
		(width 0.2)
		(layer "F.Cu")
		(net 8)
	)
	(segment
		(start 126.8 78.45)
		(end 127.441666 77.808334)
		(width 0.2)
		(layer "F.Cu")
		(net 9)
	)
	(segment
		(start 124.67 81.83)
		(end 124.67 83.675)
		(width 0.2)
		(layer "F.Cu")
		(net 9)
	)
	(segment
		(start 124.67 79.73)
		(end 125.95 78.45)
		(width 0.2)
		(layer "F.Cu")
		(net 9)
	)
	(segment
		(start 123.12 85.225)
		(end 122.27501 85.225)
		(width 0.2)
		(layer "F.Cu")
		(net 9)
	)
	(segment
		(start 124.67 83.675)
		(end 123.12 85.225)
		(width 0.2)
		(layer "F.Cu")
		(net 9)
	)
	(segment
		(start 127.441666 77.808334)
		(end 127.441666 76.435)
		(width 0.2)
		(layer "F.Cu")
		(net 9)
	)
	(segment
		(start 125.95 78.45)
		(end 126.8 78.45)
		(width 0.2)
		(layer "F.Cu")
		(net 9)
	)
	(segment
		(start 124.67 81.83)
		(end 124.67 79.73)
		(width 0.2)
		(layer "F.Cu")
		(net 9)
	)
	(segment
		(start 129.258332 78.241668)
		(end 128.5 79)
		(width 0.2)
		(layer "F.Cu")
		(net 10)
	)
	(segment
		(start 122.27501 85.875)
		(end 123.11 85.875)
		(width 0.2)
		(layer "F.Cu")
		(net 10)
	)
	(segment
		(start 125.31 80.19)
		(end 126.5 79)
		(width 0.2)
		(layer "F.Cu")
		(net 10)
	)
	(segment
		(start 125.31 83.675)
		(end 125.31 80.19)
		(width 0.2)
		(layer "F.Cu")
		(net 10)
	)
	(segment
		(start 123.11 85.875)
		(end 125.31 83.675)
		(width 0.2)
		(layer "F.Cu")
		(net 10)
	)
	(segment
		(start 128.5 79)
		(end 126.5 79)
		(width 0.2)
		(layer "F.Cu")
		(net 10)
	)
	(segment
		(start 129.258332 76.435)
		(end 129.258332 78.241668)
		(width 0.2)
		(layer "F.Cu")
		(net 10)
	)
	(segment
		(start 125.925 83.72501)
		(end 125.925 82.425)
		(width 0.2)
		(layer "F.Cu")
		(net 11)
	)
	(segment
		(start 131.075 77.075)
		(end 131.075 76.435)
		(width 0.2)
		(layer "F.Cu")
		(net 11)
	)
	(segment
		(start 123.12501 86.525)
		(end 125.925 83.72501)
		(width 0.2)
		(layer "F.Cu")
		(net 11)
	)
	(segment
		(start 125.925 82.425)
		(end 125.925 80.575)
		(width 0.2)
		(layer "F.Cu")
		(net 11)
	)
	(segment
		(start 125.925 80.575)
		(end 127 79.5)
		(width 0.2)
		(layer "F.Cu")
		(net 11)
	)
	(segment
		(start 131.075 78.825)
		(end 131.075 77.075)
		(width 0.2)
		(layer "F.Cu")
		(net 11)
	)
	(segment
		(start 122.27501 86.525)
		(end 123.12501 86.525)
		(width 0.2)
		(layer "F.Cu")
		(net 11)
	)
	(segment
		(start 127 79.5)
		(end 130.4 79.5)
		(width 0.2)
		(layer "F.Cu")
		(net 11)
	)
	(segment
		(start 130.4 79.5)
		(end 131.075 78.825)
		(width 0.2)
		(layer "F.Cu")
		(net 11)
	)
	(segment
		(start 125.905 92.1)
		(end 126.56 92.1)
		(width 0.2)
		(layer "F.Cu")
		(net 12)
	)
	(segment
		(start 125.105 85.31)
		(end 125.105 91.3)
		(width 0.2)
		(layer "F.Cu")
		(net 12)
	)
	(segment
		(start 127.14 83.275)
		(end 125.105 85.31)
		(width 0.2)
		(layer "F.Cu")
		(net 12)
	)
	(segment
		(start 132.925 97.15)
		(end 129.375 93.6)
		(width 0.2)
		(layer "F.Cu")
		(net 12)
	)
	(segment
		(start 127.975 83.275)
		(end 127.14 83.275)
		(width 0.2)
		(layer "F.Cu")
		(net 12)
	)
	(segment
		(start 125.105 91.3)
		(end 125.905 92.1)
		(width 0.2)
		(layer "F.Cu")
		(net 12)
	)
	(segment
		(start 128.025 92.1)
		(end 126.56 92.1)
		(width 0.2)
		(layer "F.Cu")
		(net 12)
	)
	(segment
		(start 128.945 92.1)
		(end 128.025 92.1)
		(width 0.2)
		(layer "F.Cu")
		(net 12)
	)
	(segment
		(start 132.925 98.7)
		(end 132.925 97.15)
		(width 0.2)
		(layer "F.Cu")
		(net 12)
	)
	(segment
		(start 129.375 93.6)
		(end 129.375 92.53)
		(width 0.2)
		(layer "F.Cu")
		(net 12)
	)
	(segment
		(start 129.375 92.53)
		(end 128.945 92.1)
		(width 0.2)
		(layer "F.Cu")
		(net 12)
	)
	(segment
		(start 126.555 90.205)
		(end 128.02 90.205)
		(width 0.2)
		(layer "F.Cu")
		(net 13)
	)
	(segment
		(start 126.555 90.205)
		(end 126.215 90.205)
		(width 0.2)
		(layer "F.Cu")
		(net 13)
	)
	(segment
		(start 129.755 93.48)
		(end 133.425 97.15)
		(width 0.2)
		(layer "F.Cu")
		(net 13)
	)
	(segment
		(start 128.025 90.2)
		(end 129.2 90.2)
		(width 0.2)
		(layer "F.Cu")
		(net 13)
	)
	(segment
		(start 126.215 90.205)
		(end 125.57 89.56)
		(width 0.2)
		(layer "F.Cu")
		(net 13)
	)
	(segment
		(start 128.02 90.205)
		(end 128.025 90.2)
		(width 0.2)
		(layer "F.Cu")
		(net 13)
	)
	(segment
		(start 133.425 97.15)
		(end 133.425 98.7)
		(width 0.2)
		(layer "F.Cu")
		(net 13)
	)
	(segment
		(start 125.57 89.56)
		(end 125.57 85.47)
		(width 0.2)
		(layer "F.Cu")
		(net 13)
	)
	(segment
		(start 129.755 90.755)
		(end 129.755 93.48)
		(width 0.2)
		(layer "F.Cu")
		(net 13)
	)
	(segment
		(start 129.2 90.2)
		(end 129.755 90.755)
		(width 0.2)
		(layer "F.Cu")
		(net 13)
	)
	(segment
		(start 125.57 85.47)
		(end 127.115 83.925)
		(width 0.2)
		(layer "F.Cu")
		(net 13)
	)
	(segment
		(start 127.115 83.925)
		(end 127.975 83.925)
		(width 0.2)
		(layer "F.Cu")
		(net 13)
	)
	(segment
		(start 127.975 88.4992)
		(end 127.975 87.175)
		(width 0.2)
		(layer "F.Cu")
		(net 14)
	)
	(segment
		(start 129.055 86.525)
		(end 129.55 87.02)
		(width 0.2)
		(layer "F.Cu")
		(net 15)
	)
	(segment
		(start 127.975 86.525)
		(end 129.055 86.525)
		(width 0.2)
		(layer "F.Cu")
		(net 15)
	)
	(segment
		(start 129.55 87.02)
		(end 129.55 88.4992)
		(width 0.2)
		(layer "F.Cu")
		(net 15)
	)
	(segment
		(start 150.425 83.65)
		(end 150.425 84.21)
		(width 0.145)
		(layer "F.Cu")
		(net 17)
	)
	(via
		(at 150.425 84.21)
		(size 0.45)
		(drill 0.15)
		(layers "F.Cu" "B.Cu")
		(net 17)
	)
	(segment
		(start 143.13216 94.968743)
		(end 143.100505 94.961518)
		(width 0.145)
		(layer "B.Cu")
		(net 17)
	)
	(segment
		(start 142.979755 95.574614)
		(end 142.965667 95.545359)
		(width 0.145)
		(layer "B.Cu")
		(net 17)
	)
	(segment
		(start 142.740298 95.224209)
		(end 142.708643 95.231435)
		(width 0.145)
		(layer "B.Cu")
		(net 17)
	)
	(segment
		(start 143.068035 94.961518)
		(end 143.03638 94.968743)
		(width 0.145)
		(layer "B.Cu")
		(net 17)
	)
	(segment
		(start 143.100505 94.961518)
		(end 143.068035 94.961518)
		(width 0.145)
		(layer "B.Cu")
		(net 17)
	)
	(segment
		(start 150 85.8)
		(end 150.425 85.375)
		(width 0.145)
		(layer "B.Cu")
		(net 17)
	)
	(segment
		(start 142.615263 95.210121)
		(end 142.589878 95.189878)
		(width 0.145)
		(layer "B.Cu")
		(net 17)
	)
	(segment
		(start 142.794938 95.189877)
		(end 142.769552 95.210121)
		(width 0.145)
		(layer "B.Cu")
		(net 17)
	)
	(segment
		(start 143.221133 95.153497)
		(end 143.228359 95.121842)
		(width 0.145)
		(layer "B.Cu")
		(net 17)
	)
	(segment
		(start 143.221133 95.057716)
		(end 143.207045 95.028462)
		(width 0.145)
		(layer "B.Cu")
		(net 17)
	)
	(segment
		(start 150.45 85)
		(end 150.425 85.025)
		(width 0.1016)
		(layer "B.Cu")
		(net 17)
	)
	(segment
		(start 142.769552 95.210121)
		(end 142.740298 95.224209)
		(width 0.145)
		(layer "B.Cu")
		(net 17)
	)
	(segment
		(start 143.228359 95.121842)
		(end 143.228359 95.089372)
		(width 0.145)
		(layer "B.Cu")
		(net 17)
	)
	(segment
		(start 143.675 97.09067)
		(end 143.824101 96.941569)
		(width 0.145)
		(layer "B.Cu")
		(net 17)
	)
	(segment
		(start 150.665 85)
		(end 150.45 85)
		(width 0.1016)
		(layer "B.Cu")
		(net 17)
	)
	(segment
		(start 142.965667 95.545359)
		(end 142.958442 95.513704)
		(width 0.145)
		(layer "B.Cu")
		(net 17)
	)
	(segment
		(start 146.4 85.8)
		(end 150 85.8)
		(width 0.145)
		(layer "B.Cu")
		(net 17)
	)
	(segment
		(start 142.965667 95.449579)
		(end 142.979755 95.420324)
		(width 0.145)
		(layer "B.Cu")
		(net 17)
	)
	(segment
		(start 143.207045 95.028462)
		(end 143.186801 95.003076)
		(width 0.145)
		(layer "B.Cu")
		(net 17)
	)
	(segment
		(start 143.161415 94.982831)
		(end 143.13216 94.968743)
		(width 0.145)
		(layer "B.Cu")
		(net 17)
	)
	(segment
		(start 143.228359 95.089372)
		(end 143.221133 95.057716)
		(width 0.145)
		(layer "B.Cu")
		(net 17)
	)
	(segment
		(start 143.007125 94.982831)
		(end 142.98174 95.003076)
		(width 0.145)
		(layer "B.Cu")
		(net 17)
	)
	(segment
		(start 142.958442 95.481234)
		(end 142.965667 95.449579)
		(width 0.145)
		(layer "B.Cu")
		(net 17)
	)
	(segment
		(start 143.207045 95.182751)
		(end 143.221133 95.153497)
		(width 0.145)
		(layer "B.Cu")
		(net 17)
	)
	(segment
		(start 142.979755 95.420324)
		(end 143 95.394939)
		(width 0.145)
		(layer "B.Cu")
		(net 17)
	)
	(segment
		(start 142.958442 95.513704)
		(end 142.958442 95.481234)
		(width 0.145)
		(layer "B.Cu")
		(net 17)
	)
	(segment
		(start 143.675 98.7)
		(end 143.675 97.09067)
		(width 0.145)
		(layer "B.Cu")
		(net 17)
	)
	(segment
		(start 142.708643 95.231435)
		(end 142.676173 95.231435)
		(width 0.145)
		(layer "B.Cu")
		(net 17)
	)
	(segment
		(start 143.186801 95.208137)
		(end 143.207045 95.182751)
		(width 0.145)
		(layer "B.Cu")
		(net 17)
	)
	(segment
		(start 142.676173 95.231435)
		(end 142.644517 95.224209)
		(width 0.145)
		(layer "B.Cu")
		(net 17)
	)
	(segment
		(start 150.425 85.025)
		(end 150.425 84.21)
		(width 0.145)
		(layer "B.Cu")
		(net 17)
	)
	(segment
		(start 142.98174 95.003076)
		(end 142.794938 95.189877)
		(width 0.145)
		(layer "B.Cu")
		(net 17)
	)
	(segment
		(start 142.375899 89.824101)
		(end 146.4 85.8)
		(width 0.145)
		(layer "B.Cu")
		(net 17)
	)
	(segment
		(start 143 95.394939)
		(end 143.186801 95.208137)
		(width 0.145)
		(layer "B.Cu")
		(net 17)
	)
	(segment
		(start 143 95.6)
		(end 142.979755 95.574614)
		(width 0.145)
		(layer "B.Cu")
		(net 17)
	)
	(segment
		(start 143.186801 95.003076)
		(end 143.161415 94.982831)
		(width 0.145)
		(layer "B.Cu")
		(net 17)
	)
	(segment
		(start 142.644517 95.224209)
		(end 142.615263 95.210121)
		(width 0.145)
		(layer "B.Cu")
		(net 17)
	)
	(segment
		(start 143.824101 96.424101)
		(end 143 95.6)
		(width 0.145)
		(layer "B.Cu")
		(net 17)
	)
	(segment
		(start 143.824101 96.941569)
		(end 143.824101 96.424101)
		(width 0.145)
		(layer "B.Cu")
		(net 17)
	)
	(segment
		(start 150.425 85.375)
		(end 150.425 85.025)
		(width 0.145)
		(layer "B.Cu")
		(net 17)
	)
	(segment
		(start 142.375899 94.975899)
		(end 142.375899 89.824101)
		(width 0.145)
		(layer "B.Cu")
		(net 17)
	)
	(segment
		(start 143.03638 94.968743)
		(end 143.007125 94.982831)
		(width 0.145)
		(layer "B.Cu")
		(net 17)
	)
	(segment
		(start 142.589878 95.189878)
		(end 142.375899 94.975899)
		(width 0.145)
		(layer "B.Cu")
		(net 17)
	)
	(segment
		(start 146.425 88.45)
		(end 145.85 88.45)
		(width 0.2)
		(layer "F.Cu")
		(net 18)
	)
	(segment
		(start 151.225 83.65)
		(end 151.225 84.21)
		(width 0.2)
		(layer "F.Cu")
		(net 18)
	)
	(segment
		(start 146.425 82.05)
		(end 145.825 82.05)
		(width 0.2)
		(layer "F.Cu")
		(net 18)
	)
	(segment
		(start 155.225 88.45)
		(end 155.625 88.85)
		(width 0.2)
		(layer "F.Cu")
		(net 18)
	)
	(segment
		(start 155.225 82.05)
		(end 155.225 81.45)
		(width 0.2)
		(layer "F.Cu")
		(net 18)
	)
	(segment
		(start 152.825 88.45)
		(end 153.225 88.85)
		(width 0.2)
		(layer "F.Cu")
		(net 18)
	)
	(segment
		(start 148.825 82.05)
		(end 148.825 81.45)
		(width 0.2)
		(layer "F.Cu")
		(net 18)
	)
	(segment
		(start 150.425 88.45)
		(end 150.025 88.85)
		(width 0.2)
		(layer "F.Cu")
		(net 18)
	)
	(segment
		(start 146.425 83.65)
		(end 145.825 83.65)
		(width 0.2)
		(layer "F.Cu")
		(net 18)
	)
	(segment
		(start 149.225 88.85)
		(end 148.825 88.45)
		(width 0.145)
		(layer "F.Cu")
		(net 18)
	)
	(segment
		(start 152.825 82.05)
		(end 152.825 81.45)
		(width 0.2)
		(layer "F.Cu")
		(net 18)
	)
	(segment
		(start 150.025 88.85)
		(end 149.225 88.85)
		(width 0.145)
		(layer "F.Cu")
		(net 18)
	)
	(via
		(at 151.225 84.21)
		(size 0.45)
		(drill 0.15)
		(layers "F.Cu" "B.Cu")
		(net 18)
	)
	(via
		(at 153.225 88.85)
		(size 0.45)
		(drill 0.15)
		(layers "F.Cu" "B.Cu")
		(net 18)
	)
	(via
		(at 145.825 82.05)
		(size 0.45)
		(drill 0.15)
		(layers "F.Cu" "B.Cu")
		(net 18)
	)
	(via
		(at 140.1 86.9)
		(size 0.45)
		(drill 0.15)
		(layers "F.Cu" "B.Cu")
		(net 18)
	)
	(via
		(at 145.85 88.45)
		(size 0.45)
		(drill 0.15)
		(layers "F.Cu" "B.Cu")
		(net 18)
	)
	(via
		(at 152.825 81.45)
		(size 0.45)
		(drill 0.15)
		(layers "F.Cu" "B.Cu")
		(net 18)
	)
	(via
		(at 145.825 83.65)
		(size 0.45)
		(drill 0.15)
		(layers "F.Cu" "B.Cu")
		(net 18)
	)
	(via
		(at 140.1 87.5)
		(size 0.45)
		(drill 0.15)
		(layers "F.Cu" "B.Cu")
		(net 18)
	)
	(via
		(at 140.7 87.5)
		(size 0.45)
		(drill 0.15)
		(layers "F.Cu" "B.Cu")
		(net 18)
	)
	(via
		(at 150.025 88.85)
		(size 0.45)
		(drill 0.15)
		(layers "F.Cu" "B.Cu")
		(net 18)
	)
	(via
		(at 140.7 86.9)
		(size 0.45)
		(drill 0.15)
		(layers "F.Cu" "B.Cu")
		(net 18)
	)
	(via
		(at 155.225 81.45)
		(size 0.45)
		(drill 0.15)
		(layers "F.Cu" "B.Cu")
		(net 18)
	)
	(via
		(at 155.625 88.85)
		(size 0.45)
		(drill 0.15)
		(layers "F.Cu" "B.Cu")
		(net 18)
	)
	(via
		(at 148.825 81.45)
		(size 0.45)
		(drill 0.15)
		(layers "F.Cu" "B.Cu")
		(net 18)
	)
	(segment
		(start 156.18 88.85)
		(end 155.625 88.85)
		(width 0.2)
		(layer "B.Cu")
		(net 18)
	)
	(segment
		(start 151.305 83.675)
		(end 151.305 84.13)
		(width 0.2)
		(layer "B.Cu")
		(net 18)
	)
	(segment
		(start 153.225 88.85)
		(end 152.745 88.85)
		(width 0.2)
		(layer "B.Cu")
		(net 18)
	)
	(segment
		(start 145.3 81.78)
		(end 145.555 81.78)
		(width 0.2)
		(layer "B.Cu")
		(net 18)
	)
	(segment
		(start 148.825 80.875)
		(end 148.82 80.87)
		(width 0.2)
		(layer "B.Cu")
		(net 18)
	)
	(segment
		(start 149.47 88.85)
		(end 150.025 88.85)
		(width 0.2)
		(layer "B.Cu")
		(net 18)
	)
	(segment
		(start 145.39 88.45)
		(end 145.32 88.38)
		(width 0.2)
		(layer "B.Cu")
		(net 18)
	)
	(segment
		(start 155.225 81.45)
		(end 155.225 80.77)
		(width 0.2)
		(layer "B.Cu")
		(net 18)
	)
	(segment
		(start 152.825 81.45)
		(end 152.825 80.745)
		(width 0.2)
		(layer "B.Cu")
		(net 18)
	)
	(segment
		(start 145.85 88.45)
		(end 145.39 88.45)
		(width 0.2)
		(layer "B.Cu")
		(net 18)
	)
	(segment
		(start 145.3 83.92)
		(end 145.555 83.92)
		(width 0.2)
		(layer "B.Cu")
		(net 18)
	)
	(segment
		(start 151.305 84.13)
		(end 151.225 84.21)
		(width 0.2)
		(layer "B.Cu")
		(net 18)
	)
	(segment
		(start 148.825 81.45)
		(end 148.825 80.875)
		(width 0.2)
		(layer "B.Cu")
		(net 18)
	)
	(segment
		(start 145.555 83.92)
		(end 145.825 83.65)
		(width 0.2)
		(layer "B.Cu")
		(net 18)
	)
	(segment
		(start 145.555 81.78)
		(end 145.825 82.05)
		(width 0.2)
		(layer "B.Cu")
		(net 18)
	)
	(segment
		(start 155.225 80.77)
		(end 155.2 80.745)
		(width 0.2)
		(layer "B.Cu")
		(net 18)
	)
	(segment
		(start 146.425 86.85)
		(end 146.425 85.425)
		(width 0.2)
		(layer "F.Cu")
		(net 19)
	)
	(segment
		(start 145.03 86.85)
		(end 145 86.88)
		(width 0.2)
		(layer "F.Cu")
		(net 19)
	)
	(segment
		(start 146.65 85.2)
		(end 155.6 85.2)
		(width 0.2)
		(layer "F.Cu")
		(net 19)
	)
	(segment
		(start 156.045 83.67)
		(end 156.025 83.65)
		(width 0.2)
		(layer "F.Cu")
		(net 19)
	)
	(segment
		(start 146.2 85.2)
		(end 139.2 85.2)
		(width 0.2)
		(layer "F.Cu")
		(net 19)
	)
	(segment
		(start 146.2 85.2)
		(end 146.65 85.2)
		(width 0.2)
		(layer "F.Cu")
		(net 19)
	)
	(segment
		(start 157.425 83.67)
		(end 156.045 83.67)
		(width 0.2)
		(layer "F.Cu")
		(net 19)
	)
	(segment
		(start 146.425 85.425)
		(end 146.2 85.2)
		(width 0.2)
		(layer "F.Cu")
		(net 19)
	)
	(segment
		(start 156.025 84.775)
		(end 156.025 83.65)
		(width 0.2)
		(layer "F.Cu")
		(net 19)
	)
	(segment
		(start 146.425 86.85)
		(end 145.03 86.85)
		(width 0.2)
		(layer "F.Cu")
		(net 19)
	)
	(segment
		(start 146.425 85.425)
		(end 146.65 85.2)
		(width 0.2)
		(layer "F.Cu")
		(net 19)
	)
	(segment
		(start 155.6 85.2)
		(end 156.025 84.775)
		(width 0.2)
		(layer "F.Cu")
		(net 19)
	)
	(segment
		(start 155.225 86.85)
		(end 155.225 86.275)
		(width 0.145)
		(layer "F.Cu")
		(net 20)
	)
	(via
		(at 154.1 94.3)
		(size 0.45)
		(drill 0.15)
		(layers "F.Cu" "B.Cu")
		(net 20)
	)
	(via
		(at 155.225 86.275)
		(size 0.45)
		(drill 0.15)
		(layers "F.Cu" "B.Cu")
		(net 20)
	)
	(segment
		(start 153.8 94.6)
		(end 152.4 94.6)
		(width 0.145)
		(layer "B.Cu")
		(net 20)
	)
	(segment
		(start 151.5 95.5)
		(end 151.5 96.9)
		(width 0.145)
		(layer "B.Cu")
		(net 20)
	)
	(segment
		(start 154.1 94.3)
		(end 153.8 94.6)
		(width 0.145)
		(layer "B.Cu")
		(net 20)
	)
	(segment
		(start 151.675 97.075)
		(end 151.675 98.7)
		(width 0.145)
		(layer "B.Cu")
		(net 20)
	)
	(segment
		(start 151.5 96.9)
		(end 151.675 97.075)
		(width 0.145)
		(layer "B.Cu")
		(net 20)
	)
	(segment
		(start 152.4 94.6)
		(end 151.5 95.5)
		(width 0.145)
		(layer "B.Cu")
		(net 20)
	)
	(segment
		(start 154.221009 93.494547)
		(end 154.1984 93.492)
		(width 0.1016)
		(layer "In2.Cu")
		(net 20)
	)
	(segment
		(start 154.3 93.1872)
		(end 154.297453 93.164591)
		(width 0.1016)
		(layer "In2.Cu")
		(net 20)
	)
	(segment
		(start 154.242483 92.872338)
		(end 154.261747 92.860234)
		(width 0.1016)
		(layer "In2.Cu")
		(net 20)
	)
	(segment
		(start 154.261747 93.673034)
		(end 154.277835 93.656946)
		(width 0.1016)
		(layer "In2.Cu")
		(net 20)
	)
	(segment
		(start 153.635504 93.840882)
		(end 153.62799 93.819408)
		(width 0.1016)
		(layer "In2.Cu")
		(net 20)
	)
	(segment
		(start 155.636746 89.444834)
		(end 155.652834 89.428746)
		(width 0.1016)
		(layer "In2.Cu")
		(net 20)
	)
	(segment
		(start 153.647608 93.733453)
		(end 153.663696 93.717365)
		(width 0.1016)
		(layer "In2.Cu")
		(net 20)
	)
	(segment
		(start 153.635504 93.346317)
		(end 153.647608 93.327053)
		(width 0.1016)
		(layer "In2.Cu")
		(net 20)
	)
	(segment
		(start 155.675 89.7718)
		(end 155.672452 89.749191)
		(width 0.1016)
		(layer "In2.Cu")
		(net 20)
	)
	(segment
		(start 154.297453 93.616208)
		(end 154.3 93.5936)
		(width 0.1016)
		(layer "In2.Cu")
		(net 20)
	)
	(segment
		(start 155.282517 89.883461)
		(end 155.303991 89.875947)
		(width 0.1016)
		(layer "In2.Cu")
		(net 20)
	)
	(segment
		(start 155.247165 89.225546)
		(end 155.235061 89.206282)
		(width 0.1016)
		(layer "In2.Cu")
		(net 20)
	)
	(segment
		(start 155.5734 89.467)
		(end 155.596008 89.464452)
		(width 0.1016)
		(layer "In2.Cu")
		(net 20)
	)
	(segment
		(start 153.704434 93.697747)
		(end 153.727042 93.6952)
		(width 0.1016)
		(layer "In2.Cu")
		(net 20)
	)
	(segment
		(start 155.3266 89.6702)
		(end 155.303991 89.667652)
		(width 0.1016)
		(layer "In2.Cu")
		(net 20)
	)
	(segment
		(start 155.652834 89.708453)
		(end 155.636746 89.692365)
		(width 0.1016)
		(layer "In2.Cu")
		(net 20)
	)
	(segment
		(start 153.727042 92.8824)
		(end 154.1984 92.8824)
		(width 0.1016)
		(layer "In2.Cu")
		(net 20)
	)
	(segment
		(start 154.261747 93.920565)
		(end 154.242483 93.908461)
		(width 0.1016)
		(layer "In2.Cu")
		(net 20)
	)
	(segment
		(start 155.263253 89.895565)
		(end 155.282517 89.883461)
		(width 0.1016)
		(layer "In2.Cu")
		(net 20)
	)
	(segment
		(start 155.596008 89.464452)
		(end 155.617482 89.456938)
		(width 0.1016)
		(layer "In2.Cu")
		(net 20)
	)
	(segment
		(start 154.1984 93.0856)
		(end 153.727042 93.0856)
		(width 0.1016)
		(layer "In2.Cu")
		(net 20)
	)
	(segment
		(start 153.727042 93.492)
		(end 153.704434 93.489452)
		(width 0.1016)
		(layer "In2.Cu")
		(net 20)
	)
	(segment
		(start 155.247165 89.505253)
		(end 155.263253 89.489165)
		(width 0.1016)
		(layer "In2.Cu")
		(net 20)
	)
	(segment
		(start 155.235061 89.612682)
		(end 155.227547 89.591208)
		(width 0.1016)
		(layer "In2.Cu")
		(net 20)
	)
	(segment
		(start 154.3 94.1)
		(end 154.3 94)
		(width 0.1016)
		(layer "In2.Cu")
		(net 20)
	)
	(segment
		(start 155.225 90.275)
		(end 155.225 89.975)
		(width 0.1016)
		(layer "In2.Cu")
		(net 20)
	)
	(segment
		(start 153.62799 93.367791)
		(end 153.635504 93.346317)
		(width 0.1016)
		(layer "In2.Cu")
		(net 20)
	)
	(segment
		(start 155.672452 89.749191)
		(end 155.664938 89.727717)
		(width 0.1016)
		(layer "In2.Cu")
		(net 20)
	)
	(segment
		(start 155.617482 89.273861)
		(end 155.596008 89.266347)
		(width 0.1016)
		(layer "In2.Cu")
		(net 20)
	)
	(segment
		(start 153.635504 93.028082)
		(end 153.62799 93.006608)
		(width 0.1016)
		(layer "In2.Cu")
		(net 20)
	)
	(segment
		(start 155.652834 89.302053)
		(end 155.636746 89.285965)
		(width 0.1016)
		(layer "In2.Cu")
		(net 20)
	)
	(segment
		(start 154.1984 93.6952)
		(end 154.221009 93.692652)
		(width 0.1016)
		(layer "In2.Cu")
		(net 20)
	)
	(segment
		(start 155.636746 89.285965)
		(end 155.617482 89.273861)
		(width 0.1016)
		(layer "In2.Cu")
		(net 20)
	)
	(segment
		(start 153.62799 93.006608)
		(end 153.625442 92.984)
		(width 0.1016)
		(layer "In2.Cu")
		(net 20)
	)
	(segment
		(start 153.68296 93.481938)
		(end 153.663696 93.469834)
		(width 0.1016)
		(layer "In2.Cu")
		(net 20)
	)
	(segment
		(start 155.235061 89.206282)
		(end 155.227547 89.184808)
		(width 0.1016)
		(layer "In2.Cu")
		(net 20)
	)
	(segment
		(start 153.663696 93.876234)
		(end 153.647608 93.860146)
		(width 0.1016)
		(layer "In2.Cu")
		(net 20)
	)
	(segment
		(start 154.289939 93.231282)
		(end 154.297453 93.209808)
		(width 0.1016)
		(layer "In2.Cu")
		(net 20)
	)
	(segment
		(start 155.664938 89.727717)
		(end 155.652834 89.708453)
		(width 0.1016)
		(layer "In2.Cu")
		(net 20)
	)
	(segment
		(start 155.263253 89.489165)
		(end 155.282517 89.477061)
		(width 0.1016)
		(layer "In2.Cu")
		(net 20)
	)
	(segment
		(start 154.221009 92.879852)
		(end 154.242483 92.872338)
		(width 0.1016)
		(layer "In2.Cu")
		(net 20)
	)
	(segment
		(start 153.727042 93.8984)
		(end 153.704434 93.895852)
		(width 0.1016)
		(layer "In2.Cu")
		(net 20)
	)
	(segment
		(start 153.704434 93.489452)
		(end 153.68296 93.481938)
		(width 0.1016)
		(layer "In2.Cu")
		(net 20)
	)
	(segment
		(start 154.3 91.2)
		(end 155.225 90.275)
		(width 0.1016)
		(layer "In2.Cu")
		(net 20)
	)
	(segment
		(start 155.3266 89.467)
		(end 155.5734 89.467)
		(width 0.1016)
		(layer "In2.Cu")
		(net 20)
	)
	(segment
		(start 155.303991 89.261252)
		(end 155.282517 89.253738)
		(width 0.1016)
		(layer "In2.Cu")
		(net 20)
	)
	(segment
		(start 155.282517 89.253738)
		(end 155.263253 89.241634)
		(width 0.1016)
		(layer "In2.Cu")
		(net 20)
	)
	(segment
		(start 154.3 92.7808)
		(end 154.3 91.2)
		(width 0.1016)
		(layer "In2.Cu")
		(net 20)
	)
	(segment
		(start 154.297453 92.803408)
		(end 154.3 92.7808)
		(width 0.1016)
		(layer "In2.Cu")
		(net 20)
	)
	(segment
		(start 153.68296 92.892461)
		(end 153.704434 92.884947)
		(width 0.1016)
		(layer "In2.Cu")
		(net 20)
	)
	(segment
		(start 154.261747 93.266634)
		(end 154.277835 93.250546)
		(width 0.1016)
		(layer "In2.Cu")
		(net 20)
	)
	(segment
		(start 153.704434 92.884947)
		(end 153.727042 92.8824)
		(width 0.1016)
		(layer "In2.Cu")
		(net 20)
	)
	(segment
		(start 154.1984 93.2888)
		(end 154.221009 93.286252)
		(width 0.1016)
		(layer "In2.Cu")
		(net 20)
	)
	(segment
		(start 154.277835 93.656946)
		(end 154.289939 93.637682)
		(width 0.1016)
		(layer "In2.Cu")
		(net 20)
	)
	(segment
		(start 155.225 89.1622)
		(end 155.225 86.275)
		(width 0.1016)
		(layer "In2.Cu")
		(net 20)
	)
	(segment
		(start 155.282517 89.660138)
		(end 155.263253 89.648034)
		(width 0.1016)
		(layer "In2.Cu")
		(net 20)
	)
	(segment
		(start 154.277835 92.844146)
		(end 154.289939 92.824882)
		(width 0.1016)
		(layer "In2.Cu")
		(net 20)
	)
	(segment
		(start 155.617482 89.863338)
		(end 155.636746 89.851234)
		(width 0.1016)
		(layer "In2.Cu")
		(net 20)
	)
	(segment
		(start 154.289939 93.955917)
		(end 154.277835 93.936653)
		(width 0.1016)
		(layer "In2.Cu")
		(net 20)
	)
	(segment
		(start 154.297453 93.209808)
		(end 154.3 93.1872)
		(width 0.1016)
		(layer "In2.Cu")
		(net 20)
	)
	(segment
		(start 154.221009 93.900947)
		(end 154.1984 93.8984)
		(width 0.1016)
		(layer "In2.Cu")
		(net 20)
	)
	(segment
		(start 153.647608 93.327053)
		(end 153.663696 93.310965)
		(width 0.1016)
		(layer "In2.Cu")
		(net 20)
	)
	(segment
		(start 154.242483 93.908461)
		(end 154.221009 93.900947)
		(width 0.1016)
		(layer "In2.Cu")
		(net 20)
	)
	(segment
		(start 154.277835 93.250546)
		(end 154.289939 93.231282)
		(width 0.1016)
		(layer "In2.Cu")
		(net 20)
	)
	(segment
		(start 155.227547 89.184808)
		(end 155.225 89.1622)
		(width 0.1016)
		(layer "In2.Cu")
		(net 20)
	)
	(segment
		(start 155.227547 89.545991)
		(end 155.235061 89.524517)
		(width 0.1016)
		(layer "In2.Cu")
		(net 20)
	)
	(segment
		(start 155.652834 89.835146)
		(end 155.664938 89.815882)
		(width 0.1016)
		(layer "In2.Cu")
		(net 20)
	)
	(segment
		(start 154.221009 93.692652)
		(end 154.242483 93.685138)
		(width 0.1016)
		(layer "In2.Cu")
		(net 20)
	)
	(segment
		(start 154.289939 93.143117)
		(end 154.277835 93.123853)
		(width 0.1016)
		(layer "In2.Cu")
		(net 20)
	)
	(segment
		(start 154.221009 93.088147)
		(end 154.1984 93.0856)
		(width 0.1016)
		(layer "In2.Cu")
		(net 20)
	)
	(segment
		(start 153.62799 93.413008)
		(end 153.625442 93.3904)
		(width 0.1016)
		(layer "In2.Cu")
		(net 20)
	)
	(segment
		(start 153.647608 93.047346)
		(end 153.635504 93.028082)
		(width 0.1016)
		(layer "In2.Cu")
		(net 20)
	)
	(segment
		(start 154.277835 93.123853)
		(end 154.261747 93.107765)
		(width 0.1016)
		(layer "In2.Cu")
		(net 20)
	)
	(segment
		(start 153.68296 93.888338)
		(end 153.663696 93.876234)
		(width 0.1016)
		(layer "In2.Cu")
		(net 20)
	)
	(segment
		(start 153.635504 92.939917)
		(end 153.647608 92.920653)
		(width 0.1016)
		(layer "In2.Cu")
		(net 20)
	)
	(segment
		(start 155.664938 89.321317)
		(end 155.652834 89.302053)
		(width 0.1016)
		(layer "In2.Cu")
		(net 20)
	)
	(segment
		(start 153.704434 93.895852)
		(end 153.68296 93.888338)
		(width 0.1016)
		(layer "In2.Cu")
		(net 20)
	)
	(segment
		(start 155.672452 89.342791)
		(end 155.664938 89.321317)
		(width 0.1016)
		(layer "In2.Cu")
		(net 20)
	)
	(segment
		(start 154.261747 93.107765)
		(end 154.242483 93.095661)
		(width 0.1016)
		(layer "In2.Cu")
		(net 20)
	)
	(segment
		(start 155.303991 89.469547)
		(end 155.3266 89.467)
		(width 0.1016)
		(layer "In2.Cu")
		(net 20)
	)
	(segment
		(start 155.3266 89.8734)
		(end 155.5734 89.8734)
		(width 0.1016)
		(layer "In2.Cu")
		(net 20)
	)
	(segment
		(start 155.596008 89.266347)
		(end 155.5734 89.2638)
		(width 0.1016)
		(layer "In2.Cu")
		(net 20)
	)
	(segment
		(start 154.297453 93.570991)
		(end 154.289939 93.549517)
		(width 0.1016)
		(layer "In2.Cu")
		(net 20)
	)
	(segment
		(start 154.277835 93.530253)
		(end 154.261747 93.514165)
		(width 0.1016)
		(layer "In2.Cu")
		(net 20)
	)
	(segment
		(start 153.663696 93.469834)
		(end 153.647608 93.453746)
		(width 0.1016)
		(layer "In2.Cu")
		(net 20)
	)
	(segment
		(start 155.225 89.5686)
		(end 155.227547 89.545991)
		(width 0.1016)
		(layer "In2.Cu")
		(net 20)
	)
	(segment
		(start 153.625442 93.3904)
		(end 153.62799 93.367791)
		(width 0.1016)
		(layer "In2.Cu")
		(net 20)
	)
	(segment
		(start 153.68296 93.075538)
		(end 153.663696 93.063434)
		(width 0.1016)
		(layer "In2.Cu")
		(net 20)
	)
	(segment
		(start 155.617482 89.680261)
		(end 155.596008 89.672747)
		(width 0.1016)
		(layer "In2.Cu")
		(net 20)
	)
	(segment
		(start 155.303991 89.875947)
		(end 155.3266 89.8734)
		(width 0.1016)
		(layer "In2.Cu")
		(net 20)
	)
	(segment
		(start 155.303991 89.667652)
		(end 155.282517 89.660138)
		(width 0.1016)
		(layer "In2.Cu")
		(net 20)
	)
	(segment
		(start 154.242483 93.095661)
		(end 154.221009 93.088147)
		(width 0.1016)
		(layer "In2.Cu")
		(net 20)
	)
	(segment
		(start 154.261747 93.514165)
		(end 154.242483 93.502061)
		(width 0.1016)
		(layer "In2.Cu")
		(net 20)
	)
	(segment
		(start 154.242483 93.278738)
		(end 154.261747 93.266634)
		(width 0.1016)
		(layer "In2.Cu")
		(net 20)
	)
	(segment
		(start 153.635504 93.752717)
		(end 153.647608 93.733453)
		(width 0.1016)
		(layer "In2.Cu")
		(net 20)
	)
	(segment
		(start 155.5734 89.2638)
		(end 155.3266 89.2638)
		(width 0.1016)
		(layer "In2.Cu")
		(net 20)
	)
	(segment
		(start 153.663696 93.063434)
		(end 153.647608 93.047346)
		(width 0.1016)
		(layer "In2.Cu")
		(net 20)
	)
	(segment
		(start 153.727042 93.2888)
		(end 154.1984 93.2888)
		(width 0.1016)
		(layer "In2.Cu")
		(net 20)
	)
	(segment
		(start 155.636746 89.692365)
		(end 155.617482 89.680261)
		(width 0.1016)
		(layer "In2.Cu")
		(net 20)
	)
	(segment
		(start 153.647608 93.860146)
		(end 153.635504 93.840882)
		(width 0.1016)
		(layer "In2.Cu")
		(net 20)
	)
	(segment
		(start 155.652834 89.428746)
		(end 155.664938 89.409482)
		(width 0.1016)
		(layer "In2.Cu")
		(net 20)
	)
	(segment
		(start 154.242483 93.685138)
		(end 154.261747 93.673034)
		(width 0.1016)
		(layer "In2.Cu")
		(net 20)
	)
	(segment
		(start 155.675 89.3654)
		(end 155.672452 89.342791)
		(width 0.1016)
		(layer "In2.Cu")
		(net 20)
	)
	(segment
		(start 153.68296 93.705261)
		(end 153.704434 93.697747)
		(width 0.1016)
		(layer "In2.Cu")
		(net 20)
	)
	(segment
		(start 155.247165 89.631946)
		(end 155.235061 89.612682)
		(width 0.1016)
		(layer "In2.Cu")
		(net 20)
	)
	(segment
		(start 154.297453 93.977391)
		(end 154.289939 93.955917)
		(width 0.1016)
		(layer "In2.Cu")
		(net 20)
	)
	(segment
		(start 155.263253 89.241634)
		(end 155.247165 89.225546)
		(width 0.1016)
		(layer "In2.Cu")
		(net 20)
	)
	(segment
		(start 155.235061 89.930917)
		(end 155.247165 89.911653)
		(width 0.1016)
		(layer "In2.Cu")
		(net 20)
	)
	(segment
		(start 153.62799 93.819408)
		(end 153.625442 93.7968)
		(width 0.1016)
		(layer "In2.Cu")
		(net 20)
	)
	(segment
		(start 153.663696 92.904565)
		(end 153.68296 92.892461)
		(width 0.1016)
		(layer "In2.Cu")
		(net 20)
	)
	(segment
		(start 154.297453 93.164591)
		(end 154.289939 93.143117)
		(width 0.1016)
		(layer "In2.Cu")
		(net 20)
	)
	(segment
		(start 155.617482 89.456938)
		(end 155.636746 89.444834)
		(width 0.1016)
		(layer "In2.Cu")
		(net 20)
	)
	(segment
		(start 153.663696 93.310965)
		(end 153.68296 93.298861)
		(width 0.1016)
		(layer "In2.Cu")
		(net 20)
	)
	(segment
		(start 154.1 94.3)
		(end 154.3 94.1)
		(width 0.1016)
		(layer "In2.Cu")
		(net 20)
	)
	(segment
		(start 154.277835 93.936653)
		(end 154.261747 93.920565)
		(width 0.1016)
		(layer "In2.Cu")
		(net 20)
	)
	(segment
		(start 155.672452 89.794408)
		(end 155.675 89.7718)
		(width 0.1016)
		(layer "In2.Cu")
		(net 20)
	)
	(segment
		(start 155.263253 89.648034)
		(end 155.247165 89.631946)
		(width 0.1016)
		(layer "In2.Cu")
		(net 20)
	)
	(segment
		(start 153.68296 93.298861)
		(end 153.704434 93.291347)
		(width 0.1016)
		(layer "In2.Cu")
		(net 20)
	)
	(segment
		(start 155.596008 89.870852)
		(end 155.617482 89.863338)
		(width 0.1016)
		(layer "In2.Cu")
		(net 20)
	)
	(segment
		(start 155.235061 89.524517)
		(end 155.247165 89.505253)
		(width 0.1016)
		(layer "In2.Cu")
		(net 20)
	)
	(segment
		(start 153.727042 93.6952)
		(end 154.1984 93.6952)
		(width 0.1016)
		(layer "In2.Cu")
		(net 20)
	)
	(segment
		(start 155.672452 89.388008)
		(end 155.675 89.3654)
		(width 0.1016)
		(layer "In2.Cu")
		(net 20)
	)
	(segment
		(start 155.596008 89.672747)
		(end 155.5734 89.6702)
		(width 0.1016)
		(layer "In2.Cu")
		(net 20)
	)
	(segment
		(start 154.3 94)
		(end 154.297453 93.977391)
		(width 0.1016)
		(layer "In2.Cu")
		(net 20)
	)
	(segment
		(start 153.647608 92.920653)
		(end 153.663696 92.904565)
		(width 0.1016)
		(layer "In2.Cu")
		(net 20)
	)
	(segment
		(start 153.647608 93.453746)
		(end 153.635504 93.434482)
		(width 0.1016)
		(layer "In2.Cu")
		(net 20)
	)
	(segment
		(start 153.635504 93.434482)
		(end 153.62799 93.413008)
		(width 0.1016)
		(layer "In2.Cu")
		(net 20)
	)
	(segment
		(start 155.664938 89.409482)
		(end 155.672452 89.388008)
		(width 0.1016)
		(layer "In2.Cu")
		(net 20)
	)
	(segment
		(start 154.221009 93.286252)
		(end 154.242483 93.278738)
		(width 0.1016)
		(layer "In2.Cu")
		(net 20)
	)
	(segment
		(start 154.1984 92.8824)
		(end 154.221009 92.879852)
		(width 0.1016)
		(layer "In2.Cu")
		(net 20)
	)
	(segment
		(start 153.663696 93.717365)
		(end 153.68296 93.705261)
		(width 0.1016)
		(layer "In2.Cu")
		(net 20)
	)
	(segment
		(start 155.5734 89.6702)
		(end 155.3266 89.6702)
		(width 0.1016)
		(layer "In2.Cu")
		(net 20)
	)
	(segment
		(start 153.62799 92.961391)
		(end 153.635504 92.939917)
		(width 0.1016)
		(layer "In2.Cu")
		(net 20)
	)
	(segment
		(start 154.289939 92.824882)
		(end 154.297453 92.803408)
		(width 0.1016)
		(layer "In2.Cu")
		(net 20)
	)
	(segment
		(start 155.5734 89.8734)
		(end 155.596008 89.870852)
		(width 0.1016)
		(layer "In2.Cu")
		(net 20)
	)
	(segment
		(start 155.3266 89.2638)
		(end 155.303991 89.261252)
		(width 0.1016)
		(layer "In2.Cu")
		(net 20)
	)
	(segment
		(start 155.282517 89.477061)
		(end 155.303991 89.469547)
		(width 0.1016)
		(layer "In2.Cu")
		(net 20)
	)
	(segment
		(start 154.261747 92.860234)
		(end 154.277835 92.844146)
		(width 0.1016)
		(layer "In2.Cu")
		(net 20)
	)
	(segment
		(start 154.242483 93.502061)
		(end 154.221009 93.494547)
		(width 0.1016)
		(layer "In2.Cu")
		(net 20)
	)
	(segment
		(start 155.636746 89.851234)
		(end 155.652834 89.835146)
		(width 0.1016)
		(layer "In2.Cu")
		(net 20)
	)
	(segment
		(start 153.704434 93.083052)
		(end 153.68296 93.075538)
		(width 0.1016)
		(layer "In2.Cu")
		(net 20)
	)
	(segment
		(start 153.625442 93.7968)
		(end 153.62799 93.774191)
		(width 0.1016)
		(layer "In2.Cu")
		(net 20)
	)
	(segment
		(start 154.3 93.5936)
		(end 154.297453 93.570991)
		(width 0.1016)
		(layer "In2.Cu")
		(net 20)
	)
	(segment
		(start 154.289939 93.637682)
		(end 154.297453 93.616208)
		(width 0.1016)
		(layer "In2.Cu")
		(net 20)
	)
	(segment
		(start 155.225 89.975)
		(end 155.227547 89.952391)
		(width 0.1016)
		(layer "In2.Cu")
		(net 20)
	)
	(segment
		(start 155.247165 89.911653)
		(end 155.263253 89.895565)
		(width 0.1016)
		(layer "In2.Cu")
		(net 20)
	)
	(segment
		(start 154.1984 93.492)
		(end 153.727042 93.492)
		(width 0.1016)
		(layer "In2.Cu")
		(net 20)
	)
	(segment
		(start 155.227547 89.952391)
		(end 155.235061 89.930917)
		(width 0.1016)
		(layer "In2.Cu")
		(net 20)
	)
	(segment
		(start 153.727042 93.0856)
		(end 153.704434 93.083052)
		(width 0.1016)
		(layer "In2.Cu")
		(net 20)
	)
	(segment
		(start 153.62799 93.774191)
		(end 153.635504 93.752717)
		(width 0.1016)
		(layer "In2.Cu")
		(net 20)
	)
	(segment
		(start 154.289939 93.549517)
		(end 154.277835 93.530253)
		(width 0.1016)
		(layer "In2.Cu")
		(net 20)
	)
	(segment
		(start 153.625442 92.984)
		(end 153.62799 92.961391)
		(width 0.1016)
		(layer "In2.Cu")
		(net 20)
	)
	(segment
		(start 153.704434 93.291347)
		(end 153.727042 93.2888)
		(width 0.1016)
		(layer "In2.Cu")
		(net 20)
	)
	(segment
		(start 155.664938 89.815882)
		(end 155.672452 89.794408)
		(width 0.1016)
		(layer "In2.Cu")
		(net 20)
	)
	(segment
		(start 155.227547 89.591208)
		(end 155.225 89.5686)
		(width 0.1016)
		(layer "In2.Cu")
		(net 20)
	)
	(segment
		(start 154.1984 93.8984)
		(end 153.727042 93.8984)
		(width 0.1016)
		(layer "In2.Cu")
		(net 20)
	)
	(segment
		(start 155.225 83.65)
		(end 155.225 84.21)
		(width 0.145)
		(layer "F.Cu")
		(net 21)
	)
	(via
		(at 155.5 92.7)
		(size 0.45)
		(drill 0.15)
		(layers "F.Cu" "B.Cu")
		(net 21)
	)
	(via
		(at 155.225 84.21)
		(size 0.45)
		(drill 0.15)
		(layers "F.Cu" "B.Cu")
		(net 21)
	)
	(segment
		(start 152.6 95)
		(end 152.2 95.4)
		(width 0.145)
		(layer "B.Cu")
		(net 21)
	)
	(segment
		(start 152.2 95.4)
		(end 152.2 96.43433)
		(width 0.145)
		(layer "B.Cu")
		(net 21)
	)
	(segment
		(start 152.2 96.43433)
		(end 152.324101 96.558431)
		(width 0.145)
		(layer "B.Cu")
		(net 21)
	)
	(segment
		(start 155.5 92.7)
		(end 155.5 93.9)
		(width 0.145)
		(layer "B.Cu")
		(net 21)
	)
	(segment
		(start 152.324101 96.941569)
		(end 152.175 97.09067)
		(width 0.145)
		(layer "B.Cu")
		(net 21)
	)
	(segment
		(start 154.4 95)
		(end 152.6 95)
		(width 0.145)
		(layer "B.Cu")
		(net 21)
	)
	(segment
		(start 152.175 97.09067)
		(end 152.175 98.7)
		(width 0.145)
		(layer "B.Cu")
		(net 21)
	)
	(segment
		(start 152.324101 96.558431)
		(end 152.324101 96.941569)
		(width 0.145)
		(layer "B.Cu")
		(net 21)
	)
	(segment
		(start 155.5 93.9)
		(end 154.4 95)
		(width 0.145)
		(layer "B.Cu")
		(net 21)
	)
	(segment
		(start 156.459569 85.449058)
		(end 156.481734 85.466734)
		(width 0.1016)
		(layer "In2.Cu")
		(net 21)
	)
	(segment
		(start 156.240133 85.529296)
		(end 156.302694 85.466734)
		(width 0.1016)
		(layer "In2.Cu")
		(net 21)
	)
	(segment
		(start 156.736117 85.788527)
		(end 156.764467 85.788527)
		(width 0.1016)
		(layer "In2.Cu")
		(net 21)
	)
	(segment
		(start 155.437475 84.523833)
		(end 155.425175 84.549374)
		(width 0.1016)
		(layer "In2.Cu")
		(net 21)
	)
	(segment
		(start 155.778361 85.207502)
		(end 155.80671 85.207502)
		(width 0.1016)
		(layer "In2.Cu")
		(net 21)
	)
	(segment
		(start 155.314962 84.765434)
		(end 155.327262 84.790975)
		(width 0.1016)
		(layer "In2.Cu")
		(net 21)
	)
	(segment
		(start 155.443784 84.496194)
		(end 155.437475 84.523833)
		(width 0.1016)
		(layer "In2.Cu")
		(net 21)
	)
	(segment
		(start 156.792106 85.794836)
		(end 156.817647 85.807136)
		(width 0.1016)
		(layer "In2.Cu")
		(net 21)
	)
	(segment
		(start 156.522866 85.923658)
		(end 156.550505 85.917349)
		(width 0.1016)
		(layer "In2.Cu")
		(net 21)
	)
	(segment
		(start 156.598211 85.887374)
		(end 156.660772 85.824812)
		(width 0.1016)
		(layer "In2.Cu")
		(net 21)
	)
	(segment
		(start 156.164788 85.56558)
		(end 156.192427 85.559271)
		(width 0.1016)
		(layer "In2.Cu")
		(net 21)
	)
	(segment
		(start 156.083258 85.546971)
		(end 156.1088 85.559271)
		(width 0.1016)
		(layer "In2.Cu")
		(net 21)
	)
	(segment
		(start 155.476271 84.843115)
		(end 155.501812 84.830815)
		(width 0.1016)
		(layer "In2.Cu")
		(net 21)
	)
	(segment
		(start 155.783253 84.772742)
		(end 155.795553 84.798284)
		(width 0.1016)
		(layer "In2.Cu")
		(net 21)
	)
	(segment
		(start 155.750722 85.201193)
		(end 155.778361 85.207502)
		(width 0.1016)
		(layer "In2.Cu")
		(net 21)
	)
	(segment
		(start 156.141331 85.26553)
		(end 156.123656 85.287695)
		(width 0.1016)
		(layer "In2.Cu")
		(net 21)
	)
	(segment
		(start 156.031118 85.397963)
		(end 156.024809 85.425601)
		(width 0.1016)
		(layer "In2.Cu")
		(net 21)
	)
	(segment
		(start 155.783253 84.907452)
		(end 155.765578 84.929617)
		(width 0.1016)
		(layer "In2.Cu")
		(net 21)
	)
	(segment
		(start 156.048311 85.072371)
		(end 156.07595 85.07868)
		(width 0.1016)
		(layer "In2.Cu")
		(net 21)
	)
	(segment
		(start 155.666731 85.095873)
		(end 155.67304 85.123512)
		(width 0.1016)
		(layer "In2.Cu")
		(net 21)
	)
	(segment
		(start 156.192427 85.559271)
		(end 156.217968 85.546971)
		(width 0.1016)
		(layer "In2.Cu")
		(net 21)
	)
	(segment
		(start 156.660772 85.824812)
		(end 156.682937 85.807136)
		(width 0.1016)
		(layer "In2.Cu")
		(net 21)
	)
	(segment
		(start 155.801862 84.854272)
		(end 155.795553 84.881911)
		(width 0.1016)
		(layer "In2.Cu")
		(net 21)
	)
	(segment
		(start 155.425175 84.549374)
		(end 155.4075 84.571539)
		(width 0.1016)
		(layer "In2.Cu")
		(net 21)
	)
	(segment
		(start 155.795553 84.881911)
		(end 155.783253 84.907452)
		(width 0.1016)
		(layer "In2.Cu")
		(net 21)
	)
	(segment
		(start 156.019961 85.072371)
		(end 156.048311 85.072371)
		(width 0.1016)
		(layer "In2.Cu")
		(net 21)
	)
	(segment
		(start 155.523977 84.81314)
		(end 155.586538 84.750578)
		(width 0.1016)
		(layer "In2.Cu")
		(net 21)
	)
	(segment
		(start 155.425175 84.414664)
		(end 155.437475 84.440206)
		(width 0.1016)
		(layer "In2.Cu")
		(net 21)
	)
	(segment
		(start 156.302694 85.466734)
		(end 156.324859 85.449058)
		(width 0.1016)
		(layer "In2.Cu")
		(net 21)
	)
	(segment
		(start 155.67304 85.123512)
		(end 155.68534 85.149053)
		(width 0.1016)
		(layer "In2.Cu")
		(net 21)
	)
	(segment
		(start 155.966781 85.09098)
		(end 155.992323 85.07868)
		(width 0.1016)
		(layer "In2.Cu")
		(net 21)
	)
	(segment
		(start 155.437475 84.440206)
		(end 155.443784 84.467845)
		(width 0.1016)
		(layer "In2.Cu")
		(net 21)
	)
	(segment
		(start 155.801862 84.825923)
		(end 155.801862 84.854272)
		(width 0.1016)
		(layer "In2.Cu")
		(net 21)
	)
	(segment
		(start 155.68534 85.014343)
		(end 155.67304 85.039885)
		(width 0.1016)
		(layer "In2.Cu")
		(net 21)
	)
	(segment
		(start 156.839812 85.824812)
		(end 157.2 86.185)
		(width 0.1016)
		(layer "In2.Cu")
		(net 21)
	)
	(segment
		(start 156.406389 85.430449)
		(end 156.434028 85.436758)
		(width 0.1016)
		(layer "In2.Cu")
		(net 21)
	)
	(segment
		(start 156.499409 85.623608)
		(end 156.481734 85.645773)
		(width 0.1016)
		(layer "In2.Cu")
		(net 21)
	)
	(segment
		(start 155.634245 84.720602)
		(end 155.661883 84.714293)
		(width 0.1016)
		(layer "In2.Cu")
		(net 21)
	)
	(segment
		(start 156.511709 85.51444)
		(end 156.518018 85.542079)
		(width 0.1016)
		(layer "In2.Cu")
		(net 21)
	)
	(segment
		(start 156.708479 85.794836)
		(end 156.736117 85.788527)
		(width 0.1016)
		(layer "In2.Cu")
		(net 21)
	)
	(segment
		(start 157.2 89.8)
		(end 155.5 91.5)
		(width 0.1016)
		(layer "In2.Cu")
		(net 21)
	)
	(segment
		(start 156.466878 85.917349)
		(end 156.494517 85.923658)
		(width 0.1016)
		(layer "In2.Cu")
		(net 21)
	)
	(segment
		(start 155.586538 84.750578)
		(end 155.608703 84.732902)
		(width 0.1016)
		(layer "In2.Cu")
		(net 21)
	)
	(segment
		(start 155.72518 85.188893)
		(end 155.750722 85.201193)
		(width 0.1016)
		(layer "In2.Cu")
		(net 21)
	)
	(segment
		(start 155.661883 84.714293)
		(end 155.690233 84.714293)
		(width 0.1016)
		(layer "In2.Cu")
		(net 21)
	)
	(segment
		(start 156.123656 85.108656)
		(end 156.141331 85.13082)
		(width 0.1016)
		(layer "In2.Cu")
		(net 21)
	)
	(segment
		(start 156.576046 85.905049)
		(end 156.598211 85.887374)
		(width 0.1016)
		(layer "In2.Cu")
		(net 21)
	)
	(segment
		(start 155.344938 84.6341)
		(end 155.327262 84.656265)
		(width 0.1016)
		(layer "In2.Cu")
		(net 21)
	)
	(segment
		(start 157.2 86.185)
		(end 157.2 89.8)
		(width 0.1016)
		(layer "In2.Cu")
		(net 21)
	)
	(segment
		(start 156.324859 85.449058)
		(end 156.350401 85.436758)
		(width 0.1016)
		(layer "In2.Cu")
		(net 21)
	)
	(segment
		(start 155.327262 84.656265)
		(end 155.314962 84.681807)
		(width 0.1016)
		(layer "In2.Cu")
		(net 21)
	)
	(segment
		(start 155.743413 84.732902)
		(end 155.765578 84.750578)
		(width 0.1016)
		(layer "In2.Cu")
		(net 21)
	)
	(segment
		(start 155.344938 84.81314)
		(end 155.367102 84.830815)
		(width 0.1016)
		(layer "In2.Cu")
		(net 21)
	)
	(segment
		(start 155.795553 84.798284)
		(end 155.801862 84.825923)
		(width 0.1016)
		(layer "In2.Cu")
		(net 21)
	)
	(segment
		(start 155.68534 85.149053)
		(end 155.703016 85.171218)
		(width 0.1016)
		(layer "In2.Cu")
		(net 21)
	)
	(segment
		(start 156.382887 85.783679)
		(end 156.382887 85.812029)
		(width 0.1016)
		(layer "In2.Cu")
		(net 21)
	)
	(segment
		(start 155.420283 84.849424)
		(end 155.448632 84.849424)
		(width 0.1016)
		(layer "In2.Cu")
		(net 21)
	)
	(segment
		(start 155.4075 84.571539)
		(end 155.344938 84.6341)
		(width 0.1016)
		(layer "In2.Cu")
		(net 21)
	)
	(segment
		(start 155.501812 84.830815)
		(end 155.523977 84.81314)
		(width 0.1016)
		(layer "In2.Cu")
		(net 21)
	)
	(segment
		(start 156.101491 85.09098)
		(end 156.123656 85.108656)
		(width 0.1016)
		(layer "In2.Cu")
		(net 21)
	)
	(segment
		(start 156.481734 85.466734)
		(end 156.499409 85.488898)
		(width 0.1016)
		(layer "In2.Cu")
		(net 21)
	)
	(segment
		(start 155.703016 84.992178)
		(end 155.68534 85.014343)
		(width 0.1016)
		(layer "In2.Cu")
		(net 21)
	)
	(segment
		(start 156.043418 85.507131)
		(end 156.061094 85.529296)
		(width 0.1016)
		(layer "In2.Cu")
		(net 21)
	)
	(segment
		(start 156.499409 85.488898)
		(end 156.511709 85.51444)
		(width 0.1016)
		(layer "In2.Cu")
		(net 21)
	)
	(segment
		(start 155.392644 84.843115)
		(end 155.420283 84.849424)
		(width 0.1016)
		(layer "In2.Cu")
		(net 21)
	)
	(segment
		(start 156.217968 85.546971)
		(end 156.240133 85.529296)
		(width 0.1016)
		(layer "In2.Cu")
		(net 21)
	)
	(segment
		(start 155.608703 84.732902)
		(end 155.634245 84.720602)
		(width 0.1016)
		(layer "In2.Cu")
		(net 21)
	)
	(segment
		(start 155.443784 84.467845)
		(end 155.443784 84.496194)
		(width 0.1016)
		(layer "In2.Cu")
		(net 21)
	)
	(segment
		(start 156.441336 85.905049)
		(end 156.466878 85.917349)
		(width 0.1016)
		(layer "In2.Cu")
		(net 21)
	)
	(segment
		(start 155.690233 84.714293)
		(end 155.717872 84.720602)
		(width 0.1016)
		(layer "In2.Cu")
		(net 21)
	)
	(segment
		(start 155.944616 85.108656)
		(end 155.966781 85.09098)
		(width 0.1016)
		(layer "In2.Cu")
		(net 21)
	)
	(segment
		(start 155.448632 84.849424)
		(end 155.476271 84.843115)
		(width 0.1016)
		(layer "In2.Cu")
		(net 21)
	)
	(segment
		(start 155.4075 84.3925)
		(end 155.425175 84.414664)
		(width 0.1016)
		(layer "In2.Cu")
		(net 21)
	)
	(segment
		(start 156.511709 85.598067)
		(end 156.499409 85.623608)
		(width 0.1016)
		(layer "In2.Cu")
		(net 21)
	)
	(segment
		(start 156.123656 85.287695)
		(end 156.061094 85.350256)
		(width 0.1016)
		(layer "In2.Cu")
		(net 21)
	)
	(segment
		(start 156.061094 85.350256)
		(end 156.043418 85.372421)
		(width 0.1016)
		(layer "In2.Cu")
		(net 21)
	)
	(segment
		(start 156.153631 85.156362)
		(end 156.15994 85.184001)
		(width 0.1016)
		(layer "In2.Cu")
		(net 21)
	)
	(segment
		(start 155.85989 85.188893)
		(end 155.882055 85.171218)
		(width 0.1016)
		(layer "In2.Cu")
		(net 21)
	)
	(segment
		(start 156.15994 85.184001)
		(end 156.15994 85.21235)
		(width 0.1016)
		(layer "In2.Cu")
		(net 21)
	)
	(segment
		(start 155.80671 85.207502)
		(end 155.834349 85.201193)
		(width 0.1016)
		(layer "In2.Cu")
		(net 21)
	)
	(segment
		(start 156.024809 85.425601)
		(end 156.024809 85.453951)
		(width 0.1016)
		(layer "In2.Cu")
		(net 21)
	)
	(segment
		(start 156.382887 85.812029)
		(end 156.389196 85.839668)
		(width 0.1016)
		(layer "In2.Cu")
		(net 21)
	)
	(segment
		(start 156.401496 85.730499)
		(end 156.389196 85.756041)
		(width 0.1016)
		(layer "In2.Cu")
		(net 21)
	)
	(segment
		(start 156.389196 85.839668)
		(end 156.401496 85.865209)
		(width 0.1016)
		(layer "In2.Cu")
		(net 21)
	)
	(segment
		(start 156.061094 85.529296)
		(end 156.083258 85.546971)
		(width 0.1016)
		(layer "In2.Cu")
		(net 21)
	)
	(segment
		(start 156.494517 85.923658)
		(end 156.522866 85.923658)
		(width 0.1016)
		(layer "In2.Cu")
		(net 21)
	)
	(segment
		(start 156.350401 85.436758)
		(end 156.378039 85.430449)
		(width 0.1016)
		(layer "In2.Cu")
		(net 21)
	)
	(segment
		(start 156.419172 85.708334)
		(end 156.401496 85.730499)
		(width 0.1016)
		(layer "In2.Cu")
		(net 21)
	)
	(segment
		(start 156.518018 85.570428)
		(end 156.511709 85.598067)
		(width 0.1016)
		(layer "In2.Cu")
		(net 21)
	)
	(segment
		(start 156.141331 85.13082)
		(end 156.153631 85.156362)
		(width 0.1016)
		(layer "In2.Cu")
		(net 21)
	)
	(segment
		(start 156.043418 85.372421)
		(end 156.031118 85.397963)
		(width 0.1016)
		(layer "In2.Cu")
		(net 21)
	)
	(segment
		(start 155.992323 85.07868)
		(end 156.019961 85.072371)
		(width 0.1016)
		(layer "In2.Cu")
		(net 21)
	)
	(segment
		(start 156.764467 85.788527)
		(end 156.792106 85.794836)
		(width 0.1016)
		(layer "In2.Cu")
		(net 21)
	)
	(segment
		(start 155.717872 84.720602)
		(end 155.743413 84.732902)
		(width 0.1016)
		(layer "In2.Cu")
		(net 21)
	)
	(segment
		(start 155.765578 84.929617)
		(end 155.703016 84.992178)
		(width 0.1016)
		(layer "In2.Cu")
		(net 21)
	)
	(segment
		(start 156.401496 85.865209)
		(end 156.419172 85.887374)
		(width 0.1016)
		(layer "In2.Cu")
		(net 21)
	)
	(segment
		(start 156.136439 85.56558)
		(end 156.164788 85.56558)
		(width 0.1016)
		(layer "In2.Cu")
		(net 21)
	)
	(segment
		(start 156.550505 85.917349)
		(end 156.576046 85.905049)
		(width 0.1016)
		(layer "In2.Cu")
		(net 21)
	)
	(segment
		(start 155.367102 84.830815)
		(end 155.392644 84.843115)
		(width 0.1016)
		(layer "In2.Cu")
		(net 21)
	)
	(segment
		(start 156.378039 85.430449)
		(end 156.406389 85.430449)
		(width 0.1016)
		(layer "In2.Cu")
		(net 21)
	)
	(segment
		(start 156.024809 85.453951)
		(end 156.031118 85.48159)
		(width 0.1016)
		(layer "In2.Cu")
		(net 21)
	)
	(segment
		(start 156.817647 85.807136)
		(end 156.839812 85.824812)
		(width 0.1016)
		(layer "In2.Cu")
		(net 21)
	)
	(segment
		(start 155.882055 85.171218)
		(end 155.944616 85.108656)
		(width 0.1016)
		(layer "In2.Cu")
		(net 21)
	)
	(segment
		(start 155.308653 84.709445)
		(end 155.308653 84.737795)
		(width 0.1016)
		(layer "In2.Cu")
		(net 21)
	)
	(segment
		(start 156.481734 85.645773)
		(end 156.419172 85.708334)
		(width 0.1016)
		(layer "In2.Cu")
		(net 21)
	)
	(segment
		(start 156.1088 85.559271)
		(end 156.136439 85.56558)
		(width 0.1016)
		(layer "In2.Cu")
		(net 21)
	)
	(segment
		(start 156.15994 85.21235)
		(end 156.153631 85.239989)
		(width 0.1016)
		(layer "In2.Cu")
		(net 21)
	)
	(segment
		(start 156.518018 85.542079)
		(end 156.518018 85.570428)
		(width 0.1016)
		(layer "In2.Cu")
		(net 21)
	)
	(segment
		(start 156.389196 85.756041)
		(end 156.382887 85.783679)
		(width 0.1016)
		(layer "In2.Cu")
		(net 21)
	)
	(segment
		(start 155.666731 85.067523)
		(end 155.666731 85.095873)
		(width 0.1016)
		(layer "In2.Cu")
		(net 21)
	)
	(segment
		(start 155.314962 84.681807)
		(end 155.308653 84.709445)
		(width 0.1016)
		(layer "In2.Cu")
		(net 21)
	)
	(segment
		(start 156.419172 85.887374)
		(end 156.441336 85.905049)
		(width 0.1016)
		(layer "In2.Cu")
		(net 21)
	)
	(segment
		(start 156.682937 85.807136)
		(end 156.708479 85.794836)
		(width 0.1016)
		(layer "In2.Cu")
		(net 21)
	)
	(segment
		(start 155.765578 84.750578)
		(end 155.783253 84.772742)
		(width 0.1016)
		(layer "In2.Cu")
		(net 21)
	)
	(segment
		(start 155.834349 85.201193)
		(end 155.85989 85.188893)
		(width 0.1016)
		(layer "In2.Cu")
		(net 21)
	)
	(segment
		(start 155.327262 84.790975)
		(end 155.344938 84.81314)
		(width 0.1016)
		(layer "In2.Cu")
		(net 21)
	)
	(segment
		(start 156.031118 85.48159)
		(end 156.043418 85.507131)
		(width 0.1016)
		(layer "In2.Cu")
		(net 21)
	)
	(segment
		(start 156.434028 85.436758)
		(end 156.459569 85.449058)
		(width 0.1016)
		(layer "In2.Cu")
		(net 21)
	)
	(segment
		(start 155.225 84.21)
		(end 155.4075 84.3925)
		(width 0.1016)
		(layer "In2.Cu")
		(net 21)
	)
	(segment
		(start 155.703016 85.171218)
		(end 155.72518 85.188893)
		(width 0.1016)
		(layer "In2.Cu")
		(net 21)
	)
	(segment
		(start 156.153631 85.239989)
		(end 156.141331 85.26553)
		(width 0.1016)
		(layer "In2.Cu")
		(net 21)
	)
	(segment
		(start 156.07595 85.07868)
		(end 156.101491 85.09098)
		(width 0.1016)
		(layer "In2.Cu")
		(net 21)
	)
	(segment
		(start 155.308653 84.737795)
		(end 155.314962 84.765434)
		(width 0.1016)
		(layer "In2.Cu")
		(net 21)
	)
	(segment
		(start 155.67304 85.039885)
		(end 155.666731 85.067523)
		(width 0.1016)
		(layer "In2.Cu")
		(net 21)
	)
	(segment
		(start 155.5 91.5)
		(end 155.5 92.7)
		(width 0.1016)
		(layer "In2.Cu")
		(net 21)
	)
	(segment
		(start 149.625 86.85)
		(end 149.625 86.29)
		(width 0.145)
		(layer "F.Cu")
		(net 22)
	)
	(segment
		(start 152.425 98.7)
		(end 152.425 96.025)
		(width 0.145)
		(layer "F.Cu")
		(net 22)
	)
	(segment
		(start 148.275 93)
		(end 147.975 92.7)
		(width 0.145)
		(layer "F.Cu")
		(net 22)
	)
	(segment
		(start 149.4 93)
		(end 148.275 93)
		(width 0.145)
		(layer "F.Cu")
		(net 22)
	)
	(segment
		(start 152.425 96.025)
		(end 149.4 93)
		(width 0.145)
		(layer "F.Cu")
		(net 22)
	)
	(via
		(at 149.625 86.29)
		(size 0.45)
		(drill 0.15)
		(layers "F.Cu" "B.Cu")
		(net 22)
	)
	(via
		(at 147.975 92.7)
		(size 0.45)
		(drill 0.15)
		(layers "F.Cu" "B.Cu")
		(net 22)
	)
	(segment
		(start 150.275636 90.5266)
		(end 149.7266 90.5266)
		(width 0.1016)
		(layer "In2.Cu")
		(net 22)
	)
	(segment
		(start 150.338983 91.520434)
		(end 150.355071 91.504346)
		(width 0.1016)
		(layer "In2.Cu")
		(net 22)
	)
	(segment
		(start 149.627548 90.447608)
		(end 149.625 90.425)
		(width 0.1016)
		(layer "In2.Cu")
		(net 22)
	)
	(segment
		(start 149.703992 91.336852)
		(end 149.682518 91.329338)
		(width 0.1016)
		(layer "In2.Cu")
		(net 22)
	)
	(segment
		(start 150.298245 90.727252)
		(end 150.319719 90.719738)
		(width 0.1016)
		(layer "In2.Cu")
		(net 22)
	)
	(segment
		(start 149.7266 90.5266)
		(end 149.703992 90.524052)
		(width 0.1016)
		(layer "In2.Cu")
		(net 22)
	)
	(segment
		(start 150.318523 89.357725)
		(end 150.290082 89.339854)
		(width 0.1016)
		(layer "In2.Cu")
		(net 22)
	)
	(segment
		(start 150.275636 90.7298)
		(end 150.298245 90.727252)
		(width 0.1016)
		(layer "In2.Cu")
		(net 22)
	)
	(segment
		(start 150.318523 89.592274)
		(end 150.342274 89.568523)
		(width 0.1016)
		(layer "In2.Cu")
		(net 22)
	)
	(segment
		(start 150.355071 91.377653)
		(end 150.338983 91.361565)
		(width 0.1016)
		(layer "In2.Cu")
		(net 22)
	)
	(segment
		(start 150.377236 91.0346)
		(end 150.374689 91.011991)
		(width 0.1016)
		(layer "In2.Cu")
		(net 22)
	)
	(segment
		(start 150.355071 91.504346)
		(end 150.367175 91.485082)
		(width 0.1016)
		(layer "In2.Cu")
		(net 22)
	)
	(segment
		(start 149.639854 89.240082)
		(end 149.62876 89.208378)
		(width 0.1016)
		(layer "In2.Cu")
		(net 22)
	)
	(segment
		(start 149.62876 89.741621)
		(end 149.639854 89.709917)
		(width 0.1016)
		(layer "In2.Cu")
		(net 22)
	)
	(segment
		(start 149.7266 91.3394)
		(end 149.703992 91.336852)
		(width 0.1016)
		(layer "In2.Cu")
		(net 22)
	)
	(segment
		(start 149.657725 89.268523)
		(end 149.639854 89.240082)
		(width 0.1016)
		(layer "In2.Cu")
		(net 22)
	)
	(segment
		(start 150.360145 89.540082)
		(end 150.371239 89.508378)
		(width 0.1016)
		(layer "In2.Cu")
		(net 22)
	)
	(segment
		(start 150.367175 90.584117)
		(end 150.355071 90.564853)
		(width 0.1016)
		(layer "In2.Cu")
		(net 22)
	)
	(segment
		(start 150.371239 89.441621)
		(end 150.360145 89.409917)
		(width 0.1016)
		(layer "In2.Cu")
		(net 22)
	)
	(segment
		(start 150.298245 90.529147)
		(end 150.275636 90.5266)
		(width 0.1016)
		(layer "In2.Cu")
		(net 22)
	)
	(segment
		(start 150.290082 89.610145)
		(end 150.318523 89.592274)
		(width 0.1016)
		(layer "In2.Cu")
		(net 22)
	)
	(segment
		(start 150.258378 89.621239)
		(end 150.290082 89.610145)
		(width 0.1016)
		(layer "In2.Cu")
		(net 22)
	)
	(segment
		(start 149.635062 91.281882)
		(end 149.627548 91.260408)
		(width 0.1016)
		(layer "In2.Cu")
		(net 22)
	)
	(segment
		(start 149.663254 90.751965)
		(end 149.682518 90.739861)
		(width 0.1016)
		(layer "In2.Cu")
		(net 22)
	)
	(segment
		(start 149.703992 91.545147)
		(end 149.7266 91.5426)
		(width 0.1016)
		(layer "In2.Cu")
		(net 22)
	)
	(segment
		(start 149.703992 91.138747)
		(end 149.7266 91.1362)
		(width 0.1016)
		(layer "In2.Cu")
		(net 22)
	)
	(segment
		(start 150.374689 90.650808)
		(end 150.377236 90.6282)
		(width 0.1016)
		(layer "In2.Cu")
		(net 22)
	)
	(segment
		(start 150.377236 90.6282)
		(end 150.374689 90.605591)
		(width 0.1016)
		(layer "In2.Cu")
		(net 22)
	)
	(segment
		(start 150.338983 91.361565)
		(end 150.319719 91.349461)
		(width 0.1016)
		(layer "In2.Cu")
		(net 22)
	)
	(segment
		(start 149.627548 90.808791)
		(end 149.635062 90.787317)
		(width 0.1016)
		(layer "In2.Cu")
		(net 22)
	)
	(segment
		(start 150.275636 90.933)
		(end 149.7266 90.933)
		(width 0.1016)
		(layer "In2.Cu")
		(net 22)
	)
	(segment
		(start 149.663254 91.317234)
		(end 149.647166 91.301146)
		(width 0.1016)
		(layer "In2.Cu")
		(net 22)
	)
	(segment
		(start 149.681476 89.657725)
		(end 149.709917 89.639854)
		(width 0.1016)
		(layer "In2.Cu")
		(net 22)
	)
	(segment
		(start 150.342274 89.381476)
		(end 150.318523 89.357725)
		(width 0.1016)
		(layer "In2.Cu")
		(net 22)
	)
	(segment
		(start 149.703992 90.732347)
		(end 149.7266 90.7298)
		(width 0.1016)
		(layer "In2.Cu")
		(net 22)
	)
	(segment
		(start 149.635062 91.193717)
		(end 149.647166 91.174453)
		(width 0.1016)
		(layer "In2.Cu")
		(net 22)
	)
	(segment
		(start 149.625 90.8314)
		(end 149.627548 90.808791)
		(width 0.1016)
		(layer "In2.Cu")
		(net 22)
	)
	(segment
		(start 149.709917 89.310145)
		(end 149.681476 89.292274)
		(width 0.1016)
		(layer "In2.Cu")
		(net 22)
	)
	(segment
		(start 149.682518 90.739861)
		(end 149.703992 90.732347)
		(width 0.1016)
		(layer "In2.Cu")
		(net 22)
	)
	(segment
		(start 150.374689 91.057208)
		(end 150.377236 91.0346)
		(width 0.1016)
		(layer "In2.Cu")
		(net 22)
	)
	(segment
		(start 149.647166 91.174453)
		(end 149.663254 91.158365)
		(width 0.1016)
		(layer "In2.Cu")
		(net 22)
	)
	(segment
		(start 150.319719 91.349461)
		(end 150.298245 91.341947)
		(width 0.1016)
		(layer "In2.Cu")
		(net 22)
	)
	(segment
		(start 150.319719 90.536661)
		(end 150.298245 90.529147)
		(width 0.1016)
		(layer "In2.Cu")
		(net 22)
	)
	(segment
		(start 149.647166 90.488346)
		(end 149.635062 90.469082)
		(width 0.1016)
		(layer "In2.Cu")
		(net 22)
	)
	(segment
		(start 149.709917 89.639854)
		(end 149.741621 89.62876)
		(width 0.1016)
		(layer "In2.Cu")
		(net 22)
	)
	(segment
		(start 149.681476 89.292274)
		(end 149.657725 89.268523)
		(width 0.1016)
		(layer "In2.Cu")
		(net 22)
	)
	(segment
		(start 149.682518 91.146261)
		(end 149.703992 91.138747)
		(width 0.1016)
		(layer "In2.Cu")
		(net 22)
	)
	(segment
		(start 149.7266 90.933)
		(end 149.703992 90.930452)
		(width 0.1016)
		(layer "In2.Cu")
		(net 22)
	)
	(segment
		(start 149.741621 89.321239)
		(end 149.709917 89.310145)
		(width 0.1016)
		(layer "In2.Cu")
		(net 22)
	)
	(segment
		(start 150.355071 90.971253)
		(end 150.338983 90.955165)
		(width 0.1016)
		(layer "In2.Cu")
		(net 22)
	)
	(segment
		(start 150.367175 91.396917)
		(end 150.355071 91.377653)
		(width 0.1016)
		(layer "In2.Cu")
		(net 22)
	)
	(segment
		(start 150.355071 91.097946)
		(end 150.367175 91.078682)
		(width 0.1016)
		(layer "In2.Cu")
		(net 22)
	)
	(segment
		(start 150.367175 90.990517)
		(end 150.355071 90.971253)
		(width 0.1016)
		(layer "In2.Cu")
		(net 22)
	)
	(segment
		(start 150.275636 91.5426)
		(end 150.298245 91.540052)
		(width 0.1016)
		(layer "In2.Cu")
		(net 22)
	)
	(segment
		(start 150.319719 91.126138)
		(end 150.338983 91.114034)
		(width 0.1016)
		(layer "In2.Cu")
		(net 22)
	)
	(segment
		(start 149.657725 89.681476)
		(end 149.681476 89.657725)
		(width 0.1016)
		(layer "In2.Cu")
		(net 22)
	)
	(segment
		(start 149.7266 91.5426)
		(end 150.275636 91.5426)
		(width 0.1016)
		(layer "In2.Cu")
		(net 22)
	)
	(segment
		(start 150.338983 90.955165)
		(end 150.319719 90.943061)
		(width 0.1016)
		(layer "In2.Cu")
		(net 22)
	)
	(segment
		(start 149.625 91.2378)
		(end 149.627548 91.215191)
		(width 0.1016)
		(layer "In2.Cu")
		(net 22)
	)
	(segment
		(start 150.374689 91.011991)
		(end 150.367175 90.990517)
		(width 0.1016)
		(layer "In2.Cu")
		(net 22)
	)
	(segment
		(start 149.682518 90.516538)
		(end 149.663254 90.504434)
		(width 0.1016)
		(layer "In2.Cu")
		(net 22)
	)
	(segment
		(start 149.7266 91.1362)
		(end 150.275636 91.1362)
		(width 0.1016)
		(layer "In2.Cu")
		(net 22)
	)
	(segment
		(start 150.290082 89.339854)
		(end 150.258378 89.32876)
		(width 0.1016)
		(layer "In2.Cu")
		(net 22)
	)
	(segment
		(start 149.741621 89.62876)
		(end 149.775 89.625)
		(width 0.1016)
		(layer "In2.Cu")
		(net 22)
	)
	(segment
		(start 149.775 89.625)
		(end 150.225 89.625)
		(width 0.1016)
		(layer "In2.Cu")
		(net 22)
	)
	(segment
		(start 149.625 92.125)
		(end 149.625 91.6442)
		(width 0.1016)
		(layer "In2.Cu")
		(net 22)
	)
	(segment
		(start 150.374689 90.605591)
		(end 150.367175 90.584117)
		(width 0.1016)
		(layer "In2.Cu")
		(net 22)
	)
	(segment
		(start 149.703992 90.930452)
		(end 149.682518 90.922938)
		(width 0.1016)
		(layer "In2.Cu")
		(net 22)
	)
	(segment
		(start 149.663254 90.504434)
		(end 149.647166 90.488346)
		(width 0.1016)
		(layer "In2.Cu")
		(net 22)
	)
	(segment
		(start 150.298245 90.935547)
		(end 150.275636 90.933)
		(width 0.1016)
		(layer "In2.Cu")
		(net 22)
	)
	(segment
		(start 149.682518 91.329338)
		(end 149.663254 91.317234)
		(width 0.1016)
		(layer "In2.Cu")
		(net 22)
	)
	(segment
		(start 149.627548 91.621591)
		(end 149.635062 91.600117)
		(width 0.1016)
		(layer "In2.Cu")
		(net 22)
	)
	(segment
		(start 149.682518 90.922938)
		(end 149.663254 90.910834)
		(width 0.1016)
		(layer "In2.Cu")
		(net 22)
	)
	(segment
		(start 150.338983 90.707634)
		(end 150.355071 90.691546)
		(width 0.1016)
		(layer "In2.Cu")
		(net 22)
	)
	(segment
		(start 149.635062 90.875482)
		(end 149.627548 90.854008)
		(width 0.1016)
		(layer "In2.Cu")
		(net 22)
	)
	(segment
		(start 149.635062 90.469082)
		(end 149.627548 90.447608)
		(width 0.1016)
		(layer "In2.Cu")
		(net 22)
	)
	(segment
		(start 150.298245 91.540052)
		(end 150.319719 91.532538)
		(width 0.1016)
		(layer "In2.Cu")
		(net 22)
	)
	(segment
		(start 149.663254 91.564765)
		(end 149.682518 91.552661)
		(width 0.1016)
		(layer "In2.Cu")
		(net 22)
	)
	(segment
		(start 150.375 89.475)
		(end 150.371239 89.441621)
		(width 0.1016)
		(layer "In2.Cu")
		(net 22)
	)
	(segment
		(start 150.374689 91.418391)
		(end 150.367175 91.396917)
		(width 0.1016)
		(layer "In2.Cu")
		(net 22)
	)
	(segment
		(start 147.975 92.7)
		(end 149.05 92.7)
		(width 0.1016)
		(layer "In2.Cu")
		(net 22)
	)
	(segment
		(start 150.258378 89.32876)
		(end 150.225 89.325)
		(width 0.1016)
		(layer "In2.Cu")
		(net 22)
	)
	(segment
		(start 149.62876 89.208378)
		(end 149.625 89.175)
		(width 0.1016)
		(layer "In2.Cu")
		(net 22)
	)
	(segment
		(start 150.338983 91.114034)
		(end 150.355071 91.097946)
		(width 0.1016)
		(layer "In2.Cu")
		(net 22)
	)
	(segment
		(start 150.367175 90.672282)
		(end 150.374689 90.650808)
		(width 0.1016)
		(layer "In2.Cu")
		(net 22)
	)
	(segment
		(start 149.682518 91.552661)
		(end 149.703992 91.545147)
		(width 0.1016)
		(layer "In2.Cu")
		(net 22)
	)
	(segment
		(start 149.625 89.775)
		(end 149.62876 89.741621)
		(width 0.1016)
		(layer "In2.Cu")
		(net 22)
	)
	(segment
		(start 150.275636 91.1362)
		(end 150.298245 91.133652)
		(width 0.1016)
		(layer "In2.Cu")
		(net 22)
	)
	(segment
		(start 150.225 89.325)
		(end 149.775 89.325)
		(width 0.1016)
		(layer "In2.Cu")
		(net 22)
	)
	(segment
		(start 150.374689 91.463608)
		(end 150.377236 91.441)
		(width 0.1016)
		(layer "In2.Cu")
		(net 22)
	)
	(segment
		(start 149.647166 90.768053)
		(end 149.663254 90.751965)
		(width 0.1016)
		(layer "In2.Cu")
		(net 22)
	)
	(segment
		(start 150.275636 91.3394)
		(end 149.7266 91.3394)
		(width 0.1016)
		(layer "In2.Cu")
		(net 22)
	)
	(segment
		(start 150.371239 89.508378)
		(end 150.375 89.475)
		(width 0.1016)
		(layer "In2.Cu")
		(net 22)
	)
	(segment
		(start 150.367175 91.078682)
		(end 150.374689 91.057208)
		(width 0.1016)
		(layer "In2.Cu")
		(net 22)
	)
	(segment
		(start 149.703992 90.524052)
		(end 149.682518 90.516538)
		(width 0.1016)
		(layer "In2.Cu")
		(net 22)
	)
	(segment
		(start 149.663254 91.158365)
		(end 149.682518 91.146261)
		(width 0.1016)
		(layer "In2.Cu")
		(net 22)
	)
	(segment
		(start 149.627548 90.854008)
		(end 149.625 90.8314)
		(width 0.1016)
		(layer "In2.Cu")
		(net 22)
	)
	(segment
		(start 150.319719 91.532538)
		(end 150.338983 91.520434)
		(width 0.1016)
		(layer "In2.Cu")
		(net 22)
	)
	(segment
		(start 149.647166 90.894746)
		(end 149.635062 90.875482)
		(width 0.1016)
		(layer "In2.Cu")
		(net 22)
	)
	(segment
		(start 150.225 89.625)
		(end 150.258378 89.621239)
		(width 0.1016)
		(layer "In2.Cu")
		(net 22)
	)
	(segment
		(start 150.355071 90.564853)
		(end 150.338983 90.548765)
		(width 0.1016)
		(layer "In2.Cu")
		(net 22)
	)
	(segment
		(start 150.355071 90.691546)
		(end 150.367175 90.672282)
		(width 0.1016)
		(layer "In2.Cu")
		(net 22)
	)
	(segment
		(start 149.647166 91.301146)
		(end 149.635062 91.281882)
		(width 0.1016)
		(layer "In2.Cu")
		(net 22)
	)
	(segment
		(start 149.625 90.425)
		(end 149.625 89.775)
		(width 0.1016)
		(layer "In2.Cu")
		(net 22)
	)
	(segment
		(start 150.338983 90.548765)
		(end 150.319719 90.536661)
		(width 0.1016)
		(layer "In2.Cu")
		(net 22)
	)
	(segment
		(start 149.627548 91.215191)
		(end 149.635062 91.193717)
		(width 0.1016)
		(layer "In2.Cu")
		(net 22)
	)
	(segment
		(start 150.342274 89.568523)
		(end 150.360145 89.540082)
		(width 0.1016)
		(layer "In2.Cu")
		(net 22)
	)
	(segment
		(start 149.625 91.6442)
		(end 149.627548 91.621591)
		(width 0.1016)
		(layer "In2.Cu")
		(net 22)
	)
	(segment
		(start 149.05 92.7)
		(end 149.625 92.125)
		(width 0.1016)
		(layer "In2.Cu")
		(net 22)
	)
	(segment
		(start 149.639854 89.709917)
		(end 149.657725 89.681476)
		(width 0.1016)
		(layer "In2.Cu")
		(net 22)
	)
	(segment
		(start 150.319719 90.943061)
		(end 150.298245 90.935547)
		(width 0.1016)
		(layer "In2.Cu")
		(net 22)
	)
	(segment
		(start 150.298245 91.341947)
		(end 150.275636 91.3394)
		(width 0.1016)
		(layer "In2.Cu")
		(net 22)
	)
	(segment
		(start 149.775 89.325)
		(end 149.741621 89.321239)
		(width 0.1016)
		(layer "In2.Cu")
		(net 22)
	)
	(segment
		(start 149.7266 90.7298)
		(end 150.275636 90.7298)
		(width 0.1016)
		(layer "In2.Cu")
		(net 22)
	)
	(segment
		(start 150.298245 91.133652)
		(end 150.319719 91.126138)
		(width 0.1016)
		(layer "In2.Cu")
		(net 22)
	)
	(segment
		(start 150.367175 91.485082)
		(end 150.374689 91.463608)
		(width 0.1016)
		(layer "In2.Cu")
		(net 22)
	)
	(segment
		(start 149.627548 91.260408)
		(end 149.625 91.2378)
		(width 0.1016)
		(layer "In2.Cu")
		(net 22)
	)
	(segment
		(start 149.635062 90.787317)
		(end 149.647166 90.768053)
		(width 0.1016)
		(layer "In2.Cu")
		(net 22)
	)
	(segment
		(start 150.360145 89.409917)
		(end 150.342274 89.381476)
		(width 0.1016)
		(layer "In2.Cu")
		(net 22)
	)
	(segment
		(start 150.319719 90.719738)
		(end 150.338983 90.707634)
		(width 0.1016)
		(layer "In2.Cu")
		(net 22)
	)
	(segment
		(start 150.377236 91.441)
		(end 150.374689 91.418391)
		(width 0.1016)
		(layer "In2.Cu")
		(net 22)
	)
	(segment
		(start 149.635062 91.600117)
		(end 149.647166 91.580853)
		(width 0.1016)
		(layer "In2.Cu")
		(net 22)
	)
	(segment
		(start 149.663254 90.910834)
		(end 149.647166 90.894746)
		(width 0.1016)
		(layer "In2.Cu")
		(net 22)
	)
	(segment
		(start 149.625 89.175)
		(end 149.625 86.29)
		(width 0.1016)
		(layer "In2.Cu")
		(net 22)
	)
	(segment
		(start 149.647166 91.580853)
		(end 149.663254 91.564765)
		(width 0.1016)
		(layer "In2.Cu")
		(net 22)
	)
	(segment
		(start 154.425 87.65)
		(end 154.825 87.25)
		(width 0.145)
		(layer "F.Cu")
		(net 23)
	)
	(via
		(at 154.825 87.25)
		(size 0.45)
		(drill 0.15)
		(layers "F.Cu" "B.Cu")
		(net 23)
	)
	(via
		(at 153.7 92.3)
		(size 0.45)
		(drill 0.15)
		(layers "F.Cu" "B.Cu")
		(net 23)
	)
	(segment
		(start 152.2 94.2)
		(end 151.175 95.225)
		(width 0.145)
		(layer "B.Cu")
		(net 23)
	)
	(segment
		(start 153.7 92.3)
		(end 153.7 93.9)
		(width 0.145)
		(layer "B.Cu")
		(net 23)
	)
	(segment
		(start 151.175 95.925)
		(end 151.175 98.7)
		(width 0.145)
		(layer "B.Cu")
		(net 23)
	)
	(segment
		(start 151.175 95.225)
		(end 151.175 95.925)
		(width 0.145)
		(layer "B.Cu")
		(net 23)
	)
	(segment
		(start 153.4 94.2)
		(end 152.2 94.2)
		(width 0.145)
		(layer "B.Cu")
		(net 23)
	)
	(segment
		(start 153.7 93.9)
		(end 153.4 94.2)
		(width 0.145)
		(layer "B.Cu")
		(net 23)
	)
	(segment
		(start 154.425 87.9026)
		(end 154.427548 87.879991)
		(width 0.1016)
		(layer "In2.Cu")
		(net 23)
	)
	(segment
		(start 154.5266 87.801)
		(end 154.7234 87.801)
		(width 0.1016)
		(layer "In2.Cu")
		(net 23)
	)
	(segment
		(start 153.638253 91.266634)
		(end 153.622165 91.250546)
		(width 0.1016)
		(layer "In2.Cu")
		(net 23)
	)
	(segment
		(start 154.463254 87.982034)
		(end 154.447166 87.965946)
		(width 0.1016)
		(layer "In2.Cu")
		(net 23)
	)
	(segment
		(start 154.5266 88.6138)
		(end 154.7234 88.6138)
		(width 0.1016)
		(layer "In2.Cu")
		(net 23)
	)
	(segment
		(start 154.482518 88.217461)
		(end 154.503992 88.209947)
		(width 0.1016)
		(layer "In2.Cu")
		(net 23)
	)
	(segment
		(start 154.560146 90.477835)
		(end 154.576234 90.461747)
		(width 0.1016)
		(layer "In2.Cu")
		(net 23)
	)
	(segment
		(start 153.7 92.3)
		(end 153.6 92.2)
		(width 0.1016)
		(layer "In2.Cu")
		(net 23)
	)
	(segment
		(start 154.767483 88.827061)
		(end 154.746009 88.819547)
		(width 0.1016)
		(layer "In2.Cu")
		(net 23)
	)
	(segment
		(start 154.249517 90.010062)
		(end 154.270991 90.002548)
		(width 0.1016)
		(layer "In2.Cu")
		(net 23)
	)
	(segment
		(start 154.825 88.5122)
		(end 154.822453 88.489591)
		(width 0.1016)
		(layer "In2.Cu")
		(net 23)
	)
	(segment
		(start 153.678991 91.900947)
		(end 153.7016 91.8984)
		(width 0.1016)
		(layer "In2.Cu")
		(net 23)
	)
	(segment
		(start 154.802835 88.575546)
		(end 154.814939 88.556282)
		(width 0.1016)
		(layer "In2.Cu")
		(net 23)
	)
	(segment
		(start 153.622165 91.123853)
		(end 153.638253 91.107765)
		(width 0.1016)
		(layer "In2.Cu")
		(net 23)
	)
	(segment
		(start 154.3952 90.3984)
		(end 154.397747 90.421009)
		(width 0.1016)
		(layer "In2.Cu")
		(net 23)
	)
	(segment
		(start 154.447166 88.245653)
		(end 154.463254 88.229565)
		(width 0.1016)
		(layer "In2.Cu")
		(net 23)
	)
	(segment
		(start 154.822453 87.722008)
		(end 154.825 87.6994)
		(width 0.1016)
		(layer "In2.Cu")
		(net 23)
	)
	(segment
		(start 153.924238 91.3904)
		(end 153.92169 91.367791)
		(width 0.1016)
		(layer "In2.Cu")
		(net 23)
	)
	(segment
		(start 154.435062 87.946682)
		(end 154.427548 87.925208)
		(width 0.1016)
		(layer "In2.Cu")
		(net 23)
	)
	(segment
		(start 153.931282 90.010062)
		(end 153.950546 90.022166)
		(width 0.1016)
		(layer "In2.Cu")
		(net 23)
	)
	(segment
		(start 154.746009 88.611252)
		(end 154.767483 88.603738)
		(width 0.1016)
		(layer "In2.Cu")
		(net 23)
	)
	(segment
		(start 154.786747 87.778834)
		(end 154.802835 87.762746)
		(width 0.1016)
		(layer "In2.Cu")
		(net 23)
	)
	(segment
		(start 154.392652 90.078992)
		(end 154.3952 90.1016)
		(width 0.1016)
		(layer "In2.Cu")
		(net 23)
	)
	(segment
		(start 154.192 90.1016)
		(end 154.194547 90.078992)
		(width 0.1016)
		(layer "In2.Cu")
		(net 23)
	)
	(segment
		(start 154.214165 90.038254)
		(end 154.230253 90.022166)
		(width 0.1016)
		(layer "In2.Cu")
		(net 23)
	)
	(segment
		(start 154.767483 89.010138)
		(end 154.786747 88.998034)
		(width 0.1016)
		(layer "In2.Cu")
		(net 23)
	)
	(segment
		(start 154.027053 90.477835)
		(end 154.046317 90.489939)
		(width 0.1016)
		(layer "In2.Cu")
		(net 23)
	)
	(segment
		(start 154.503992 89.220852)
		(end 154.482518 89.213338)
		(width 0.1016)
		(layer "In2.Cu")
		(net 23)
	)
	(segment
		(start 153.845246 91.083052)
		(end 153.86672 91.075538)
		(width 0.1016)
		(layer "In2.Cu")
		(net 23)
	)
	(segment
		(start 153.885984 91.063434)
		(end 153.902072 91.047346)
		(width 0.1016)
		(layer "In2.Cu")
		(net 23)
	)
	(segment
		(start 154.427548 87.879991)
		(end 154.435062 87.858517)
		(width 0.1016)
		(layer "In2.Cu")
		(net 23)
	)
	(segment
		(start 154.435062 88.264917)
		(end 154.447166 88.245653)
		(width 0.1016)
		(layer "In2.Cu")
		(net 23)
	)
	(segment
		(start 154.5266 88.4106)
		(end 154.503992 88.408052)
		(width 0.1016)
		(layer "In2.Cu")
		(net 23)
	)
	(segment
		(start 154.814939 88.061717)
		(end 154.802835 88.042453)
		(width 0.1016)
		(layer "In2.Cu")
		(net 23)
	)
	(segment
		(start 153.8 90)
		(end 153.8872 90)
		(width 0.1016)
		(layer "In2.Cu")
		(net 23)
	)
	(segment
		(start 153.622165 91.530253)
		(end 153.638253 91.514165)
		(width 0.1016)
		(layer "In2.Cu")
		(net 23)
	)
	(segment
		(start 154.825 87.6994)
		(end 154.825 87.25)
		(width 0.1016)
		(layer "In2.Cu")
		(net 23)
	)
	(segment
		(start 154.802835 88.855253)
		(end 154.786747 88.839165)
		(width 0.1016)
		(layer "In2.Cu")
		(net 23)
	)
	(segment
		(start 153.885984 91.717365)
		(end 153.86672 91.705261)
		(width 0.1016)
		(layer "In2.Cu")
		(net 23)
	)
	(segment
		(start 154.746009 89.225947)
		(end 154.7234 89.2234)
		(width 0.1016)
		(layer "In2.Cu")
		(net 23)
	)
	(segment
		(start 153.678991 91.692652)
		(end 153.657517 91.685138)
		(width 0.1016)
		(layer "In2.Cu")
		(net 23)
	)
	(segment
		(start 153.610061 90.824882)
		(end 153.602547 90.803408)
		(width 0.1016)
		(layer "In2.Cu")
		(net 23)
	)
	(segment
		(start 154.189452 90.421009)
		(end 154.192 90.3984)
		(width 0.1016)
		(layer "In2.Cu")
		(net 23)
	)
	(segment
		(start 153.822638 91.492)
		(end 153.845246 91.489452)
		(width 0.1016)
		(layer "In2.Cu")
		(net 23)
	)
	(segment
		(start 154.427548 88.738008)
		(end 154.425 88.7154)
		(width 0.1016)
		(layer "In2.Cu")
		(net 23)
	)
	(segment
		(start 153.902072 91.733453)
		(end 153.885984 91.717365)
		(width 0.1016)
		(layer "In2.Cu")
		(net 23)
	)
	(segment
		(start 153.914176 91.434482)
		(end 153.92169 91.413008)
		(width 0.1016)
		(layer "In2.Cu")
		(net 23)
	)
	(segment
		(start 154.767483 89.233461)
		(end 154.746009 89.225947)
		(width 0.1016)
		(layer "In2.Cu")
		(net 23)
	)
	(segment
		(start 154.5266 88.817)
		(end 154.503992 88.814452)
		(width 0.1016)
		(layer "In2.Cu")
		(net 23)
	)
	(segment
		(start 153.902072 91.047346)
		(end 153.914176 91.028082)
		(width 0.1016)
		(layer "In2.Cu")
		(net 23)
	)
	(segment
		(start 154.5266 89.2234)
		(end 154.503992 89.220852)
		(width 0.1016)
		(layer "In2.Cu")
		(net 23)
	)
	(segment
		(start 154.427548 89.099191)
		(end 154.435062 89.077717)
		(width 0.1016)
		(layer "In2.Cu")
		(net 23)
	)
	(segment
		(start 153.92169 91.819408)
		(end 153.924238 91.7968)
		(width 0.1016)
		(layer "In2.Cu")
		(net 23)
	)
	(segment
		(start 153.902072 91.860146)
		(end 153.914176 91.840882)
		(width 0.1016)
		(layer "In2.Cu")
		(net 23)
	)
	(segment
		(start 154.010965 90.461747)
		(end 154.027053 90.477835)
		(width 0.1016)
		(layer "In2.Cu")
		(net 23)
	)
	(segment
		(start 154.425 88.309)
		(end 154.427548 88.286391)
		(width 0.1016)
		(layer "In2.Cu")
		(net 23)
	)
	(segment
		(start 153.7016 90.8824)
		(end 153.678991 90.879852)
		(width 0.1016)
		(layer "In2.Cu")
		(net 23)
	)
	(segment
		(start 153.902072 91.327053)
		(end 153.885984 91.310965)
		(width 0.1016)
		(layer "In2.Cu")
		(net 23)
	)
	(segment
		(start 154.503992 87.803547)
		(end 154.5266 87.801)
		(width 0.1016)
		(layer "In2.Cu")
		(net 23)
	)
	(segment
		(start 154.503992 88.408052)
		(end 154.482518 88.400538)
		(width 0.1016)
		(layer "In2.Cu")
		(net 23)
	)
	(segment
		(start 154.192 90.3984)
		(end 154.192 90.1016)
		(width 0.1016)
		(layer "In2.Cu")
		(net 23)
	)
	(segment
		(start 153.610061 91.637682)
		(end 153.602547 91.616208)
		(width 0.1016)
		(layer "In2.Cu")
		(net 23)
	)
	(segment
		(start 154.482518 88.623861)
		(end 154.503992 88.616347)
		(width 0.1016)
		(layer "In2.Cu")
		(net 23)
	)
	(segment
		(start 153.657517 90.872338)
		(end 153.638253 90.860234)
		(width 0.1016)
		(layer "In2.Cu")
		(net 23)
	)
	(segment
		(start 154.463254 89.042365)
		(end 154.482518 89.030261)
		(width 0.1016)
		(layer "In2.Cu")
		(net 23)
	)
	(segment
		(start 154.814939 88.962682)
		(end 154.822453 88.941208)
		(width 0.1016)
		(layer "In2.Cu")
		(net 23)
	)
	(segment
		(start 154.435062 89.077717)
		(end 154.447166 89.058453)
		(width 0.1016)
		(layer "In2.Cu")
		(net 23)
	)
	(segment
		(start 154.620565 90.038254)
		(end 154.636653 90.022166)
		(width 0.1016)
		(layer "In2.Cu")
		(net 23)
	)
	(segment
		(start 154.825 88.9186)
		(end 154.822453 88.895991)
		(width 0.1016)
		(layer "In2.Cu")
		(net 23)
	)
	(segment
		(start 154.4968 90.5)
		(end 154.519408 90.497453)
		(width 0.1016)
		(layer "In2.Cu")
		(net 23)
	)
	(segment
		(start 153.902072 91.453746)
		(end 153.914176 91.434482)
		(width 0.1016)
		(layer "In2.Cu")
		(net 23)
	)
	(segment
		(start 154.447166 88.372346)
		(end 154.435062 88.353082)
		(width 0.1016)
		(layer "In2.Cu")
		(net 23)
	)
	(segment
		(start 154.825 89.325)
		(end 154.822453 89.302391)
		(width 0.1016)
		(layer "In2.Cu")
		(net 23)
	)
	(segment
		(start 154.0904 90.5)
		(end 154.113008 90.497453)
		(width 0.1016)
		(layer "In2.Cu")
		(net 23)
	)
	(segment
		(start 154.447166 87.965946)
		(end 154.435062 87.946682)
		(width 0.1016)
		(layer "In2.Cu")
		(net 23)
	)
	(segment
		(start 154.746009 89.017652)
		(end 154.767483 89.010138)
		(width 0.1016)
		(layer "In2.Cu")
		(net 23)
	)
	(segment
		(start 154.425 88.7154)
		(end 154.427548 88.692791)
		(width 0.1016)
		(layer "In2.Cu")
		(net 23)
	)
	(segment
		(start 154.5266 88.2074)
		(end 154.7234 88.2074)
		(width 0.1016)
		(layer "In2.Cu")
		(net 23)
	)
	(segment
		(start 154.814939 88.468117)
		(end 154.802835 88.448853)
		(width 0.1016)
		(layer "In2.Cu")
		(net 23)
	)
	(segment
		(start 154.814939 89.280917)
		(end 154.802835 89.261653)
		(width 0.1016)
		(layer "In2.Cu")
		(net 23)
	)
	(segment
		(start 154.802835 88.981946)
		(end 154.814939 88.962682)
		(width 0.1016)
		(layer "In2.Cu")
		(net 23)
	)
	(segment
		(start 153.914176 91.840882)
		(end 153.92169 91.819408)
		(width 0.1016)
		(layer "In2.Cu")
		(net 23)
	)
	(segment
		(start 154.337682 90.010062)
		(end 154.356946 90.022166)
		(width 0.1016)
		(layer "In2.Cu")
		(net 23)
	)
	(segment
		(start 153.86672 91.705261)
		(end 153.845246 91.697747)
		(width 0.1016)
		(layer "In2.Cu")
		(net 23)
	)
	(segment
		(start 154.3952 90.1016)
		(end 154.3952 90.3984)
		(width 0.1016)
		(layer "In2.Cu")
		(net 23)
	)
	(segment
		(start 154.113008 90.497453)
		(end 154.134482 90.489939)
		(width 0.1016)
		(layer "In2.Cu")
		(net 23)
	)
	(segment
		(start 154.7234 88.6138)
		(end 154.746009 88.611252)
		(width 0.1016)
		(layer "In2.Cu")
		(net 23)
	)
	(segment
		(start 153.86672 91.298861)
		(end 153.845246 91.291347)
		(width 0.1016)
		(layer "In2.Cu")
		(net 23)
	)
	(segment
		(start 154.452717 90.489939)
		(end 154.474191 90.497453)
		(width 0.1016)
		(layer "In2.Cu")
		(net 23)
	)
	(segment
		(start 154.600947 90.078992)
		(end 154.608461 90.057518)
		(width 0.1016)
		(layer "In2.Cu")
		(net 23)
	)
	(segment
		(start 154.503992 88.209947)
		(end 154.5266 88.2074)
		(width 0.1016)
		(layer "In2.Cu")
		(net 23)
	)
	(segment
		(start 153.822638 91.6952)
		(end 153.7016 91.6952)
		(width 0.1016)
		(layer "In2.Cu")
		(net 23)
	)
	(segment
		(start 154.608461 90.057518)
		(end 154.620565 90.038254)
		(width 0.1016)
		(layer "In2.Cu")
		(net 23)
	)
	(segment
		(start 154.786747 89.245565)
		(end 154.767483 89.233461)
		(width 0.1016)
		(layer "In2.Cu")
		(net 23)
	)
	(segment
		(start 153.991347 90.421009)
		(end 153.998861 90.442483)
		(width 0.1016)
		(layer "In2.Cu")
		(net 23)
	)
	(segment
		(start 154.5266 88.0042)
		(end 154.503992 88.001652)
		(width 0.1016)
		(layer "In2.Cu")
		(net 23)
	)
	(segment
		(start 154.463254 88.794834)
		(end 154.447166 88.778746)
		(width 0.1016)
		(layer "In2.Cu")
		(net 23)
	)
	(segment
		(start 154.636653 90.022166)
		(end 154.655917 90.010062)
		(width 0.1016)
		(layer "In2.Cu")
		(net 23)
	)
	(segment
		(start 154.202061 90.057518)
		(end 154.214165 90.038254)
		(width 0.1016)
		(layer "In2.Cu")
		(net 23)
	)
	(segment
		(start 154.5984 90.1016)
		(end 154.600947 90.078992)
		(width 0.1016)
		(layer "In2.Cu")
		(net 23)
	)
	(segment
		(start 153.822638 91.0856)
		(end 153.845246 91.083052)
		(width 0.1016)
		(layer "In2.Cu")
		(net 23)
	)
	(segment
		(start 153.678991 91.286252)
		(end 153.657517 91.278738)
		(width 0.1016)
		(layer "In2.Cu")
		(net 23)
	)
	(segment
		(start 154.588338 90.442483)
		(end 154.595852 90.421009)
		(width 0.1016)
		(layer "In2.Cu")
		(net 23)
	)
	(segment
		(start 153.610061 91.549517)
		(end 153.622165 91.530253)
		(width 0.1016)
		(layer "In2.Cu")
		(net 23)
	)
	(segment
		(start 153.678991 91.494547)
		(end 153.7016 91.492)
		(width 0.1016)
		(layer "In2.Cu")
		(net 23)
	)
	(segment
		(start 153.86672 91.075538)
		(end 153.885984 91.063434)
		(width 0.1016)
		(layer "In2.Cu")
		(net 23)
	)
	(segment
		(start 153.845246 91.697747)
		(end 153.822638 91.6952)
		(width 0.1016)
		(layer "In2.Cu")
		(net 23)
	)
	(segment
		(start 154.427548 88.331608)
		(end 154.425 88.309)
		(width 0.1016)
		(layer "In2.Cu")
		(net 23)
	)
	(segment
		(start 154.447166 88.652053)
		(end 154.463254 88.635965)
		(width 0.1016)
		(layer "In2.Cu")
		(net 23)
	)
	(segment
		(start 154.463254 88.635965)
		(end 154.482518 88.623861)
		(width 0.1016)
		(layer "In2.Cu")
		(net 23)
	)
	(segment
		(start 153.8872 90)
		(end 153.909808 90.002548)
		(width 0.1016)
		(layer "In2.Cu")
		(net 23)
	)
	(segment
		(start 154.786747 88.591634)
		(end 154.802835 88.575546)
		(width 0.1016)
		(layer "In2.Cu")
		(net 23)
	)
	(segment
		(start 154.397747 90.421009)
		(end 154.405261 90.442483)
		(width 0.1016)
		(layer "In2.Cu")
		(net 23)
	)
	(segment
		(start 154.7234 88.817)
		(end 154.5266 88.817)
		(width 0.1016)
		(layer "In2.Cu")
		(net 23)
	)
	(segment
		(start 154.447166 89.058453)
		(end 154.463254 89.042365)
		(width 0.1016)
		(layer "In2.Cu")
		(net 23)
	)
	(segment
		(start 154.519408 90.497453)
		(end 154.540882 90.489939)
		(width 0.1016)
		(layer "In2.Cu")
		(net 23)
	)
	(segment
		(start 154.802835 87.762746)
		(end 154.814939 87.743482)
		(width 0.1016)
		(layer "In2.Cu")
		(net 23)
	)
	(segment
		(start 154.427548 89.144408)
		(end 154.425 89.1218)
		(width 0.1016)
		(layer "In2.Cu")
		(net 23)
	)
	(segment
		(start 153.86672 91.481938)
		(end 153.885984 91.469834)
		(width 0.1016)
		(layer "In2.Cu")
		(net 23)
	)
	(segment
		(start 154.270991 90.002548)
		(end 154.2936 90)
		(width 0.1016)
		(layer "In2.Cu")
		(net 23)
	)
	(segment
		(start 153.638253 91.920565)
		(end 153.657517 91.908461)
		(width 0.1016)
		(layer "In2.Cu")
		(net 23)
	)
	(segment
		(start 154.435062 89.165882)
		(end 154.427548 89.144408)
		(width 0.1016)
		(layer "In2.Cu")
		(net 23)
	)
	(segment
		(start 154.482518 88.400538)
		(end 154.463254 88.388434)
		(width 0.1016)
		(layer "In2.Cu")
		(net 23)
	)
	(segment
		(start 154.7234 87.801)
		(end 154.746009 87.798452)
		(width 0.1016)
		(layer "In2.Cu")
		(net 23)
	)
	(segment
		(start 154.433453 90.477835)
		(end 154.452717 90.489939)
		(width 0.1016)
		(layer "In2.Cu")
		(net 23)
	)
	(segment
		(start 154.503992 89.022747)
		(end 154.5266 89.0202)
		(width 0.1016)
		(layer "In2.Cu")
		(net 23)
	)
	(segment
		(start 153.6 91.1872)
		(end 153.602547 91.164591)
		(width 0.1016)
		(layer "In2.Cu")
		(net 23)
	)
	(segment
		(start 154.169834 90.461747)
		(end 154.181938 90.442483)
		(width 0.1016)
		(layer "In2.Cu")
		(net 23)
	)
	(segment
		(start 154.822453 88.895991)
		(end 154.814939 88.874517)
		(width 0.1016)
		(layer "In2.Cu")
		(net 23)
	)
	(segment
		(start 153.914176 91.346317)
		(end 153.902072 91.327053)
		(width 0.1016)
		(layer "In2.Cu")
		(net 23)
	)
	(segment
		(start 153.845246 90.884947)
		(end 153.822638 90.8824)
		(width 0.1016)
		(layer "In2.Cu")
		(net 23)
	)
	(segment
		(start 154.153746 90.477835)
		(end 154.169834 90.461747)
		(width 0.1016)
		(layer "In2.Cu")
		(net 23)
	)
	(segment
		(start 153.822638 90.8824)
		(end 153.7016 90.8824)
		(width 0.1016)
		(layer "In2.Cu")
		(net 23)
	)
	(segment
		(start 153.638253 91.107765)
		(end 153.657517 91.095661)
		(width 0.1016)
		(layer "In2.Cu")
		(net 23)
	)
	(segment
		(start 154.786747 88.998034)
		(end 154.802835 88.981946)
		(width 0.1016)
		(layer "In2.Cu")
		(net 23)
	)
	(segment
		(start 154.373034 90.038254)
		(end 154.385138 90.057518)
		(width 0.1016)
		(layer "In2.Cu")
		(net 23)
	)
	(segment
		(start 154.7234 88.4106)
		(end 154.5266 88.4106)
		(width 0.1016)
		(layer "In2.Cu")
		(net 23)
	)
	(segment
		(start 154.802835 88.169146)
		(end 154.814939 88.149882)
		(width 0.1016)
		(layer "In2.Cu")
		(net 23)
	)
	(segment
		(start 153.845246 91.489452)
		(end 153.86672 91.481938)
		(width 0.1016)
		(layer "In2.Cu")
		(net 23)
	)
	(segment
		(start 154.503992 88.814452)
		(end 154.482518 88.806938)
		(width 0.1016)
		(layer "In2.Cu")
		(net 23)
	)
	(segment
		(start 154.822453 88.941208)
		(end 154.825 88.9186)
		(width 0.1016)
		(layer "In2.Cu")
		(net 23)
	)
	(segment
		(start 154.746009 88.819547)
		(end 154.7234 88.817)
		(width 0.1016)
		(layer "In2.Cu")
		(net 23)
	)
	(segment
		(start 154.230253 90.022166)
		(end 154.249517 90.010062)
		(width 0.1016)
		(layer "In2.Cu")
		(net 23)
	)
	(segment
		(start 154.503992 88.001652)
		(end 154.482518 87.994138)
		(width 0.1016)
		(layer "In2.Cu")
		(net 23)
	)
	(segment
		(start 153.602547 91.209808)
		(end 153.6 91.1872)
		(width 0.1016)
		(layer "In2.Cu")
		(net 23)
	)
	(segment
		(start 153.885984 90.904565)
		(end 153.86672 90.892461)
		(width 0.1016)
		(layer "In2.Cu")
		(net 23)
	)
	(segment
		(start 154.427548 88.286391)
		(end 154.435062 88.264917)
		(width 0.1016)
		(layer "In2.Cu")
		(net 23)
	)
	(segment
		(start 153.978738 90.057518)
		(end 153.986252 90.078992)
		(width 0.1016)
		(layer "In2.Cu")
		(net 23)
	)
	(segment
		(start 153.6 90.7808)
		(end 153.6 90.2)
		(width 0.1016)
		(layer "In2.Cu")
		(net 23)
	)
	(segment
		(start 153.986252 90.078992)
		(end 153.9888 90.1016)
		(width 0.1016)
		(layer "In2.Cu")
		(net 23)
	)
	(segment
		(start 154.677391 90.002548)
		(end 154.7 90)
		(width 0.1016)
		(layer "In2.Cu")
		(net 23)
	)
	(segment
		(start 154.767483 88.420661)
		(end 154.746009 88.413147)
		(width 0.1016)
		(layer "In2.Cu")
		(net 23)
	)
	(segment
		(start 154.463254 88.388434)
		(end 154.447166 88.372346)
		(width 0.1016)
		(layer "In2.Cu")
		(net 23)
	)
	(segment
		(start 154.822453 88.534808)
		(end 154.825 88.5122)
		(width 0.1016)
		(layer "In2.Cu")
		(net 23)
	)
	(segment
		(start 154.746009 88.006747)
		(end 154.7234 88.0042)
		(width 0.1016)
		(layer "In2.Cu")
		(net 23)
	)
	(segment
		(start 154.5984 90.3984)
		(end 154.5984 90.1016)
		(width 0.1016)
		(layer "In2.Cu")
		(net 23)
	)
	(segment
		(start 153.6 92)
		(end 153.602547 91.977391)
		(width 0.1016)
		(layer "In2.Cu")
		(net 23)
	)
	(segment
		(start 154.482518 87.994138)
		(end 154.463254 87.982034)
		(width 0.1016)
		(layer "In2.Cu")
		(net 23)
	)
	(segment
		(start 154.7234 89.0202)
		(end 154.746009 89.017652)
		(width 0.1016)
		(layer "In2.Cu")
		(net 23)
	)
	(segment
		(start 154.802835 89.261653)
		(end 154.786747 89.245565)
		(width 0.1016)
		(layer "In2.Cu")
		(net 23)
	)
	(segment
		(start 154.825 88.1058)
		(end 154.822453 88.083191)
		(width 0.1016)
		(layer "In2.Cu")
		(net 23)
	)
	(segment
		(start 154.822453 88.083191)
		(end 154.814939 88.061717)
		(width 0.1016)
		(layer "In2.Cu")
		(net 23)
	)
	(segment
		(start 154.7 90)
		(end 154.825 89.875)
		(width 0.1016)
		(layer "In2.Cu")
		(net 23)
	)
	(segment
		(start 154.814939 88.556282)
		(end 154.822453 88.534808)
		(width 0.1016)
		(layer "In2.Cu")
		(net 23)
	)
	(segment
		(start 153.6 91.5936)
		(end 153.602547 91.570991)
		(width 0.1016)
		(layer "In2.Cu")
		(net 23)
	)
	(segment
		(start 154.822453 88.128408)
		(end 154.825 88.1058)
		(width 0.1016)
		(layer "In2.Cu")
		(net 23)
	)
	(segment
		(start 154.427548 88.692791)
		(end 154.435062 88.671317)
		(width 0.1016)
		(layer "In2.Cu")
		(net 23)
	)
	(segment
		(start 153.602547 91.164591)
		(end 153.610061 91.143117)
		(width 0.1016)
		(layer "In2.Cu")
		(net 23)
	)
	(segment
		(start 153.914176 90.939917)
		(end 153.902072 90.920653)
		(width 0.1016)
		(layer "In2.Cu")
		(net 23)
	)
	(segment
		(start 154.746009 88.413147)
		(end 154.7234 88.4106)
		(width 0.1016)
		(layer "In2.Cu")
		(net 23)
	)
	(segment
		(start 153.6 90.2)
		(end 153.8 90)
		(width 0.1016)
		(layer "In2.Cu")
		(net 23)
	)
	(segment
		(start 153.92169 91.774191)
		(end 153.914176 91.752717)
		(width 0.1016)
		(layer "In2.Cu")
		(net 23)
	)
	(segment
		(start 154.046317 90.489939)
		(end 154.067791 90.497453)
		(width 0.1016)
		(layer "In2.Cu")
		(net 23)
	)
	(segment
		(start 153.657517 91.685138)
		(end 153.638253 91.673034)
		(width 0.1016)
		(layer "In2.Cu")
		(net 23)
	)
	(segment
		(start 154.655917 90.010062)
		(end 154.677391 90.002548)
		(width 0.1016)
		(layer "In2.Cu")
		(net 23)
	)
	(segment
		(start 154.405261 90.442483)
		(end 154.417365 90.461747)
		(width 0.1016)
		(layer "In2.Cu")
		(net 23)
	)
	(segment
		(start 153.7016 91.0856)
		(end 153.822638 91.0856)
		(width 0.1016)
		(layer "In2.Cu")
		(net 23)
	)
	(segment
		(start 153.7016 91.2888)
		(end 153.678991 91.286252)
		(width 0.1016)
		(layer "In2.Cu")
		(net 23)
	)
	(segment
		(start 153.602547 90.803408)
		(end 153.6 90.7808)
		(width 0.1016)
		(layer "In2.Cu")
		(net 23)
	)
	(segment
		(start 154.825 89.875)
		(end 154.825 89.325)
		(width 0.1016)
		(layer "In2.Cu")
		(net 23)
	)
	(segment
		(start 153.914176 91.028082)
		(end 153.92169 91.006608)
		(width 0.1016)
		(layer "In2.Cu")
		(net 23)
	)
	(segment
		(start 153.92169 91.367791)
		(end 153.914176 91.346317)
		(width 0.1016)
		(layer "In2.Cu")
		(net 23)
	)
	(segment
		(start 153.622165 91.936653)
		(end 153.638253 91.920565)
		(width 0.1016)
		(layer "In2.Cu")
		(net 23)
	)
	(segment
		(start 154.576234 90.461747)
		(end 154.588338 90.442483)
		(width 0.1016)
		(layer "In2.Cu")
		(net 23)
	)
	(segment
		(start 154.425 89.1218)
		(end 154.427548 89.099191)
		(width 0.1016)
		(layer "In2.Cu")
		(net 23)
	)
	(segment
		(start 153.950546 90.022166)
		(end 153.966634 90.038254)
		(width 0.1016)
		(layer "In2.Cu")
		(net 23)
	)
	(segment
		(start 153.602547 91.616208)
		(end 153.6 91.5936)
		(width 0.1016)
		(layer "In2.Cu")
		(net 23)
	)
	(segment
		(start 153.885984 91.310965)
		(end 153.86672 91.298861)
		(width 0.1016)
		(layer "In2.Cu")
		(net 23)
	)
	(segment
		(start 154.181938 90.442483)
		(end 154.189452 90.421009)
		(width 0.1016)
		(layer "In2.Cu")
		(net 23)
	)
	(segment
		(start 153.902072 90.920653)
		(end 153.885984 90.904565)
		(width 0.1016)
		(layer "In2.Cu")
		(net 23)
	)
	(segment
		(start 154.7234 88.0042)
		(end 154.5266 88.0042)
		(width 0.1016)
		(layer "In2.Cu")
		(net 23)
	)
	(segment
		(start 153.92169 91.413008)
		(end 153.924238 91.3904)
		(width 0.1016)
		(layer "In2.Cu")
		(net 23)
	)
	(segment
		(start 153.86672 91.888338)
		(end 153.885984 91.876234)
		(width 0.1016)
		(layer "In2.Cu")
		(net 23)
	)
	(segment
		(start 153.638253 91.514165)
		(end 153.657517 91.502061)
		(width 0.1016)
		(layer "In2.Cu")
		(net 23)
	)
	(segment
		(start 153.610061 91.231282)
		(end 153.602547 91.209808)
		(width 0.1016)
		(layer "In2.Cu")
		(net 23)
	)
	(segment
		(start 154.482518 89.030261)
		(end 154.503992 89.022747)
		(width 0.1016)
		(layer "In2.Cu")
		(net 23)
	)
	(segment
		(start 154.447166 87.839253)
		(end 154.463254 87.823165)
		(width 0.1016)
		(layer "In2.Cu")
		(net 23)
	)
	(segment
		(start 154.435062 88.353082)
		(end 154.427548 88.331608)
		(width 0.1016)
		(layer "In2.Cu")
		(net 23)
	)
	(segment
		(start 154.7234 89.2234)
		(end 154.5266 89.2234)
		(width 0.1016)
		(layer "In2.Cu")
		(net 23)
	)
	(segment
		(start 153.9888 90.1016)
		(end 153.9888 90.3984)
		(width 0.1016)
		(layer "In2.Cu")
		(net 23)
	)
	(segment
		(start 154.447166 88.778746)
		(end 154.435062 88.759482)
		(width 0.1016)
		(layer "In2.Cu")
		(net 23)
	)
	(segment
		(start 154.746009 88.204852)
		(end 154.767483 88.197338)
		(width 0.1016)
		(layer "In2.Cu")
		(net 23)
	)
	(segment
		(start 153.638253 91.673034)
		(end 153.622165 91.656946)
		(width 0.1016)
		(layer "In2.Cu")
		(net 23)
	)
	(segment
		(start 153.622165 91.250546)
		(end 153.610061 91.231282)
		(width 0.1016)
		(layer "In2.Cu")
		(net 23)
	)
	(segment
		(start 153.92169 91.006608)
		(end 153.924238 90.984)
		(width 0.1016)
		(layer "In2.Cu")
		(net 23)
	)
	(segment
		(start 154.435062 88.759482)
		(end 154.427548 88.738008)
		(width 0.1016)
		(layer "In2.Cu")
		(net 23)
	)
	(segment
		(start 153.610061 91.955917)
		(end 153.622165 91.936653)
		(width 0.1016)
		(layer "In2.Cu")
		(net 23)
	)
	(segment
		(start 153.9888 90.3984)
		(end 153.991347 90.421009)
		(width 0.1016)
		(layer "In2.Cu")
		(net 23)
	)
	(segment
		(start 153.657517 91.095661)
		(end 153.678991 91.088147)
		(width 0.1016)
		(layer "In2.Cu")
		(net 23)
	)
	(segment
		(start 154.767483 88.603738)
		(end 154.786747 88.591634)
		(width 0.1016)
		(layer "In2.Cu")
		(net 23)
	)
	(segment
		(start 153.610061 91.143117)
		(end 153.622165 91.123853)
		(width 0.1016)
		(layer "In2.Cu")
		(net 23)
	)
	(segment
		(start 153.86672 90.892461)
		(end 153.845246 90.884947)
		(width 0.1016)
		(layer "In2.Cu")
		(net 23)
	)
	(segment
		(start 153.909808 90.002548)
		(end 153.931282 90.010062)
		(width 0.1016)
		(layer "In2.Cu")
		(net 23)
	)
	(segment
		(start 153.602547 91.570991)
		(end 153.610061 91.549517)
		(width 0.1016)
		(layer "In2.Cu")
		(net 23)
	)
	(segment
		(start 154.417365 90.461747)
		(end 154.433453 90.477835)
		(width 0.1016)
		(layer "In2.Cu")
		(net 23)
	)
	(segment
		(start 154.540882 90.489939)
		(end 154.560146 90.477835)
		(width 0.1016)
		(layer "In2.Cu")
		(net 23)
	)
	(segment
		(start 154.2936 90)
		(end 154.316208 90.002548)
		(width 0.1016)
		(layer "In2.Cu")
		(net 23)
	)
	(segment
		(start 153.678991 90.879852)
		(end 153.657517 90.872338)
		(width 0.1016)
		(layer "In2.Cu")
		(net 23)
	)
	(segment
		(start 154.802835 88.042453)
		(end 154.786747 88.026365)
		(width 0.1016)
		(layer "In2.Cu")
		(net 23)
	)
	(segment
		(start 153.657517 91.908461)
		(end 153.678991 91.900947)
		(width 0.1016)
		(layer "In2.Cu")
		(net 23)
	)
	(segment
		(start 154.435062 88.671317)
		(end 154.447166 88.652053)
		(width 0.1016)
		(layer "In2.Cu")
		(net 23)
	)
	(segment
		(start 154.786747 88.026365)
		(end 154.767483 88.014261)
		(width 0.1016)
		(layer "In2.Cu")
		(net 23)
	)
	(segment
		(start 154.7234 88.2074)
		(end 154.746009 88.204852)
		(width 0.1016)
		(layer "In2.Cu")
		(net 23)
	)
	(segment
		(start 154.482518 88.806938)
		(end 154.463254 88.794834)
		(width 0.1016)
		(layer "In2.Cu")
		(net 23)
	)
	(segment
		(start 154.134482 90.489939)
		(end 154.153746 90.477835)
		(width 0.1016)
		(layer "In2.Cu")
		(net 23)
	)
	(segment
		(start 154.786747 88.839165)
		(end 154.767483 88.827061)
		(width 0.1016)
		(layer "In2.Cu")
		(net 23)
	)
	(segment
		(start 153.924238 91.7968)
		(end 153.92169 91.774191)
		(width 0.1016)
		(layer "In2.Cu")
		(net 23)
	)
	(segment
		(start 153.678991 91.088147)
		(end 153.7016 91.0856)
		(width 0.1016)
		(layer "In2.Cu")
		(net 23)
	)
	(segment
		(start 154.385138 90.057518)
		(end 154.392652 90.078992)
		(width 0.1016)
		(layer "In2.Cu")
		(net 23)
	)
	(segment
		(start 153.6 92.2)
		(end 153.6 92)
		(width 0.1016)
		(layer "In2.Cu")
		(net 23)
	)
	(segment
		(start 154.463254 89.201234)
		(end 154.447166 89.185146)
		(width 0.1016)
		(layer "In2.Cu")
		(net 23)
	)
	(segment
		(start 154.482518 89.213338)
		(end 154.463254 89.201234)
		(width 0.1016)
		(layer "In2.Cu")
		(net 23)
	)
	(segment
		(start 154.767483 87.790938)
		(end 154.786747 87.778834)
		(width 0.1016)
		(layer "In2.Cu")
		(net 23)
	)
	(segment
		(start 154.5266 89.0202)
		(end 154.7234 89.0202)
		(width 0.1016)
		(layer "In2.Cu")
		(net 23)
	)
	(segment
		(start 153.622165 91.656946)
		(end 153.610061 91.637682)
		(width 0.1016)
		(layer "In2.Cu")
		(net 23)
	)
	(segment
		(start 153.885984 91.876234)
		(end 153.902072 91.860146)
		(width 0.1016)
		(layer "In2.Cu")
		(net 23)
	)
	(segment
		(start 154.463254 88.229565)
		(end 154.482518 88.217461)
		(width 0.1016)
		(layer "In2.Cu")
		(net 23)
	)
	(segment
		(start 153.924238 90.984)
		(end 153.92169 90.961391)
		(width 0.1016)
		(layer "In2.Cu")
		(net 23)
	)
	(segment
		(start 153.7016 91.492)
		(end 153.822638 91.492)
		(width 0.1016)
		(layer "In2.Cu")
		(net 23)
	)
	(segment
		(start 154.814939 87.743482)
		(end 154.822453 87.722008)
		(width 0.1016)
		(layer "In2.Cu")
		(net 23)
	)
	(segment
		(start 153.914176 91.752717)
		(end 153.902072 91.733453)
		(width 0.1016)
		(layer "In2.Cu")
		(net 23)
	)
	(segment
		(start 154.767483 88.197338)
		(end 154.786747 88.185234)
		(width 0.1016)
		(layer "In2.Cu")
		(net 23)
	)
	(segment
		(start 154.822453 88.489591)
		(end 154.814939 88.468117)
		(width 0.1016)
		(layer "In2.Cu")
		(net 23)
	)
	(segment
		(start 153.885984 91.469834)
		(end 153.902072 91.453746)
		(width 0.1016)
		(layer "In2.Cu")
		(net 23)
	)
	(segment
		(start 154.067791 90.497453)
		(end 154.0904 90.5)
		(width 0.1016)
		(layer "In2.Cu")
		(net 23)
	)
	(segment
		(start 154.822453 89.302391)
		(end 154.814939 89.280917)
		(width 0.1016)
		(layer "In2.Cu")
		(net 23)
	)
	(segment
		(start 154.474191 90.497453)
		(end 154.4968 90.5)
		(width 0.1016)
		(layer "In2.Cu")
		(net 23)
	)
	(segment
		(start 153.602547 91.977391)
		(end 153.610061 91.955917)
		(width 0.1016)
		(layer "In2.Cu")
		(net 23)
	)
	(segment
		(start 153.845246 91.895852)
		(end 153.86672 91.888338)
		(width 0.1016)
		(layer "In2.Cu")
		(net 23)
	)
	(segment
		(start 153.7016 91.6952)
		(end 153.678991 91.692652)
		(width 0.1016)
		(layer "In2.Cu")
		(net 23)
	)
	(segment
		(start 154.435062 87.858517)
		(end 154.447166 87.839253)
		(width 0.1016)
		(layer "In2.Cu")
		(net 23)
	)
	(segment
		(start 154.463254 87.823165)
		(end 154.482518 87.811061)
		(width 0.1016)
		(layer "In2.Cu")
		(net 23)
	)
	(segment
		(start 154.194547 90.078992)
		(end 154.202061 90.057518)
		(width 0.1016)
		(layer "In2.Cu")
		(net 23)
	)
	(segment
		(start 154.802835 88.448853)
		(end 154.786747 88.432765)
		(width 0.1016)
		(layer "In2.Cu")
		(net 23)
	)
	(segment
		(start 153.638253 90.860234)
		(end 153.622165 90.844146)
		(width 0.1016)
		(layer "In2.Cu")
		(net 23)
	)
	(segment
		(start 154.447166 89.185146)
		(end 154.435062 89.165882)
		(width 0.1016)
		(layer "In2.Cu")
		(net 23)
	)
	(segment
		(start 153.822638 91.2888)
		(end 153.7016 91.2888)
		(width 0.1016)
		(layer "In2.Cu")
		(net 23)
	)
	(segment
		(start 153.7016 91.8984)
		(end 153.822638 91.8984)
		(width 0.1016)
		(layer "In2.Cu")
		(net 23)
	)
	(segment
		(start 154.427548 87.925208)
		(end 154.425 87.9026)
		(width 0.1016)
		(layer "In2.Cu")
		(net 23)
	)
	(segment
		(start 153.966634 90.038254)
		(end 153.978738 90.057518)
		(width 0.1016)
		(layer "In2.Cu")
		(net 23)
	)
	(segment
		(start 154.767483 88.014261)
		(end 154.746009 88.006747)
		(width 0.1016)
		(layer "In2.Cu")
		(net 23)
	)
	(segment
		(start 153.657517 91.502061)
		(end 153.678991 91.494547)
		(width 0.1016)
		(layer "In2.Cu")
		(net 23)
	)
	(segment
		(start 153.92169 90.961391)
		(end 153.914176 90.939917)
		(width 0.1016)
		(layer "In2.Cu")
		(net 23)
	)
	(segment
		(start 154.786747 88.185234)
		(end 154.802835 88.169146)
		(width 0.1016)
		(layer "In2.Cu")
		(net 23)
	)
	(segment
		(start 154.786747 88.432765)
		(end 154.767483 88.420661)
		(width 0.1016)
		(layer "In2.Cu")
		(net 23)
	)
	(segment
		(start 153.622165 90.844146)
		(end 153.610061 90.824882)
		(width 0.1016)
		(layer "In2.Cu")
		(net 23)
	)
	(segment
		(start 153.822638 91.8984)
		(end 153.845246 91.895852)
		(width 0.1016)
		(layer "In2.Cu")
		(net 23)
	)
	(segment
		(start 154.503992 88.616347)
		(end 154.5266 88.6138)
		(width 0.1016)
		(layer "In2.Cu")
		(net 23)
	)
	(segment
		(start 153.998861 90.442483)
		(end 154.010965 90.461747)
		(width 0.1016)
		(layer "In2.Cu")
		(net 23)
	)
	(segment
		(start 153.845246 91.291347)
		(end 153.822638 91.2888)
		(width 0.1016)
		(layer "In2.Cu")
		(net 23)
	)
	(segment
		(start 153.657517 91.278738)
		(end 153.638253 91.266634)
		(width 0.1016)
		(layer "In2.Cu")
		(net 23)
	)
	(segment
		(start 154.814939 88.149882)
		(end 154.822453 88.128408)
		(width 0.1016)
		(layer "In2.Cu")
		(net 23)
	)
	(segment
		(start 154.482518 87.811061)
		(end 154.503992 87.803547)
		(width 0.1016)
		(layer "In2.Cu")
		(net 23)
	)
	(segment
		(start 154.316208 90.002548)
		(end 154.337682 90.010062)
		(width 0.1016)
		(layer "In2.Cu")
		(net 23)
	)
	(segment
		(start 154.746009 87.798452)
		(end 154.767483 87.790938)
		(width 0.1016)
		(layer "In2.Cu")
		(net 23)
	)
	(segment
		(start 154.595852 90.421009)
		(end 154.5984 90.3984)
		(width 0.1016)
		(layer "In2.Cu")
		(net 23)
	)
	(segment
		(start 154.814939 88.874517)
		(end 154.802835 88.855253)
		(width 0.1016)
		(layer "In2.Cu")
		(net 23)
	)
	(segment
		(start 154.356946 90.022166)
		(end 154.373034 90.038254)
		(width 0.1016)
		(layer "In2.Cu")
		(net 23)
	)
	(segment
		(start 148.425 96.425)
		(end 148.425 98.7)
		(width 0.145)
		(layer "F.Cu")
		(net 24)
	)
	(segment
		(start 147.8 95.8)
		(end 148.425 96.425)
		(width 0.145)
		(layer "F.Cu")
		(net 24)
	)
	(segment
		(start 149.625 83.65)
		(end 149.625 84.21)
		(width 0.145)
		(layer "F.Cu")
		(net 24)
	)
	(segment
		(start 146.6 95.8)
		(end 147.8 95.8)
		(width 0.145)
		(layer "F.Cu")
		(net 24)
	)
	(segment
		(start 145.175 92.3)
		(end 145.175 94.375)
		(width 0.145)
		(layer "F.Cu")
		(net 24)
	)
	(segment
		(start 145.175 94.375)
		(end 146.6 95.8)
		(width 0.145)
		(layer "F.Cu")
		(net 24)
	)
	(via
		(at 145.175 92.3)
		(size 0.45)
		(drill 0.15)
		(layers "F.Cu" "B.Cu")
		(net 24)
	)
	(via
		(at 149.625 84.21)
		(size 0.45)
		(drill 0.15)
		(layers "F.Cu" "B.Cu")
		(net 24)
	)
	(segment
		(start 146.745852 86.032043)
		(end 146.738338 86.053517)
		(width 0.1016)
		(layer "In2.Cu")
		(net 24)
	)
	(segment
		(start 146.5452 85.8516)
		(end 146.542652 85.828992)
		(width 0.1016)
		(layer "In2.Cu")
		(net 24)
	)
	(segment
		(start 146.669408 86.108487)
		(end 146.6468 86.111034)
		(width 0.1016)
		(layer "In2.Cu")
		(net 24)
	)
	(segment
		(start 146.177053 86.088869)
		(end 146.160965 86.072781)
		(width 0.1016)
		(layer "In2.Cu")
		(net 24)
	)
	(segment
		(start 146.1388 86.009434)
		(end 146.1388 85.8516)
		(width 0.1016)
		(layer "In2.Cu")
		(net 24)
	)
	(segment
		(start 146.263008 86.108487)
		(end 146.2404 86.111034)
		(width 0.1016)
		(layer "In2.Cu")
		(net 24)
	)
	(segment
		(start 146.352061 85.807518)
		(end 146.344547 85.828992)
		(width 0.1016)
		(layer "In2.Cu")
		(net 24)
	)
	(segment
		(start 146.542652 85.828992)
		(end 146.535138 85.807518)
		(width 0.1016)
		(layer "In2.Cu")
		(net 24)
	)
	(segment
		(start 146.059808 85.752548)
		(end 146.0372 85.75)
		(width 0.1016)
		(layer "In2.Cu")
		(net 24)
	)
	(segment
		(start 146.4436 85.75)
		(end 146.420991 85.752548)
		(width 0.1016)
		(layer "In2.Cu")
		(net 24)
	)
	(segment
		(start 149.625 85.3)
		(end 149.175 85.75)
		(width 0.1016)
		(layer "In2.Cu")
		(net 24)
	)
	(segment
		(start 145.8 85.75)
		(end 145.175 86.375)
		(width 0.1016)
		(layer "In2.Cu")
		(net 24)
	)
	(segment
		(start 146.319834 86.072781)
		(end 146.303746 86.088869)
		(width 0.1016)
		(layer "In2.Cu")
		(net 24)
	)
	(segment
		(start 146.690882 86.100973)
		(end 146.669408 86.108487)
		(width 0.1016)
		(layer "In2.Cu")
		(net 24)
	)
	(segment
		(start 149.175 85.75)
		(end 146.85 85.75)
		(width 0.1016)
		(layer "In2.Cu")
		(net 24)
	)
	(segment
		(start 146.602717 86.100973)
		(end 146.583453 86.088869)
		(width 0.1016)
		(layer "In2.Cu")
		(net 24)
	)
	(segment
		(start 146.128738 85.807518)
		(end 146.116634 85.788254)
		(width 0.1016)
		(layer "In2.Cu")
		(net 24)
	)
	(segment
		(start 146.567365 86.072781)
		(end 146.555261 86.053517)
		(width 0.1016)
		(layer "In2.Cu")
		(net 24)
	)
	(segment
		(start 146.160965 86.072781)
		(end 146.148861 86.053517)
		(width 0.1016)
		(layer "In2.Cu")
		(net 24)
	)
	(segment
		(start 146.710146 86.088869)
		(end 146.690882 86.100973)
		(width 0.1016)
		(layer "In2.Cu")
		(net 24)
	)
	(segment
		(start 149.625 84.21)
		(end 149.625 85.3)
		(width 0.1016)
		(layer "In2.Cu")
		(net 24)
	)
	(segment
		(start 146.523034 85.788254)
		(end 146.506946 85.772166)
		(width 0.1016)
		(layer "In2.Cu")
		(net 24)
	)
	(segment
		(start 146.506946 85.772166)
		(end 146.487682 85.760062)
		(width 0.1016)
		(layer "In2.Cu")
		(net 24)
	)
	(segment
		(start 146.726234 86.072781)
		(end 146.710146 86.088869)
		(width 0.1016)
		(layer "In2.Cu")
		(net 24)
	)
	(segment
		(start 146.770565 85.788254)
		(end 146.758461 85.807518)
		(width 0.1016)
		(layer "In2.Cu")
		(net 24)
	)
	(segment
		(start 146.583453 86.088869)
		(end 146.567365 86.072781)
		(width 0.1016)
		(layer "In2.Cu")
		(net 24)
	)
	(segment
		(start 146.380253 85.772166)
		(end 146.364165 85.788254)
		(width 0.1016)
		(layer "In2.Cu")
		(net 24)
	)
	(segment
		(start 146.342 85.8516)
		(end 146.342 86.009434)
		(width 0.1016)
		(layer "In2.Cu")
		(net 24)
	)
	(segment
		(start 146.141347 86.032043)
		(end 146.1388 86.009434)
		(width 0.1016)
		(layer "In2.Cu")
		(net 24)
	)
	(segment
		(start 146.148861 86.053517)
		(end 146.141347 86.032043)
		(width 0.1016)
		(layer "In2.Cu")
		(net 24)
	)
	(segment
		(start 146.805917 85.760062)
		(end 146.786653 85.772166)
		(width 0.1016)
		(layer "In2.Cu")
		(net 24)
	)
	(segment
		(start 146.85 85.75)
		(end 146.827391 85.752548)
		(width 0.1016)
		(layer "In2.Cu")
		(net 24)
	)
	(segment
		(start 146.535138 85.807518)
		(end 146.523034 85.788254)
		(width 0.1016)
		(layer "In2.Cu")
		(net 24)
	)
	(segment
		(start 146.284482 86.100973)
		(end 146.263008 86.108487)
		(width 0.1016)
		(layer "In2.Cu")
		(net 24)
	)
	(segment
		(start 146.487682 85.760062)
		(end 146.466208 85.752548)
		(width 0.1016)
		(layer "In2.Cu")
		(net 24)
	)
	(segment
		(start 146.750947 85.828992)
		(end 146.7484 85.8516)
		(width 0.1016)
		(layer "In2.Cu")
		(net 24)
	)
	(segment
		(start 146.196317 86.100973)
		(end 146.177053 86.088869)
		(width 0.1016)
		(layer "In2.Cu")
		(net 24)
	)
	(segment
		(start 146.1388 85.8516)
		(end 146.136252 85.828992)
		(width 0.1016)
		(layer "In2.Cu")
		(net 24)
	)
	(segment
		(start 146.5452 86.009434)
		(end 146.5452 85.8516)
		(width 0.1016)
		(layer "In2.Cu")
		(net 24)
	)
	(segment
		(start 146.0372 85.75)
		(end 145.8 85.75)
		(width 0.1016)
		(layer "In2.Cu")
		(net 24)
	)
	(segment
		(start 146.466208 85.752548)
		(end 146.4436 85.75)
		(width 0.1016)
		(layer "In2.Cu")
		(net 24)
	)
	(segment
		(start 146.339452 86.032043)
		(end 146.331938 86.053517)
		(width 0.1016)
		(layer "In2.Cu")
		(net 24)
	)
	(segment
		(start 146.827391 85.752548)
		(end 146.805917 85.760062)
		(width 0.1016)
		(layer "In2.Cu")
		(net 24)
	)
	(segment
		(start 146.7484 85.8516)
		(end 146.7484 86.009434)
		(width 0.1016)
		(layer "In2.Cu")
		(net 24)
	)
	(segment
		(start 146.136252 85.828992)
		(end 146.128738 85.807518)
		(width 0.1016)
		(layer "In2.Cu")
		(net 24)
	)
	(segment
		(start 146.344547 85.828992)
		(end 146.342 85.8516)
		(width 0.1016)
		(layer "In2.Cu")
		(net 24)
	)
	(segment
		(start 146.786653 85.772166)
		(end 146.770565 85.788254)
		(width 0.1016)
		(layer "In2.Cu")
		(net 24)
	)
	(segment
		(start 146.100546 85.772166)
		(end 146.081282 85.760062)
		(width 0.1016)
		(layer "In2.Cu")
		(net 24)
	)
	(segment
		(start 146.364165 85.788254)
		(end 146.352061 85.807518)
		(width 0.1016)
		(layer "In2.Cu")
		(net 24)
	)
	(segment
		(start 146.555261 86.053517)
		(end 146.547747 86.032043)
		(width 0.1016)
		(layer "In2.Cu")
		(net 24)
	)
	(segment
		(start 146.342 86.009434)
		(end 146.339452 86.032043)
		(width 0.1016)
		(layer "In2.Cu")
		(net 24)
	)
	(segment
		(start 145.175 86.375)
		(end 145.175 92.3)
		(width 0.1016)
		(layer "In2.Cu")
		(net 24)
	)
	(segment
		(start 146.7484 86.009434)
		(end 146.745852 86.032043)
		(width 0.1016)
		(layer "In2.Cu")
		(net 24)
	)
	(segment
		(start 146.758461 85.807518)
		(end 146.750947 85.828992)
		(width 0.1016)
		(layer "In2.Cu")
		(net 24)
	)
	(segment
		(start 146.116634 85.788254)
		(end 146.100546 85.772166)
		(width 0.1016)
		(layer "In2.Cu")
		(net 24)
	)
	(segment
		(start 146.6468 86.111034)
		(end 146.624191 86.108487)
		(width 0.1016)
		(layer "In2.Cu")
		(net 24)
	)
	(segment
		(start 146.399517 85.760062)
		(end 146.380253 85.772166)
		(width 0.1016)
		(layer "In2.Cu")
		(net 24)
	)
	(segment
		(start 146.738338 86.053517)
		(end 146.726234 86.072781)
		(width 0.1016)
		(layer "In2.Cu")
		(net 24)
	)
	(segment
		(start 146.2404 86.111034)
		(end 146.217791 86.108487)
		(width 0.1016)
		(layer "In2.Cu")
		(net 24)
	)
	(segment
		(start 146.547747 86.032043)
		(end 146.5452 86.009434)
		(width 0.1016)
		(layer "In2.Cu")
		(net 24)
	)
	(segment
		(start 146.303746 86.088869)
		(end 146.284482 86.100973)
		(width 0.1016)
		(layer "In2.Cu")
		(net 24)
	)
	(segment
		(start 146.081282 85.760062)
		(end 146.059808 85.752548)
		(width 0.1016)
		(layer "In2.Cu")
		(net 24)
	)
	(segment
		(start 146.217791 86.108487)
		(end 146.196317 86.100973)
		(width 0.1016)
		(layer "In2.Cu")
		(net 24)
	)
	(segment
		(start 146.420991 85.752548)
		(end 146.399517 85.760062)
		(width 0.1016)
		(layer "In2.Cu")
		(net 24)
	)
	(segment
		(start 146.624191 86.108487)
		(end 146.602717 86.100973)
		(width 0.1016)
		(layer "In2.Cu")
		(net 24)
	)
	(segment
		(start 146.331938 86.053517)
		(end 146.319834 86.072781)
		(width 0.1016)
		(layer "In2.Cu")
		(net 24)
	)
	(segment
		(start 154.425 82.85)
		(end 154.825 83.25)
		(width 0.145)
		(layer "F.Cu")
		(net 25)
	)
	(via
		(at 154.825 83.25)
		(size 0.45)
		(drill 0.15)
		(layers "F.Cu" "B.Cu")
		(net 25)
	)
	(via
		(at 155.9 92.3)
		(size 0.45)
		(drill 0.15)
		(layers "F.Cu" "B.Cu")
		(net 25)
	)
	(segment
		(start 152.8 95.4)
		(end 152.500099 95.699901)
		(width 0.145)
		(layer "B.Cu")
		(net 25)
	)
	(segment
		(start 154.6 95.4)
		(end 152.8 95.4)
		(width 0.145)
		(layer "B.Cu")
		(net 25)
	)
	(segment
		(start 155.9 94.1)
		(end 154.6 95.4)
		(width 0.145)
		(layer "B.Cu")
		(net 25)
	)
	(segment
		(start 152.500099 96.251518)
		(end 152.675 96.426419)
		(width 0.145)
		(layer "B.Cu")
		(net 25)
	)
	(segment
		(start 155.9 92.3)
		(end 155.9 94.1)
		(width 0.145)
		(layer "B.Cu")
		(net 25)
	)
	(segment
		(start 152.675 96.426419)
		(end 152.675 98.7)
		(width 0.145)
		(layer "B.Cu")
		(net 25)
	)
	(segment
		(start 152.500099 95.699901)
		(end 152.500099 96.251518)
		(width 0.145)
		(layer "B.Cu")
		(net 25)
	)
	(segment
		(start 157.6 90)
		(end 155.9 91.7)
		(width 0.1016)
		(layer "In2.Cu")
		(net 25)
	)
	(segment
		(start 157.6 86.025)
		(end 157.6 90)
		(width 0.1016)
		(layer "In2.Cu")
		(net 25)
	)
	(segment
		(start 155.9 91.7)
		(end 155.9 92.3)
		(width 0.1016)
		(layer "In2.Cu")
		(net 25)
	)
	(segment
		(start 154.825 83.25)
		(end 157.6 86.025)
		(width 0.1016)
		(layer "In2.Cu")
		(net 25)
	)
	(segment
		(start 154.1266 84.215444)
		(end 154.3008 84.389644)
		(width 0.1016)
		(layer "F.Cu")
		(net 26)
	)
	(segment
		(start 153.425 98.7)
		(end 153.425 96.824999)
		(width 0.1016)
		(layer "F.Cu")
		(net 26)
	)
	(segment
		(start 153.2766 96.676599)
		(end 153.2766 96.234149)
		(width 0.1016)
		(layer "F.Cu")
		(net 26)
	)
	(segment
		(start 153.425 96.824999)
		(end 153.2766 96.676599)
		(width 0.1016)
		(layer "F.Cu")
		(net 26)
	)
	(segment
		(start 154.425 83.65)
		(end 154.1266 83.9484)
		(width 0.1016)
		(layer "F.Cu")
		(net 26)
	)
	(segment
		(start 154.1266 83.9484)
		(end 154.1266 84.215444)
		(width 0.1016)
		(layer "F.Cu")
		(net 26)
	)
	(segment
		(start 153.2766 96.234149)
		(end 153.4508 96.059949)
		(width 0.1016)
		(layer "F.Cu")
		(net 26)
	)
	(via
		(at 153.4508 96.059949)
		(size 0.45)
		(drill 0.15)
		(layers "F.Cu" "B.Cu")
		(net 26)
	)
	(via
		(at 154.3008 84.389644)
		(size 0.45)
		(drill 0.15)
		(layers "F.Cu" "B.Cu")
		(net 26)
	)
	(segment
		(start 155.573375 93.525)
		(end 155.125 93.525)
		(width 0.1016)
		(layer "In2.Cu")
		(net 26)
	)
	(segment
		(start 153.4508 96.059949)
		(end 153.3508 95.959949)
		(width 0.1016)
		(layer "In2.Cu")
		(net 26)
	)
	(segment
		(start 155.678375 94.514769)
		(end 155.778109 94.47987)
		(width 0.1016)
		(layer "In2.Cu")
		(net 26)
	)
	(segment
		(start 155.998508 94.259471)
		(end 156.033407 94.159737)
		(width 0.1016)
		(layer "In2.Cu")
		(net 26)
	)
	(segment
		(start 156.033407 93.891862)
		(end 155.998508 93.792128)
		(width 0.1016)
		(layer "In2.Cu")
		(net 26)
	)
	(segment
		(start 155.867577 93.627945)
		(end 155.778109 93.571729)
		(width 0.1016)
		(layer "In2.Cu")
		(net 26)
	)
	(segment
		(start 154.97954 94.642599)
		(end 154.990575 94.611064)
		(width 0.1016)
		(layer "In2.Cu")
		(net 26)
	)
	(segment
		(start 155.031975 94.55915)
		(end 155.060264 94.541375)
		(width 0.1016)
		(layer "In2.Cu")
		(net 26)
	)
	(segment
		(start 155.031975 93.492449)
		(end 155.00835 93.468824)
		(width 0.1016)
		(layer "In2.Cu")
		(net 26)
	)
	(segment
		(start 155.125 93.525)
		(end 155.091799 93.521259)
		(width 0.1016)
		(layer "In2.Cu")
		(net 26)
	)
	(segment
		(start 155.942292 93.70266)
		(end 155.867577 93.627945)
		(width 0.1016)
		(layer "In2.Cu")
		(net 26)
	)
	(segment
		(start 154.9758 91.47282)
		(end 156.5758 89.87282)
		(width 0.1016)
		(layer "In2.Cu")
		(net 26)
	)
	(segment
		(start 153.3508 95.658045)
		(end 153.533045 95.4758)
		(width 0.1016)
		(layer "In2.Cu")
		(net 26)
	)
	(segment
		(start 155.678375 93.53683)
		(end 155.573375 93.525)
		(width 0.1016)
		(layer "In2.Cu")
		(net 26)
	)
	(segment
		(start 154.9758 94.6758)
		(end 154.97954 94.642599)
		(width 0.1016)
		(layer "In2.Cu")
		(net 26)
	)
	(segment
		(start 154.9758 94.97282)
		(end 154.9758 94.6758)
		(width 0.1016)
		(layer "In2.Cu")
		(net 26)
	)
	(segment
		(start 156.045238 94.054737)
		(end 156.045238 93.996862)
		(width 0.1016)
		(layer "In2.Cu")
		(net 26)
	)
	(segment
		(start 155.998508 93.792128)
		(end 155.942292 93.70266)
		(width 0.1016)
		(layer "In2.Cu")
		(net 26)
	)
	(segment
		(start 155.778109 93.571729)
		(end 155.678375 93.53683)
		(width 0.1016)
		(layer "In2.Cu")
		(net 26)
	)
	(segment
		(start 153.533045 95.4758)
		(end 154.47282 95.4758)
		(width 0.1016)
		(layer "In2.Cu")
		(net 26)
	)
	(segment
		(start 156.5758 89.87282)
		(end 156.5758 86.524781)
		(width 0.1016)
		(layer "In2.Cu")
		(net 26)
	)
	(segment
		(start 154.990575 93.440535)
		(end 154.97954 93.409)
		(width 0.1016)
		(layer "In2.Cu")
		(net 26)
	)
	(segment
		(start 155.00835 93.468824)
		(end 154.990575 93.440535)
		(width 0.1016)
		(layer "In2.Cu")
		(net 26)
	)
	(segment
		(start 154.2008 84.489644)
		(end 154.3008 84.389644)
		(width 0.1016)
		(layer "In2.Cu")
		(net 26)
	)
	(segment
		(start 156.045238 93.996862)
		(end 156.033407 93.891862)
		(width 0.1016)
		(layer "In2.Cu")
		(net 26)
	)
	(segment
		(start 155.091799 93.521259)
		(end 155.060264 93.510224)
		(width 0.1016)
		(layer "In2.Cu")
		(net 26)
	)
	(segment
		(start 155.867577 94.423654)
		(end 155.942292 94.348939)
		(width 0.1016)
		(layer "In2.Cu")
		(net 26)
	)
	(segment
		(start 154.990575 94.611064)
		(end 155.00835 94.582775)
		(width 0.1016)
		(layer "In2.Cu")
		(net 26)
	)
	(segment
		(start 154.47282 85.2242)
		(end 154.2008 84.95218)
		(width 0.1016)
		(layer "In2.Cu")
		(net 26)
	)
	(segment
		(start 154.47282 95.4758)
		(end 154.9758 94.97282)
		(width 0.1016)
		(layer "In2.Cu")
		(net 26)
	)
	(segment
		(start 154.2008 84.95218)
		(end 154.2008 84.489644)
		(width 0.1016)
		(layer "In2.Cu")
		(net 26)
	)
	(segment
		(start 155.125 94.5266)
		(end 155.573375 94.5266)
		(width 0.1016)
		(layer "In2.Cu")
		(net 26)
	)
	(segment
		(start 155.091799 94.53034)
		(end 155.125 94.5266)
		(width 0.1016)
		(layer "In2.Cu")
		(net 26)
	)
	(segment
		(start 155.060264 93.510224)
		(end 155.031975 93.492449)
		(width 0.1016)
		(layer "In2.Cu")
		(net 26)
	)
	(segment
		(start 155.060264 94.541375)
		(end 155.091799 94.53034)
		(width 0.1016)
		(layer "In2.Cu")
		(net 26)
	)
	(segment
		(start 155.00835 94.582775)
		(end 155.031975 94.55915)
		(width 0.1016)
		(layer "In2.Cu")
		(net 26)
	)
	(segment
		(start 153.3508 95.959949)
		(end 153.3508 95.658045)
		(width 0.1016)
		(layer "In2.Cu")
		(net 26)
	)
	(segment
		(start 155.942292 94.348939)
		(end 155.998508 94.259471)
		(width 0.1016)
		(layer "In2.Cu")
		(net 26)
	)
	(segment
		(start 154.97954 93.409)
		(end 154.9758 93.3758)
		(width 0.1016)
		(layer "In2.Cu")
		(net 26)
	)
	(segment
		(start 155.778109 94.47987)
		(end 155.867577 94.423654)
		(width 0.1016)
		(layer "In2.Cu")
		(net 26)
	)
	(segment
		(start 154.9758 93.3758)
		(end 154.9758 91.47282)
		(width 0.1016)
		(layer "In2.Cu")
		(net 26)
	)
	(segment
		(start 155.573375 94.5266)
		(end 155.678375 94.514769)
		(width 0.1016)
		(layer "In2.Cu")
		(net 26)
	)
	(segment
		(start 156.5758 86.524781)
		(end 155.275219 85.2242)
		(width 0.1016)
		(layer "In2.Cu")
		(net 26)
	)
	(segment
		(start 156.033407 94.159737)
		(end 156.045238 94.054737)
		(width 0.1016)
		(layer "In2.Cu")
		(net 26)
	)
	(segment
		(start 155.275219 85.2242)
		(end 154.47282 85.2242)
		(width 0.1016)
		(layer "In2.Cu")
		(net 26)
	)
	(segment
		(start 153.9234 84.215444)
		(end 153.7492 84.389644)
		(width 0.1016)
		(layer "F.Cu")
		(net 27)
	)
	(segment
		(start 153.0734 96.676599)
		(end 153.0734 96.234149)
		(width 0.1016)
		(layer "F.Cu")
		(net 27)
	)
	(segment
		(start 153.9234 83.9484)
		(end 153.9234 84.215444)
		(width 0.1016)
		(layer "F.Cu")
		(net 27)
	)
	(segment
		(start 153.0734 96.234149)
		(end 152.8992 96.059949)
		(width 0.1016)
		(layer "F.Cu")
		(net 27)
	)
	(segment
		(start 152.925 98.7)
		(end 152.925 96.824999)
		(width 0.1016)
		(layer "F.Cu")
		(net 27)
	)
	(segment
		(start 153.625 83.65)
		(end 153.9234 83.9484)
		(width 0.1016)
		(layer "F.Cu")
		(net 27)
	)
	(segment
		(start 152.925 96.824999)
		(end 153.0734 96.676599)
		(width 0.1016)
		(layer "F.Cu")
		(net 27)
	)
	(via
		(at 152.8992 96.059949)
		(size 0.45)
		(drill 0.15)
		(layers "F.Cu" "B.Cu")
		(net 27)
	)
	(via
		(at 153.7492 84.389644)
		(size 0.45)
		(drill 0.15)
		(layers "F.Cu" "B.Cu")
		(net 27)
	)
	(segment
		(start 156.2242 89.72718)
		(end 156.2242 86.670419)
		(width 0.1016)
		(layer "In2.Cu")
		(net 27)
	)
	(segment
		(start 152.9992 95.512405)
		(end 153.387405 95.1242)
		(width 0.1016)
		(layer "In2.Cu")
		(net 27)
	)
	(segment
		(start 154.727145 93.698939)
		(end 154.670929 93.609471)
		(width 0.1016)
		(layer "In2.Cu")
		(net 27)
	)
	(segment
		(start 155.544438 94.175)
		(end 155.577638 94.171259)
		(width 0.1016)
		(layer "In2.Cu")
		(net 27)
	)
	(segment
		(start 155.661087 94.118824)
		(end 155.678862 94.090535)
		(width 0.1016)
		(layer "In2.Cu")
		(net 27)
	)
	(segment
		(start 154.6242 91.32718)
		(end 156.2242 89.72718)
		(width 0.1016)
		(layer "In2.Cu")
		(net 27)
	)
	(segment
		(start 152.8992 96.059949)
		(end 152.9992 95.959949)
		(width 0.1016)
		(layer "In2.Cu")
		(net 27)
	)
	(segment
		(start 153.8492 84.489644)
		(end 153.7492 84.389644)
		(width 0.1016)
		(layer "In2.Cu")
		(net 27)
	)
	(segment
		(start 155.678862 93.961064)
		(end 155.661087 93.932775)
		(width 0.1016)
		(layer "In2.Cu")
		(net 27)
	)
	(segment
		(start 154.991062 93.864769)
		(end 154.891328 93.82987)
		(width 0.1016)
		(layer "In2.Cu")
		(net 27)
	)
	(segment
		(start 155.609173 94.160224)
		(end 155.637462 94.142449)
		(width 0.1016)
		(layer "In2.Cu")
		(net 27)
	)
	(segment
		(start 154.6242 94.82718)
		(end 154.6242 94.646862)
		(width 0.1016)
		(layer "In2.Cu")
		(net 27)
	)
	(segment
		(start 155.577638 93.88034)
		(end 155.544438 93.8766)
		(width 0.1016)
		(layer "In2.Cu")
		(net 27)
	)
	(segment
		(start 155.637462 93.90915)
		(end 155.609173 93.891375)
		(width 0.1016)
		(layer "In2.Cu")
		(net 27)
	)
	(segment
		(start 152.9992 95.959949)
		(end 152.9992 95.512405)
		(width 0.1016)
		(layer "In2.Cu")
		(net 27)
	)
	(segment
		(start 155.678862 94.090535)
		(end 155.689897 94.059)
		(width 0.1016)
		(layer "In2.Cu")
		(net 27)
	)
	(segment
		(start 154.6242 93.404737)
		(end 154.6242 91.32718)
		(width 0.1016)
		(layer "In2.Cu")
		(net 27)
	)
	(segment
		(start 154.32718 85.5758)
		(end 153.8492 85.09782)
		(width 0.1016)
		(layer "In2.Cu")
		(net 27)
	)
	(segment
		(start 155.637462 94.142449)
		(end 155.661087 94.118824)
		(width 0.1016)
		(layer "In2.Cu")
		(net 27)
	)
	(segment
		(start 155.609173 93.891375)
		(end 155.577638 93.88034)
		(width 0.1016)
		(layer "In2.Cu")
		(net 27)
	)
	(segment
		(start 154.727145 94.35266)
		(end 154.80186 94.277945)
		(width 0.1016)
		(layer "In2.Cu")
		(net 27)
	)
	(segment
		(start 155.129581 85.5758)
		(end 154.32718 85.5758)
		(width 0.1016)
		(layer "In2.Cu")
		(net 27)
	)
	(segment
		(start 155.096062 94.175)
		(end 155.544438 94.175)
		(width 0.1016)
		(layer "In2.Cu")
		(net 27)
	)
	(segment
		(start 154.80186 93.773654)
		(end 154.727145 93.698939)
		(width 0.1016)
		(layer "In2.Cu")
		(net 27)
	)
	(segment
		(start 154.63603 93.509737)
		(end 154.6242 93.404737)
		(width 0.1016)
		(layer "In2.Cu")
		(net 27)
	)
	(segment
		(start 154.991062 94.18683)
		(end 155.096062 94.175)
		(width 0.1016)
		(layer "In2.Cu")
		(net 27)
	)
	(segment
		(start 155.544438 93.8766)
		(end 155.096062 93.8766)
		(width 0.1016)
		(layer "In2.Cu")
		(net 27)
	)
	(segment
		(start 154.32718 95.1242)
		(end 154.6242 94.82718)
		(width 0.1016)
		(layer "In2.Cu")
		(net 27)
	)
	(segment
		(start 155.577638 94.171259)
		(end 155.609173 94.160224)
		(width 0.1016)
		(layer "In2.Cu")
		(net 27)
	)
	(segment
		(start 155.096062 93.8766)
		(end 154.991062 93.864769)
		(width 0.1016)
		(layer "In2.Cu")
		(net 27)
	)
	(segment
		(start 154.891328 94.221729)
		(end 154.991062 94.18683)
		(width 0.1016)
		(layer "In2.Cu")
		(net 27)
	)
	(segment
		(start 156.2242 86.670419)
		(end 155.129581 85.5758)
		(width 0.1016)
		(layer "In2.Cu")
		(net 27)
	)
	(segment
		(start 154.6242 94.646862)
		(end 154.63603 94.541862)
		(width 0.1016)
		(layer "In2.Cu")
		(net 27)
	)
	(segment
		(start 154.670929 93.609471)
		(end 154.63603 93.509737)
		(width 0.1016)
		(layer "In2.Cu")
		(net 27)
	)
	(segment
		(start 155.693638 94.0258)
		(end 155.689897 93.992599)
		(width 0.1016)
		(layer "In2.Cu")
		(net 27)
	)
	(segment
		(start 154.80186 94.277945)
		(end 154.891328 94.221729)
		(width 0.1016)
		(layer "In2.Cu")
		(net 27)
	)
	(segment
		(start 153.8492 85.09782)
		(end 153.8492 84.489644)
		(width 0.1016)
		(layer "In2.Cu")
		(net 27)
	)
	(segment
		(start 153.387405 95.1242)
		(end 154.32718 95.1242)
		(width 0.1016)
		(layer "In2.Cu")
		(net 27)
	)
	(segment
		(start 154.63603 94.541862)
		(end 154.670929 94.442128)
		(width 0.1016)
		(layer "In2.Cu")
		(net 27)
	)
	(segment
		(start 155.689897 94.059)
		(end 155.693638 94.0258)
		(width 0.1016)
		(layer "In2.Cu")
		(net 27)
	)
	(segment
		(start 154.670929 94.442128)
		(end 154.727145 94.35266)
		(width 0.1016)
		(layer "In2.Cu")
		(net 27)
	)
	(segment
		(start 154.891328 93.82987)
		(end 154.80186 93.773654)
		(width 0.1016)
		(layer "In2.Cu")
		(net 27)
	)
	(segment
		(start 155.661087 93.932775)
		(end 155.637462 93.90915)
		(width 0.1016)
		(layer "In2.Cu")
		(net 27)
	)
	(segment
		(start 155.689897 93.992599)
		(end 155.678862 93.961064)
		(width 0.1016)
		(layer "In2.Cu")
		(net 27)
	)
	(segment
		(start 152.825 86.85)
		(end 152.825 85.8)
		(width 0.145)
		(layer "F.Cu")
		(net 28)
	)
	(via
		(at 152.5 93.1)
		(size 0.45)
		(drill 0.15)
		(layers "F.Cu" "B.Cu")
		(net 28)
	)
	(via
		(at 152.825 85.8)
		(size 0.45)
		(drill 0.15)
		(layers "F.Cu" "B.Cu")
		(net 28)
	)
	(segment
		(start 152.23433 93.1)
		(end 148.675 96.65933)
		(width 0.145)
		(layer "B.Cu")
		(net 28)
	)
	(segment
		(start 152.5 93.1)
		(end 152.23433 93.1)
		(width 0.145)
		(layer "B.Cu")
		(net 28)
	)
	(segment
		(start 148.675 96.65933)
		(end 148.675 98.7)
		(width 0.145)
		(layer "B.Cu")
		(net 28)
	)
	(segment
		(start 152.802834 86.443053)
		(end 152.814938 86.462317)
		(width 0.1016)
		(layer "In2.Cu")
		(net 28)
	)
	(segment
		(start 152.807518 89.722938)
		(end 152.828992 89.730452)
		(width 0.1016)
		(layer "In2.Cu")
		(net 28)
	)
	(segment
		(start 152.788254 90.771165)
		(end 152.772166 90.787253)
		(width 0.1016)
		(layer "In2.Cu")
		(net 28)
	)
	(segment
		(start 152.8516 91.765)
		(end 152.9484 91.765)
		(width 0.1016)
		(layer "In2.Cu")
		(net 28)
	)
	(segment
		(start 153.047453 90.218391)
		(end 153.05 90.241)
		(width 0.1016)
		(layer "In2.Cu")
		(net 28)
	)
	(segment
		(start 153.027835 90.177653)
		(end 153.039939 90.196917)
		(width 0.1016)
		(layer "In2.Cu")
		(net 28)
	)
	(segment
		(start 152.828992 89.324052)
		(end 152.8516 89.3266)
		(width 0.1016)
		(layer "In2.Cu")
		(net 28)
	)
	(segment
		(start 152.825 88.990226)
		(end 152.75 89.065226)
		(width 0.1016)
		(layer "In2.Cu")
		(net 28)
	)
	(segment
		(start 152.992483 90.555861)
		(end 153.011747 90.567965)
		(width 0.1016)
		(layer "In2.Cu")
		(net 28)
	)
	(segment
		(start 152.9484 89.5298)
		(end 152.8516 89.5298)
		(width 0.1016)
		(layer "In2.Cu")
		(net 28)
	)
	(segment
		(start 152.760062 89.675482)
		(end 152.772166 89.694746)
		(width 0.1016)
		(layer "In2.Cu")
		(net 28)
	)
	(segment
		(start 152.828992 90.136852)
		(end 152.8516 90.1394)
		(width 0.1016)
		(layer "In2.Cu")
		(net 28)
	)
	(segment
		(start 153.027835 91.523546)
		(end 153.011747 91.539634)
		(width 0.1016)
		(layer "In2.Cu")
		(net 28)
	)
	(segment
		(start 153.047453 91.076408)
		(end 153.039939 91.097882)
		(width 0.1016)
		(layer "In2.Cu")
		(net 28)
	)
	(segment
		(start 153.039939 90.691482)
		(end 153.027835 90.710746)
		(width 0.1016)
		(layer "In2.Cu")
		(net 28)
	)
	(segment
		(start 152.992483 89.743061)
		(end 153.011747 89.755165)
		(width 0.1016)
		(layer "In2.Cu")
		(net 28)
	)
	(segment
		(start 153.05 91.0538)
		(end 153.047453 91.076408)
		(width 0.1016)
		(layer "In2.Cu")
		(net 28)
	)
	(segment
		(start 152.413647 86.808652)
		(end 152.436256 86.8112)
		(width 0.1016)
		(layer "In2.Cu")
		(net 28)
	)
	(segment
		(start 152.392173 86.211661)
		(end 152.372909 86.223765)
		(width 0.1016)
		(layer "In2.Cu")
		(net 28)
	)
	(segment
		(start 152.825 85.8)
		(end 152.825 86.1)
		(width 0.1016)
		(layer "In2.Cu")
		(net 28)
	)
	(segment
		(start 153.039939 91.097882)
		(end 153.027835 91.117146)
		(width 0.1016)
		(layer "In2.Cu")
		(net 28)
	)
	(segment
		(start 153.011747 89.348765)
		(end 153.027835 89.364853)
		(width 0.1016)
		(layer "In2.Cu")
		(net 28)
	)
	(segment
		(start 153.05 90.241)
		(end 153.047453 90.263608)
		(width 0.1016)
		(layer "In2.Cu")
		(net 28)
	)
	(segment
		(start 152.788254 91.742834)
		(end 152.807518 91.754938)
		(width 0.1016)
		(layer "In2.Cu")
		(net 28)
	)
	(segment
		(start 152.392173 86.618061)
		(end 152.372909 86.630165)
		(width 0.1016)
		(layer "In2.Cu")
		(net 28)
	)
	(segment
		(start 152.7234 86.4048)
		(end 152.746008 86.407347)
		(width 0.1016)
		(layer "In2.Cu")
		(net 28)
	)
	(segment
		(start 152.971009 90.340052)
		(end 152.9484 90.3426)
		(width 0.1016)
		(layer "In2.Cu")
		(net 28)
	)
	(segment
		(start 152.356821 86.366546)
		(end 152.372909 86.382634)
		(width 0.1016)
		(layer "In2.Cu")
		(net 28)
	)
	(segment
		(start 152.971009 90.141947)
		(end 152.992483 90.149461)
		(width 0.1016)
		(layer "In2.Cu")
		(net 28)
	)
	(segment
		(start 152.9484 91.765)
		(end 152.971009 91.767547)
		(width 0.1016)
		(layer "In2.Cu")
		(net 28)
	)
	(segment
		(start 152.807518 90.535738)
		(end 152.828992 90.543252)
		(width 0.1016)
		(layer "In2.Cu")
		(net 28)
	)
	(segment
		(start 152.802834 86.163346)
		(end 152.786746 86.179434)
		(width 0.1016)
		(layer "In2.Cu")
		(net 28)
	)
	(segment
		(start 152.971009 91.965652)
		(end 152.9484 91.9682)
		(width 0.1016)
		(layer "In2.Cu")
		(net 28)
	)
	(segment
		(start 153.039939 91.009717)
		(end 153.047453 91.031191)
		(width 0.1016)
		(layer "In2.Cu")
		(net 28)
	)
	(segment
		(start 152.971009 89.527252)
		(end 152.9484 89.5298)
		(width 0.1016)
		(layer "In2.Cu")
		(net 28)
	)
	(segment
		(start 152.344717 86.753682)
		(end 152.356821 86.772946)
		(width 0.1016)
		(layer "In2.Cu")
		(net 28)
	)
	(segment
		(start 152.752548 90.060408)
		(end 152.760062 90.081882)
		(width 0.1016)
		(layer "In2.Cu")
		(net 28)
	)
	(segment
		(start 153.027835 89.771253)
		(end 153.039939 89.790517)
		(width 0.1016)
		(layer "In2.Cu")
		(net 28)
	)
	(segment
		(start 152.752548 89.608791)
		(end 152.75 89.6314)
		(width 0.1016)
		(layer "In2.Cu")
		(net 28)
	)
	(segment
		(start 152.971009 91.559252)
		(end 152.9484 91.5618)
		(width 0.1016)
		(layer "In2.Cu")
		(net 28)
	)
	(segment
		(start 152.788254 91.583965)
		(end 152.772166 91.600053)
		(width 0.1016)
		(layer "In2.Cu")
		(net 28)
	)
	(segment
		(start 152.807518 90.129338)
		(end 152.828992 90.136852)
		(width 0.1016)
		(layer "In2.Cu")
		(net 28)
	)
	(segment
		(start 152.992483 89.336661)
		(end 153.011747 89.348765)
		(width 0.1016)
		(layer "In2.Cu")
		(net 28)
	)
	(segment
		(start 152.971009 91.152852)
		(end 152.9484 91.1554)
		(width 0.1016)
		(layer "In2.Cu")
		(net 28)
	)
	(segment
		(start 153.011747 89.914034)
		(end 152.992483 89.926138)
		(width 0.1016)
		(layer "In2.Cu")
		(net 28)
	)
	(segment
		(start 152.9484 91.1554)
		(end 152.8516 91.1554)
		(width 0.1016)
		(layer "In2.Cu")
		(net 28)
	)
	(segment
		(start 153.011747 91.787165)
		(end 153.027835 91.803253)
		(width 0.1016)
		(layer "In2.Cu")
		(net 28)
	)
	(segment
		(start 152.334656 86.3032)
		(end 152.337203 86.325808)
		(width 0.1016)
		(layer "In2.Cu")
		(net 28)
	)
	(segment
		(start 152.786746 86.585834)
		(end 152.767482 86.597938)
		(width 0.1016)
		(layer "In2.Cu")
		(net 28)
	)
	(segment
		(start 152.788254 89.958365)
		(end 152.772166 89.974453)
		(width 0.1016)
		(layer "In2.Cu")
		(net 28)
	)
	(segment
		(start 152.8516 90.1394)
		(end 152.9484 90.1394)
		(width 0.1016)
		(layer "In2.Cu")
		(net 28)
	)
	(segment
		(start 152.788254 91.177565)
		(end 152.772166 91.193653)
		(width 0.1016)
		(layer "In2.Cu")
		(net 28)
	)
	(segment
		(start 152.75 92.85)
		(end 152.5 93.1)
		(width 0.1016)
		(layer "In2.Cu")
		(net 28)
	)
	(segment
		(start 152.760062 91.707482)
		(end 152.772166 91.726746)
		(width 0.1016)
		(layer "In2.Cu")
		(net 28)
	)
	(segment
		(start 152.971009 90.548347)
		(end 152.992483 90.555861)
		(width 0.1016)
		(layer "In2.Cu")
		(net 28)
	)
	(segment
		(start 152.334656 86.7096)
		(end 152.337203 86.732208)
		(width 0.1016)
		(layer "In2.Cu")
		(net 28)
	)
	(segment
		(start 153.05 89.8346)
		(end 153.047453 89.857208)
		(width 0.1016)
		(layer "In2.Cu")
		(net 28)
	)
	(segment
		(start 152.8516 91.1554)
		(end 152.828992 91.157947)
		(width 0.1016)
		(layer "In2.Cu")
		(net 28)
	)
	(segment
		(start 152.772166 89.568053)
		(end 152.760062 89.587317)
		(width 0.1016)
		(layer "In2.Cu")
		(net 28)
	)
	(segment
		(start 152.7234 86.2016)
		(end 152.436256 86.2016)
		(width 0.1016)
		(layer "In2.Cu")
		(net 28)
	)
	(segment
		(start 152.75 90.8506)
		(end 152.752548 90.873208)
		(width 0.1016)
		(layer "In2.Cu")
		(net 28)
	)
	(segment
		(start 152.752548 89.247608)
		(end 152.760062 89.269082)
		(width 0.1016)
		(layer "In2.Cu")
		(net 28)
	)
	(segment
		(start 153.039939 91.416117)
		(end 153.047453 91.437591)
		(width 0.1016)
		(layer "In2.Cu")
		(net 28)
	)
	(segment
		(start 152.760062 90.400117)
		(end 152.752548 90.421591)
		(width 0.1016)
		(layer "In2.Cu")
		(net 28)
	)
	(segment
		(start 152.788254 91.990365)
		(end 152.772166 92.006453)
		(width 0.1016)
		(layer "In2.Cu")
		(net 28)
	)
	(segment
		(start 152.752548 89.654008)
		(end 152.760062 89.675482)
		(width 0.1016)
		(layer "In2.Cu")
		(net 28)
	)
	(segment
		(start 152.767482 86.821261)
		(end 152.786746 86.833365)
		(width 0.1016)
		(layer "In2.Cu")
		(net 28)
	)
	(segment
		(start 152.7234 86.608)
		(end 152.436256 86.608)
		(width 0.1016)
		(layer "In2.Cu")
		(net 28)
	)
	(segment
		(start 152.760062 91.619317)
		(end 152.752548 91.640791)
		(width 0.1016)
		(layer "In2.Cu")
		(net 28)
	)
	(segment
		(start 152.772166 90.101146)
		(end 152.788254 90.117234)
		(width 0.1016)
		(layer "In2.Cu")
		(net 28)
	)
	(segment
		(start 152.992483 89.519738)
		(end 152.971009 89.527252)
		(width 0.1016)
		(layer "In2.Cu")
		(net 28)
	)
	(segment
		(start 152.436256 86.8112)
		(end 152.7234 86.8112)
		(width 0.1016)
		(layer "In2.Cu")
		(net 28)
	)
	(segment
		(start 153.047453 89.811991)
		(end 153.05 89.8346)
		(width 0.1016)
		(layer "In2.Cu")
		(net 28)
	)
	(segment
		(start 153.011747 90.974365)
		(end 153.027835 90.990453)
		(width 0.1016)
		(layer "In2.Cu")
		(net 28)
	)
	(segment
		(start 153.027835 89.897946)
		(end 153.011747 89.914034)
		(width 0.1016)
		(layer "In2.Cu")
		(net 28)
	)
	(segment
		(start 153.039939 90.285082)
		(end 153.027835 90.304346)
		(width 0.1016)
		(layer "In2.Cu")
		(net 28)
	)
	(segment
		(start 152.8516 90.9522)
		(end 152.9484 90.9522)
		(width 0.1016)
		(layer "In2.Cu")
		(net 28)
	)
	(segment
		(start 152.8516 89.9362)
		(end 152.828992 89.938747)
		(width 0.1016)
		(layer "In2.Cu")
		(net 28)
	)
	(segment
		(start 152.746008 86.407347)
		(end 152.767482 86.414861)
		(width 0.1016)
		(layer "In2.Cu")
		(net 28)
	)
	(segment
		(start 152.786746 86.833365)
		(end 152.802834 86.849453)
		(width 0.1016)
		(layer "In2.Cu")
		(net 28)
	)
	(segment
		(start 152.344717 86.665517)
		(end 152.337203 86.686991)
		(width 0.1016)
		(layer "In2.Cu")
		(net 28)
	)
	(segment
		(start 153.047453 91.889208)
		(end 153.039939 91.910682)
		(width 0.1016)
		(layer "In2.Cu")
		(net 28)
	)
	(segment
		(start 152.992483 90.332538)
		(end 152.971009 90.340052)
		(width 0.1016)
		(layer "In2.Cu")
		(net 28)
	)
	(segment
		(start 153.047453 91.482808)
		(end 153.039939 91.504282)
		(width 0.1016)
		(layer "In2.Cu")
		(net 28)
	)
	(segment
		(start 152.752548 91.279608)
		(end 152.760062 91.301082)
		(width 0.1016)
		(layer "In2.Cu")
		(net 28)
	)
	(segment
		(start 152.746008 86.199052)
		(end 152.7234 86.2016)
		(width 0.1016)
		(layer "In2.Cu")
		(net 28)
	)
	(segment
		(start 152.807518 91.348538)
		(end 152.828992 91.356052)
		(width 0.1016)
		(layer "In2.Cu")
		(net 28)
	)
	(segment
		(start 152.971009 91.361147)
		(end 152.992483 91.368661)
		(width 0.1016)
		(layer "In2.Cu")
		(net 28)
	)
	(segment
		(start 152.807518 91.978261)
		(end 152.788254 91.990365)
		(width 0.1016)
		(layer "In2.Cu")
		(net 28)
	)
	(segment
		(start 152.828992 90.751547)
		(end 152.807518 90.759061)
		(width 0.1016)
		(layer "In2.Cu")
		(net 28)
	)
	(segment
		(start 152.971009 89.933652)
		(end 152.9484 89.9362)
		(width 0.1016)
		(layer "In2.Cu")
		(net 28)
	)
	(segment
		(start 153.047453 91.437591)
		(end 153.05 91.4602)
		(width 0.1016)
		(layer "In2.Cu")
		(net 28)
	)
	(segment
		(start 152.760062 91.212917)
		(end 152.752548 91.234391)
		(width 0.1016)
		(layer "In2.Cu")
		(net 28)
	)
	(segment
		(start 152.788254 90.364765)
		(end 152.772166 90.380853)
		(width 0.1016)
		(layer "In2.Cu")
		(net 28)
	)
	(segment
		(start 152.8516 90.5458)
		(end 152.9484 90.5458)
		(width 0.1016)
		(layer "In2.Cu")
		(net 28)
	)
	(segment
		(start 152.75 91.257)
		(end 152.752548 91.279608)
		(width 0.1016)
		(layer "In2.Cu")
		(net 28)
	)
	(segment
		(start 153.011747 91.133234)
		(end 152.992483 91.145338)
		(width 0.1016)
		(layer "In2.Cu")
		(net 28)
	)
	(segment
		(start 153.047453 91.031191)
		(end 153.05 91.0538)
		(width 0.1016)
		(layer "In2.Cu")
		(net 28)
	)
	(segment
		(start 152.7234 86.8112)
		(end 152.746008 86.813747)
		(width 0.1016)
		(layer "In2.Cu")
		(net 28)
	)
	(segment
		(start 153.027835 90.710746)
		(end 153.011747 90.726834)
		(width 0.1016)
		(layer "In2.Cu")
		(net 28)
	)
	(segment
		(start 153.011747 90.726834)
		(end 152.992483 90.738938)
		(width 0.1016)
		(layer "In2.Cu")
		(net 28)
	)
	(segment
		(start 152.788254 90.117234)
		(end 152.807518 90.129338)
		(width 0.1016)
		(layer "In2.Cu")
		(net 28)
	)
	(segment
		(start 153.011747 91.380765)
		(end 153.027835 91.396853)
		(width 0.1016)
		(layer "In2.Cu")
		(net 28)
	)
	(segment
		(start 152.788254 90.523634)
		(end 152.807518 90.535738)
		(width 0.1016)
		(layer "In2.Cu")
		(net 28)
	)
	(segment
		(start 153.039939 91.822517)
		(end 153.047453 91.843991)
		(width 0.1016)
		(layer "In2.Cu")
		(net 28)
	)
	(segment
		(start 153.039939 89.472282)
		(end 153.027835 89.491546)
		(width 0.1016)
		(layer "In2.Cu")
		(net 28)
	)
	(segment
		(start 152.75 89.065226)
		(end 152.75 89.225)
		(width 0.1016)
		(layer "In2.Cu")
		(net 28)
	)
	(segment
		(start 152.760062 89.587317)
		(end 152.752548 89.608791)
		(width 0.1016)
		(layer "In2.Cu")
		(net 28)
	)
	(segment
		(start 152.807518 89.539861)
		(end 152.788254 89.551965)
		(width 0.1016)
		(layer "In2.Cu")
		(net 28)
	)
	(segment
		(start 152.788254 89.304434)
		(end 152.807518 89.316538)
		(width 0.1016)
		(layer "In2.Cu")
		(net 28)
	)
	(segment
		(start 153.039939 89.878682)
		(end 153.027835 89.897946)
		(width 0.1016)
		(layer "In2.Cu")
		(net 28)
	)
	(segment
		(start 152.760062 91.301082)
		(end 152.772166 91.320346)
		(width 0.1016)
		(layer "In2.Cu")
		(net 28)
	)
	(segment
		(start 152.772166 91.193653)
		(end 152.760062 91.212917)
		(width 0.1016)
		(layer "In2.Cu")
		(net 28)
	)
	(segment
		(start 152.752548 90.421591)
		(end 152.75 90.4442)
		(width 0.1016)
		(layer "In2.Cu")
		(net 28)
	)
	(segment
		(start 153.027835 90.584053)
		(end 153.039939 90.603317)
		(width 0.1016)
		(layer "In2.Cu")
		(net 28)
	)
	(segment
		(start 152.356821 86.239853)
		(end 152.344717 86.259117)
		(width 0.1016)
		(layer "In2.Cu")
		(net 28)
	)
	(segment
		(start 152.828992 89.938747)
		(end 152.807518 89.946261)
		(width 0.1016)
		(layer "In2.Cu")
		(net 28)
	)
	(segment
		(start 152.807518 91.754938)
		(end 152.828992 91.762452)
		(width 0.1016)
		(layer "In2.Cu")
		(net 28)
	)
	(segment
		(start 153.039939 89.790517)
		(end 153.047453 89.811991)
		(width 0.1016)
		(layer "In2.Cu")
		(net 28)
	)
	(segment
		(start 152.372909 86.382634)
		(end 152.392173 86.394738)
		(width 0.1016)
		(layer "In2.Cu")
		(net 28)
	)
	(segment
		(start 152.828992 90.949652)
		(end 152.8516 90.9522)
		(width 0.1016)
		(layer "In2.Cu")
		(net 28)
	)
	(segment
		(start 152.992483 90.738938)
		(end 152.971009 90.746452)
		(width 0.1016)
		(layer "In2.Cu")
		(net 28)
	)
	(segment
		(start 152.436256 86.2016)
		(end 152.413647 86.204147)
		(width 0.1016)
		(layer "In2.Cu")
		(net 28)
	)
	(segment
		(start 152.802834 86.849453)
		(end 152.814938 86.868717)
		(width 0.1016)
		(layer "In2.Cu")
		(net 28)
	)
	(segment
		(start 153.027835 91.117146)
		(end 153.011747 91.133234)
		(width 0.1016)
		(layer "In2.Cu")
		(net 28)
	)
	(segment
		(start 153.027835 91.929946)
		(end 153.011747 91.946034)
		(width 0.1016)
		(layer "In2.Cu")
		(net 28)
	)
	(segment
		(start 152.971009 90.954747)
		(end 152.992483 90.962261)
		(width 0.1016)
		(layer "In2.Cu")
		(net 28)
	)
	(segment
		(start 152.8516 91.5618)
		(end 152.828992 91.564347)
		(width 0.1016)
		(layer "In2.Cu")
		(net 28)
	)
	(segment
		(start 152.825 86.1)
		(end 152.822452 86.122608)
		(width 0.1016)
		(layer "In2.Cu")
		(net 28)
	)
	(segment
		(start 152.9484 91.3586)
		(end 152.971009 91.361147)
		(width 0.1016)
		(layer "In2.Cu")
		(net 28)
	)
	(segment
		(start 152.392173 86.801138)
		(end 152.413647 86.808652)
		(width 0.1016)
		(layer "In2.Cu")
		(net 28)
	)
	(segment
		(start 152.822452 86.122608)
		(end 152.814938 86.144082)
		(width 0.1016)
		(layer "In2.Cu")
		(net 28)
	)
	(segment
		(start 153.047453 89.857208)
		(end 153.039939 89.878682)
		(width 0.1016)
		(layer "In2.Cu")
		(net 28)
	)
	(segment
		(start 153.011747 90.161565)
		(end 153.027835 90.177653)
		(width 0.1016)
		(layer "In2.Cu")
		(net 28)
	)
	(segment
		(start 152.9484 90.3426)
		(end 152.8516 90.3426)
		(width 0.1016)
		(layer "In2.Cu")
		(net 28)
	)
	(segment
		(start 153.039939 90.603317)
		(end 153.047453 90.624791)
		(width 0.1016)
		(layer "In2.Cu")
		(net 28)
	)
	(segment
		(start 152.828992 91.157947)
		(end 152.807518 91.165461)
		(width 0.1016)
		(layer "In2.Cu")
		(net 28)
	)
	(segment
		(start 152.337203 86.325808)
		(end 152.344717 86.347282)
		(width 0.1016)
		(layer "In2.Cu")
		(net 28)
	)
	(segment
		(start 153.011747 89.755165)
		(end 153.027835 89.771253)
		(width 0.1016)
		(layer "In2.Cu")
		(net 28)
	)
	(segment
		(start 153.027835 91.396853)
		(end 153.039939 91.416117)
		(width 0.1016)
		(layer "In2.Cu")
		(net 28)
	)
	(segment
		(start 152.992483 91.958138)
		(end 152.971009 91.965652)
		(width 0.1016)
		(layer "In2.Cu")
		(net 28)
	)
	(segment
		(start 152.372909 86.789034)
		(end 152.392173 86.801138)
		(width 0.1016)
		(layer "In2.Cu")
		(net 28)
	)
	(segment
		(start 153.027835 89.491546)
		(end 153.011747 89.507634)
		(width 0.1016)
		(layer "In2.Cu")
		(net 28)
	)
	(segment
		(start 152.992483 91.551738)
		(end 152.971009 91.559252)
		(width 0.1016)
		(layer "In2.Cu")
		(net 28)
	)
	(segment
		(start 152.752548 90.873208)
		(end 152.760062 90.894682)
		(width 0.1016)
		(layer "In2.Cu")
		(net 28)
	)
	(segment
		(start 152.75 91.6634)
		(end 152.752548 91.686008)
		(width 0.1016)
		(layer "In2.Cu")
		(net 28)
	)
	(segment
		(start 152.760062 90.488282)
		(end 152.772166 90.507546)
		(width 0.1016)
		(layer "In2.Cu")
		(net 28)
	)
	(segment
		(start 152.992483 91.145338)
		(end 152.971009 91.152852)
		(width 0.1016)
		(layer "In2.Cu")
		(net 28)
	)
	(segment
		(start 152.807518 90.352661)
		(end 152.788254 90.364765)
		(width 0.1016)
		(layer "In2.Cu")
		(net 28)
	)
	(segment
		(start 152.356821 86.646253)
		(end 152.344717 86.665517)
		(width 0.1016)
		(layer "In2.Cu")
		(net 28)
	)
	(segment
		(start 152.807518 89.316538)
		(end 152.828992 89.324052)
		(width 0.1016)
		(layer "In2.Cu")
		(net 28)
	)
	(segment
		(start 152.356821 86.772946)
		(end 152.372909 86.789034)
		(width 0.1016)
		(layer "In2.Cu")
		(net 28)
	)
	(segment
		(start 152.760062 90.081882)
		(end 152.772166 90.101146)
		(width 0.1016)
		(layer "In2.Cu")
		(net 28)
	)
	(segment
		(start 152.8516 89.5298)
		(end 152.828992 89.532347)
		(width 0.1016)
		(layer "In2.Cu")
		(net 28)
	)
	(segment
		(start 153.05 91.4602)
		(end 153.047453 91.482808)
		(width 0.1016)
		(layer "In2.Cu")
		(net 28)
	)
	(segment
		(start 152.992483 90.149461)
		(end 153.011747 90.161565)
		(width 0.1016)
		(layer "In2.Cu")
		(net 28)
	)
	(segment
		(start 152.772166 90.787253)
		(end 152.760062 90.806517)
		(width 0.1016)
		(layer "In2.Cu")
		(net 28)
	)
	(segment
		(start 152.337203 86.686991)
		(end 152.334656 86.7096)
		(width 0.1016)
		(layer "In2.Cu")
		(net 28)
	)
	(segment
		(start 152.344717 86.347282)
		(end 152.356821 86.366546)
		(width 0.1016)
		(layer "In2.Cu")
		(net 28)
	)
	(segment
		(start 152.75 90.0378)
		(end 152.752548 90.060408)
		(width 0.1016)
		(layer "In2.Cu")
		(net 28)
	)
	(segment
		(start 152.992483 89.926138)
		(end 152.971009 89.933652)
		(width 0.1016)
		(layer "In2.Cu")
		(net 28)
	)
	(segment
		(start 153.047453 90.670008)
		(end 153.039939 90.691482)
		(width 0.1016)
		(layer "In2.Cu")
		(net 28)
	)
	(segment
		(start 152.9484 90.9522)
		(end 152.971009 90.954747)
		(width 0.1016)
		(layer "In2.Cu")
		(net 28)
	)
	(segment
		(start 153.011747 89.507634)
		(end 152.992483 89.519738)
		(width 0.1016)
		(layer "In2.Cu")
		(net 28)
	)
	(segment
		(start 152.788254 91.336434)
		(end 152.807518 91.348538)
		(width 0.1016)
		(layer "In2.Cu")
		(net 28)
	)
	(segment
		(start 153.05 89.4282)
		(end 153.047453 89.450808)
		(width 0.1016)
		(layer "In2.Cu")
		(net 28)
	)
	(segment
		(start 153.047453 89.450808)
		(end 153.039939 89.472282)
		(width 0.1016)
		(layer "In2.Cu")
		(net 28)
	)
	(segment
		(start 152.807518 89.946261)
		(end 152.788254 89.958365)
		(width 0.1016)
		(layer "In2.Cu")
		(net 28)
	)
	(segment
		(start 153.039939 89.384117)
		(end 153.047453 89.405591)
		(width 0.1016)
		(layer "In2.Cu")
		(net 28)
	)
	(segment
		(start 152.760062 90.806517)
		(end 152.752548 90.827991)
		(width 0.1016)
		(layer "In2.Cu")
		(net 28)
	)
	(segment
		(start 152.8516 89.733)
		(end 152.9484 89.733)
		(width 0.1016)
		(layer "In2.Cu")
		(net 28)
	)
	(segment
		(start 152.760062 90.894682)
		(end 152.772166 90.913946)
		(width 0.1016)
		(layer "In2.Cu")
		(net 28)
	)
	(segment
		(start 153.027835 90.990453)
		(end 153.039939 91.009717)
		(width 0.1016)
		(layer "In2.Cu")
		(net 28)
	)
	(segment
		(start 152.822452 86.483791)
		(end 152.825 86.5064)
		(width 0.1016)
		(layer "In2.Cu")
		(net 28)
	)
	(segment
		(start 152.75 89.225)
		(end 152.752548 89.247608)
		(width 0.1016)
		(layer "In2.Cu")
		(net 28)
	)
	(segment
		(start 152.772166 91.600053)
		(end 152.760062 91.619317)
		(width 0.1016)
		(layer "In2.Cu")
		(net 28)
	)
	(segment
		(start 152.788254 89.551965)
		(end 152.772166 89.568053)
		(width 0.1016)
		(layer "In2.Cu")
		(net 28)
	)
	(segment
		(start 152.772166 92.006453)
		(end 152.760062 92.025717)
		(width 0.1016)
		(layer "In2.Cu")
		(net 28)
	)
	(segment
		(start 152.807518 91.571861)
		(end 152.788254 91.583965)
		(width 0.1016)
		(layer "In2.Cu")
		(net 28)
	)
	(segment
		(start 152.802834 86.569746)
		(end 152.786746 86.585834)
		(width 0.1016)
		(layer "In2.Cu")
		(net 28)
	)
	(segment
		(start 153.011747 91.539634)
		(end 152.992483 91.551738)
		(width 0.1016)
		(layer "In2.Cu")
		(net 28)
	)
	(segment
		(start 152.772166 91.726746)
		(end 152.788254 91.742834)
		(width 0.1016)
		(layer "In2.Cu")
		(net 28)
	)
	(segment
		(start 152.752548 90.466808)
		(end 152.760062 90.488282)
		(width 0.1016)
		(layer "In2.Cu")
		(net 28)
	)
	(segment
		(start 152.828992 91.762452)
		(end 152.8516 91.765)
		(width 0.1016)
		(layer "In2.Cu")
		(net 28)
	)
	(segment
		(start 152.825 86.9128)
		(end 152.825 88.990226)
		(width 0.1016)
		(layer "In2.Cu")
		(net 28)
	)
	(segment
		(start 152.772166 90.913946)
		(end 152.788254 90.930034)
		(width 0.1016)
		(layer "In2.Cu")
		(net 28)
	)
	(segment
		(start 152.786746 86.426965)
		(end 152.802834 86.443053)
		(width 0.1016)
		(layer "In2.Cu")
		(net 28)
	)
	(segment
		(start 152.8516 90.749)
		(end 152.828992 90.751547)
		(width 0.1016)
		(layer "In2.Cu")
		(net 28)
	)
	(segment
		(start 152.814938 86.144082)
		(end 152.802834 86.163346)
		(width 0.1016)
		(layer "In2.Cu")
		(net 28)
	)
	(segment
		(start 152.814938 86.462317)
		(end 152.822452 86.483791)
		(width 0.1016)
		(layer "In2.Cu")
		(net 28)
	)
	(segment
		(start 152.752548 91.686008)
		(end 152.760062 91.707482)
		(width 0.1016)
		(layer "In2.Cu")
		(net 28)
	)
	(segment
		(start 152.828992 89.730452)
		(end 152.8516 89.733)
		(width 0.1016)
		(layer "In2.Cu")
		(net 28)
	)
	(segment
		(start 152.828992 91.564347)
		(end 152.807518 91.571861)
		(width 0.1016)
		(layer "In2.Cu")
		(net 28)
	)
	(segment
		(start 152.992483 90.962261)
		(end 153.011747 90.974365)
		(width 0.1016)
		(layer "In2.Cu")
		(net 28)
	)
	(segment
		(start 152.992483 91.368661)
		(end 153.011747 91.380765)
		(width 0.1016)
		(layer "In2.Cu")
		(net 28)
	)
	(segment
		(start 152.8516 89.3266)
		(end 152.9484 89.3266)
		(width 0.1016)
		(layer "In2.Cu")
		(net 28)
	)
	(segment
		(start 153.039939 91.504282)
		(end 153.027835 91.523546)
		(width 0.1016)
		(layer "In2.Cu")
		(net 28)
	)
	(segment
		(start 152.337203 86.280591)
		(end 152.334656 86.3032)
		(width 0.1016)
		(layer "In2.Cu")
		(net 28)
	)
	(segment
		(start 152.9484 91.9682)
		(end 152.8516 91.9682)
		(width 0.1016)
		(layer "In2.Cu")
		(net 28)
	)
	(segment
		(start 152.814938 86.550482)
		(end 152.802834 86.569746)
		(width 0.1016)
		(layer "In2.Cu")
		(net 28)
	)
	(segment
		(start 152.372909 86.630165)
		(end 152.356821 86.646253)
		(width 0.1016)
		(layer "In2.Cu")
		(net 28)
	)
	(segment
		(start 152.822452 86.529008)
		(end 152.814938 86.550482)
		(width 0.1016)
		(layer "In2.Cu")
		(net 28)
	)
	(segment
		(start 152.828992 90.345147)
		(end 152.807518 90.352661)
		(width 0.1016)
		(layer "In2.Cu")
		(net 28)
	)
	(segment
		(start 152.413647 86.204147)
		(end 152.392173 86.211661)
		(width 0.1016)
		(layer "In2.Cu")
		(net 28)
	)
	(segment
		(start 152.8516 90.3426)
		(end 152.828992 90.345147)
		(width 0.1016)
		(layer "In2.Cu")
		(net 28)
	)
	(segment
		(start 152.971009 89.329147)
		(end 152.992483 89.336661)
		(width 0.1016)
		(layer "In2.Cu")
		(net 28)
	)
	(segment
		(start 152.752548 91.234391)
		(end 152.75 91.257)
		(width 0.1016)
		(layer "In2.Cu")
		(net 28)
	)
	(segment
		(start 153.011747 91.946034)
		(end 152.992483 91.958138)
		(width 0.1016)
		(layer "In2.Cu")
		(net 28)
	)
	(segment
		(start 152.825 86.5064)
		(end 152.822452 86.529008)
		(width 0.1016)
		(layer "In2.Cu")
		(net 28)
	)
	(segment
		(start 152.772166 89.288346)
		(end 152.788254 89.304434)
		(width 0.1016)
		(layer "In2.Cu")
		(net 28)
	)
	(segment
		(start 153.047453 91.843991)
		(end 153.05 91.8666)
		(width 0.1016)
		(layer "In2.Cu")
		(net 28)
	)
	(segment
		(start 153.027835 89.364853)
		(end 153.039939 89.384117)
		(width 0.1016)
		(layer "In2.Cu")
		(net 28)
	)
	(segment
		(start 153.039939 91.910682)
		(end 153.027835 91.929946)
		(width 0.1016)
		(layer "In2.Cu")
		(net 28)
	)
	(segment
		(start 152.9484 90.5458)
		(end 152.971009 90.548347)
		(width 0.1016)
		(layer "In2.Cu")
		(net 28)
	)
	(segment
		(start 152.760062 89.269082)
		(end 152.772166 89.288346)
		(width 0.1016)
		(layer "In2.Cu")
		(net 28)
	)
	(segment
		(start 152.9484 89.733)
		(end 152.971009 89.735547)
		(width 0.1016)
		(layer "In2.Cu")
		(net 28)
	)
	(segment
		(start 152.971009 90.746452)
		(end 152.9484 90.749)
		(width 0.1016)
		(layer "In2.Cu")
		(net 28)
	)
	(segment
		(start 152.772166 89.694746)
		(end 152.788254 89.710834)
		(width 0.1016)
		(layer "In2.Cu")
		(net 28)
	)
	(segment
		(start 152.344717 86.259117)
		(end 152.337203 86.280591)
		(width 0.1016)
		(layer "In2.Cu")
		(net 28)
	)
	(segment
		(start 152.436256 86.608)
		(end 152.413647 86.610547)
		(width 0.1016)
		(layer "In2.Cu")
		(net 28)
	)
	(segment
		(start 152.752548 90.015191)
		(end 152.75 90.0378)
		(width 0.1016)
		(layer "In2.Cu")
		(net 28)
	)
	(segment
		(start 152.786746 86.179434)
		(end 152.767482 86.191538)
		(width 0.1016)
		(layer "In2.Cu")
		(net 28)
	)
	(segment
		(start 152.767482 86.597938)
		(end 152.746008 86.605452)
		(width 0.1016)
		(layer "In2.Cu")
		(net 28)
	)
	(segment
		(start 152.75 92.0698)
		(end 152.75 92.85)
		(width 0.1016)
		(layer "In2.Cu")
		(net 28)
	)
	(segment
		(start 152.392173 86.394738)
		(end 152.413647 86.402252)
		(width 0.1016)
		(layer "In2.Cu")
		(net 28)
	)
	(segment
		(start 152.9484 91.5618)
		(end 152.8516 91.5618)
		(width 0.1016)
		(layer "In2.Cu")
		(net 28)
	)
	(segment
		(start 152.752548 91.640791)
		(end 152.75 91.6634)
		(width 0.1016)
		(layer "In2.Cu")
		(net 28)
	)
	(segment
		(start 152.788254 90.930034)
		(end 152.807518 90.942138)
		(width 0.1016)
		(layer "In2.Cu")
		(net 28)
	)
	(segment
		(start 153.05 90.6474)
		(end 153.047453 90.670008)
		(width 0.1016)
		(layer "In2.Cu")
		(net 28)
	)
	(segment
		(start 153.047453 90.263608)
		(end 153.039939 90.285082)
		(width 0.1016)
		(layer "In2.Cu")
		(net 28)
	)
	(segment
		(start 152.760062 92.025717)
		(end 152.752548 92.047191)
		(width 0.1016)
		(layer "In2.Cu")
		(net 28)
	)
	(segment
		(start 153.011747 90.567965)
		(end 153.027835 90.584053)
		(width 0.1016)
		(layer "In2.Cu")
		(net 28)
	)
	(segment
		(start 152.413647 86.610547)
		(end 152.392173 86.618061)
		(width 0.1016)
		(layer "In2.Cu")
		(net 28)
	)
	(segment
		(start 153.011747 90.320434)
		(end 152.992483 90.332538)
		(width 0.1016)
		(layer "In2.Cu")
		(net 28)
	)
	(segment
		(start 152.752548 92.047191)
		(end 152.75 92.0698)
		(width 0.1016)
		(layer "In2.Cu")
		(net 28)
	)
	(segment
		(start 152.9484 89.9362)
		(end 152.8516 89.9362)
		(width 0.1016)
		(layer "In2.Cu")
		(net 28)
	)
	(segment
		(start 152.413647 86.402252)
		(end 152.436256 86.4048)
		(width 0.1016)
		(layer "In2.Cu")
		(net 28)
	)
	(segment
		(start 153.027835 91.803253)
		(end 153.039939 91.822517)
		(width 0.1016)
		(layer "In2.Cu")
		(net 28)
	)
	(segment
		(start 152.828992 90.543252)
		(end 152.8516 90.5458)
		(width 0.1016)
		(layer "In2.Cu")
		(net 28)
	)
	(segment
		(start 152.436256 86.4048)
		(end 152.7234 86.4048)
		(width 0.1016)
		(layer "In2.Cu")
		(net 28)
	)
	(segment
		(start 152.8516 91.9682)
		(end 152.828992 91.970747)
		(width 0.1016)
		(layer "In2.Cu")
		(net 28)
	)
	(segment
		(start 152.75 90.4442)
		(end 152.752548 90.466808)
		(width 0.1016)
		(layer "In2.Cu")
		(net 28)
	)
	(segment
		(start 152.971009 89.735547)
		(end 152.992483 89.743061)
		(width 0.1016)
		(layer "In2.Cu")
		(net 28)
	)
	(segment
		(start 152.807518 91.165461)
		(end 152.788254 91.177565)
		(width 0.1016)
		(layer "In2.Cu")
		(net 28)
	)
	(segment
		(start 152.772166 90.507546)
		(end 152.788254 90.523634)
		(width 0.1016)
		(layer "In2.Cu")
		(net 28)
	)
	(segment
		(start 152.752548 90.827991)
		(end 152.75 90.8506)
		(width 0.1016)
		(layer "In2.Cu")
		(net 28)
	)
	(segment
		(start 153.027835 90.304346)
		(end 153.011747 90.320434)
		(width 0.1016)
		(layer "In2.Cu")
		(net 28)
	)
	(segment
		(start 152.746008 86.813747)
		(end 152.767482 86.821261)
		(width 0.1016)
		(layer "In2.Cu")
		(net 28)
	)
	(segment
		(start 152.767482 86.191538)
		(end 152.746008 86.199052)
		(width 0.1016)
		(layer "In2.Cu")
		(net 28)
	)
	(segment
		(start 152.772166 89.974453)
		(end 152.760062 89.993717)
		(width 0.1016)
		(layer "In2.Cu")
		(net 28)
	)
	(segment
		(start 152.788254 89.710834)
		(end 152.807518 89.722938)
		(width 0.1016)
		(layer "In2.Cu")
		(net 28)
	)
	(segment
		(start 152.760062 89.993717)
		(end 152.752548 90.015191)
		(width 0.1016)
		(layer "In2.Cu")
		(net 28)
	)
	(segment
		(start 152.337203 86.732208)
		(end 152.344717 86.753682)
		(width 0.1016)
		(layer "In2.Cu")
		(net 28)
	)
	(segment
		(start 152.992483 91.775061)
		(end 153.011747 91.787165)
		(width 0.1016)
		(layer "In2.Cu")
		(net 28)
	)
	(segment
		(start 152.75 89.6314)
		(end 152.752548 89.654008)
		(width 0.1016)
		(layer "In2.Cu")
		(net 28)
	)
	(segment
		(start 152.8516 91.3586)
		(end 152.9484 91.3586)
		(width 0.1016)
		(layer "In2.Cu")
		(net 28)
	)
	(segment
		(start 152.9484 90.749)
		(end 152.8516 90.749)
		(width 0.1016)
		(layer "In2.Cu")
		(net 28)
	)
	(segment
		(start 152.814938 86.868717)
		(end 152.822452 86.890191)
		(width 0.1016)
		(layer "In2.Cu")
		(net 28)
	)
	(segment
		(start 152.828992 89.532347)
		(end 152.807518 89.539861)
		(width 0.1016)
		(layer "In2.Cu")
		(net 28)
	)
	(segment
		(start 153.05 91.8666)
		(end 153.047453 91.889208)
		(width 0.1016)
		(layer "In2.Cu")
		(net 28)
	)
	(segment
		(start 153.047453 90.624791)
		(end 153.05 90.6474)
		(width 0.1016)
		(layer "In2.Cu")
		(net 28)
	)
	(segment
		(start 152.971009 91.767547)
		(end 152.992483 91.775061)
		(width 0.1016)
		(layer "In2.Cu")
		(net 28)
	)
	(segment
		(start 152.772166 91.320346)
		(end 152.788254 91.336434)
		(width 0.1016)
		(layer "In2.Cu")
		(net 28)
	)
	(segment
		(start 152.767482 86.414861)
		(end 152.786746 86.426965)
		(width 0.1016)
		(layer "In2.Cu")
		(net 28)
	)
	(segment
		(start 152.9484 89.3266)
		(end 152.971009 89.329147)
		(width 0.1016)
		(layer "In2.Cu")
		(net 28)
	)
	(segment
		(start 152.746008 86.605452)
		(end 152.7234 86.608)
		(width 0.1016)
		(layer "In2.Cu")
		(net 28)
	)
	(segment
		(start 152.807518 90.759061)
		(end 152.788254 90.771165)
		(width 0.1016)
		(layer "In2.Cu")
		(net 28)
	)
	(segment
		(start 152.772166 90.380853)
		(end 152.760062 90.400117)
		(width 0.1016)
		(layer "In2.Cu")
		(net 28)
	)
	(segment
		(start 152.807518 90.942138)
		(end 152.828992 90.949652)
		(width 0.1016)
		(layer "In2.Cu")
		(net 28)
	)
	(segment
		(start 152.828992 91.356052)
		(end 152.8516 91.3586)
		(width 0.1016)
		(layer "In2.Cu")
		(net 28)
	)
	(segment
		(start 152.372909 86.223765)
		(end 152.356821 86.239853)
		(width 0.1016)
		(layer "In2.Cu")
		(net 28)
	)
	(segment
		(start 152.822452 86.890191)
		(end 152.825 86.9128)
		(width 0.1016)
		(layer "In2.Cu")
		(net 28)
	)
	(segment
		(start 152.9484 90.1394)
		(end 152.971009 90.141947)
		(width 0.1016)
		(layer "In2.Cu")
		(net 28)
	)
	(segment
		(start 152.828992 91.970747)
		(end 152.807518 91.978261)
		(width 0.1016)
		(layer "In2.Cu")
		(net 28)
	)
	(segment
		(start 153.039939 90.196917)
		(end 153.047453 90.218391)
		(width 0.1016)
		(layer "In2.Cu")
		(net 28)
	)
	(segment
		(start 153.047453 89.405591)
		(end 153.05 89.4282)
		(width 0.1016)
		(layer "In2.Cu")
		(net 28)
	)
	(segment
		(start 152.825 83.65)
		(end 152.825 84.21)
		(width 0.145)
		(layer "F.Cu")
		(net 29)
	)
	(via
		(at 151.2 92.9)
		(size 0.45)
		(drill 0.15)
		(layers "F.Cu" "B.Cu")
		(net 29)
	)
	(via
		(at 152.825 84.21)
		(size 0.45)
		(drill 0.15)
		(layers "F.Cu" "B.Cu")
		(net 29)
	)
	(segment
		(start 147.675 97.09067)
		(end 147.675 98.7)
		(width 0.145)
		(layer "B.Cu")
		(net 29)
	)
	(segment
		(start 151.2 92.9)
		(end 147.9 96.2)
		(width 0.145)
		(layer "B.Cu")
		(net 29)
	)
	(segment
		(start 147.9 96.86567)
		(end 147.675 97.09067)
		(width 0.145)
		(layer "B.Cu")
		(net 29)
	)
	(segment
		(start 147.9 96.2)
		(end 147.9 96.86567)
		(width 0.145)
		(layer "B.Cu")
		(net 29)
	)
	(segment
		(start 151.695781 89.572946)
		(end 151.679693 89.589034)
		(width 0.1016)
		(layer "In2.Cu")
		(net 29)
	)
	(segment
		(start 151.679693 89.023765)
		(end 151.695781 89.039853)
		(width 0.1016)
		(layer "In2.Cu")
		(net 29)
	)
	(segment
		(start 151.717946 89.1032)
		(end 151.715399 89.125808)
		(width 0.1016)
		(layer "In2.Cu")
		(net 29)
	)
	(segment
		(start 151.422166 90.995346)
		(end 151.438254 91.011434)
		(width 0.1016)
		(layer "In2.Cu")
		(net 29)
	)
	(segment
		(start 151.638955 89.202252)
		(end 151.616346 89.2048)
		(width 0.1016)
		(layer "In2.Cu")
		(net 29)
	)
	(segment
		(start 151.660429 90.230861)
		(end 151.679693 90.242965)
		(width 0.1016)
		(layer "In2.Cu")
		(net 29)
	)
	(segment
		(start 151.660429 89.194738)
		(end 151.638955 89.202252)
		(width 0.1016)
		(layer "In2.Cu")
		(net 29)
	)
	(segment
		(start 151.695781 89.979346)
		(end 151.679693 89.995434)
		(width 0.1016)
		(layer "In2.Cu")
		(net 29)
	)
	(segment
		(start 151.638955 90.827852)
		(end 151.616346 90.8304)
		(width 0.1016)
		(layer "In2.Cu")
		(net 29)
	)
	(segment
		(start 151.422166 91.401746)
		(end 151.438254 91.417834)
		(width 0.1016)
		(layer "In2.Cu")
		(net 29)
	)
	(segment
		(start 151.660429 89.601138)
		(end 151.638955 89.608652)
		(width 0.1016)
		(layer "In2.Cu")
		(net 29)
	)
	(segment
		(start 151.707885 91.497517)
		(end 151.715399 91.518991)
		(width 0.1016)
		(layer "In2.Cu")
		(net 29)
	)
	(segment
		(start 151.438254 89.385834)
		(end 151.457518 89.397938)
		(width 0.1016)
		(layer "In2.Cu")
		(net 29)
	)
	(segment
		(start 151.695781 89.039853)
		(end 151.707885 89.059117)
		(width 0.1016)
		(layer "In2.Cu")
		(net 29)
	)
	(segment
		(start 151.679693 90.808234)
		(end 151.660429 90.820338)
		(width 0.1016)
		(layer "In2.Cu")
		(net 29)
	)
	(segment
		(start 151.679693 89.182634)
		(end 151.660429 89.194738)
		(width 0.1016)
		(layer "In2.Cu")
		(net 29)
	)
	(segment
		(start 151.616346 90.8304)
		(end 151.5016 90.8304)
		(width 0.1016)
		(layer "In2.Cu")
		(net 29)
	)
	(segment
		(start 151.457518 89.804338)
		(end 151.478992 89.811852)
		(width 0.1016)
		(layer "In2.Cu")
		(net 29)
	)
	(segment
		(start 151.4 91.7448)
		(end 151.4 92.7)
		(width 0.1016)
		(layer "In2.Cu")
		(net 29)
	)
	(segment
		(start 151.4 90.5256)
		(end 151.402548 90.548208)
		(width 0.1016)
		(layer "In2.Cu")
		(net 29)
	)
	(segment
		(start 151.616346 89.8144)
		(end 151.638955 89.816947)
		(width 0.1016)
		(layer "In2.Cu")
		(net 29)
	)
	(segment
		(start 151.410062 91.700717)
		(end 151.402548 91.722191)
		(width 0.1016)
		(layer "In2.Cu")
		(net 29)
	)
	(segment
		(start 151.660429 91.226738)
		(end 151.638955 91.234252)
		(width 0.1016)
		(layer "In2.Cu")
		(net 29)
	)
	(segment
		(start 151.679693 91.462165)
		(end 151.695781 91.478253)
		(width 0.1016)
		(layer "In2.Cu")
		(net 29)
	)
	(segment
		(start 151.422166 91.681453)
		(end 151.410062 91.700717)
		(width 0.1016)
		(layer "In2.Cu")
		(net 29)
	)
	(segment
		(start 151.457518 90.840461)
		(end 151.438254 90.852565)
		(width 0.1016)
		(layer "In2.Cu")
		(net 29)
	)
	(segment
		(start 151.457518 89.621261)
		(end 151.438254 89.633365)
		(width 0.1016)
		(layer "In2.Cu")
		(net 29)
	)
	(segment
		(start 151.422166 90.182546)
		(end 151.438254 90.198634)
		(width 0.1016)
		(layer "In2.Cu")
		(net 29)
	)
	(segment
		(start 151.717946 89.5096)
		(end 151.715399 89.532208)
		(width 0.1016)
		(layer "In2.Cu")
		(net 29)
	)
	(segment
		(start 151.715399 89.893391)
		(end 151.717946 89.916)
		(width 0.1016)
		(layer "In2.Cu")
		(net 29)
	)
	(segment
		(start 151.410062 91.294317)
		(end 151.402548 91.315791)
		(width 0.1016)
		(layer "In2.Cu")
		(net 29)
	)
	(segment
		(start 151.402548 89.329008)
		(end 151.410062 89.350482)
		(width 0.1016)
		(layer "In2.Cu")
		(net 29)
	)
	(segment
		(start 151.457518 90.027661)
		(end 151.438254 90.039765)
		(width 0.1016)
		(layer "In2.Cu")
		(net 29)
	)
	(segment
		(start 151.422166 89.369746)
		(end 151.438254 89.385834)
		(width 0.1016)
		(layer "In2.Cu")
		(net 29)
	)
	(segment
		(start 151.410062 91.382482)
		(end 151.422166 91.401746)
		(width 0.1016)
		(layer "In2.Cu")
		(net 29)
	)
	(segment
		(start 151.422166 90.055853)
		(end 151.410062 90.075117)
		(width 0.1016)
		(layer "In2.Cu")
		(net 29)
	)
	(segment
		(start 151.679693 91.621034)
		(end 151.660429 91.633138)
		(width 0.1016)
		(layer "In2.Cu")
		(net 29)
	)
	(segment
		(start 151.616346 90.0176)
		(end 151.5016 90.0176)
		(width 0.1016)
		(layer "In2.Cu")
		(net 29)
	)
	(segment
		(start 151.5016 89.408)
		(end 151.616346 89.408)
		(width 0.1016)
		(layer "In2.Cu")
		(net 29)
	)
	(segment
		(start 151.438254 91.665365)
		(end 151.422166 91.681453)
		(width 0.1016)
		(layer "In2.Cu")
		(net 29)
	)
	(segment
		(start 151.402548 91.315791)
		(end 151.4 91.3384)
		(width 0.1016)
		(layer "In2.Cu")
		(net 29)
	)
	(segment
		(start 151.616346 91.6432)
		(end 151.5016 91.6432)
		(width 0.1016)
		(layer "In2.Cu")
		(net 29)
	)
	(segment
		(start 151.717946 90.7288)
		(end 151.715399 90.751408)
		(width 0.1016)
		(layer "In2.Cu")
		(net 29)
	)
	(segment
		(start 151.715399 91.518991)
		(end 151.717946 91.5416)
		(width 0.1016)
		(layer "In2.Cu")
		(net 29)
	)
	(segment
		(start 151.410062 90.075117)
		(end 151.402548 90.096591)
		(width 0.1016)
		(layer "In2.Cu")
		(net 29)
	)
	(segment
		(start 151.695781 90.385746)
		(end 151.679693 90.401834)
		(width 0.1016)
		(layer "In2.Cu")
		(net 29)
	)
	(segment
		(start 151.616346 90.424)
		(end 151.5016 90.424)
		(width 0.1016)
		(layer "In2.Cu")
		(net 29)
	)
	(segment
		(start 151.679693 89.836565)
		(end 151.695781 89.852653)
		(width 0.1016)
		(layer "In2.Cu")
		(net 29)
	)
	(segment
		(start 151.478992 91.031052)
		(end 151.5016 91.0336)
		(width 0.1016)
		(layer "In2.Cu")
		(net 29)
	)
	(segment
		(start 151.707885 91.091117)
		(end 151.715399 91.112591)
		(width 0.1016)
		(layer "In2.Cu")
		(net 29)
	)
	(segment
		(start 151.410062 89.350482)
		(end 151.422166 89.369746)
		(width 0.1016)
		(layer "In2.Cu")
		(net 29)
	)
	(segment
		(start 151.616346 90.6272)
		(end 151.638955 90.629747)
		(width 0.1016)
		(layer "In2.Cu")
		(net 29)
	)
	(segment
		(start 151.5016 90.8304)
		(end 151.478992 90.832947)
		(width 0.1016)
		(layer "In2.Cu")
		(net 29)
	)
	(segment
		(start 151.4 92.7)
		(end 151.2 92.9)
		(width 0.1016)
		(layer "In2.Cu")
		(net 29)
	)
	(segment
		(start 151.715399 90.751408)
		(end 151.707885 90.772882)
		(width 0.1016)
		(layer "In2.Cu")
		(net 29)
	)
	(segment
		(start 151.5016 90.2208)
		(end 151.616346 90.2208)
		(width 0.1016)
		(layer "In2.Cu")
		(net 29)
	)
	(segment
		(start 151.410062 90.976082)
		(end 151.422166 90.995346)
		(width 0.1016)
		(layer "In2.Cu")
		(net 29)
	)
	(segment
		(start 151.707885 89.553682)
		(end 151.695781 89.572946)
		(width 0.1016)
		(layer "In2.Cu")
		(net 29)
	)
	(segment
		(start 151.5016 91.2368)
		(end 151.478992 91.239347)
		(width 0.1016)
		(layer "In2.Cu")
		(net 29)
	)
	(segment
		(start 151.707885 89.059117)
		(end 151.715399 89.080591)
		(width 0.1016)
		(layer "In2.Cu")
		(net 29)
	)
	(segment
		(start 151.438254 90.198634)
		(end 151.457518 90.210738)
		(width 0.1016)
		(layer "In2.Cu")
		(net 29)
	)
	(segment
		(start 151.679693 89.995434)
		(end 151.660429 90.007538)
		(width 0.1016)
		(layer "In2.Cu")
		(net 29)
	)
	(segment
		(start 151.410062 90.163282)
		(end 151.422166 90.182546)
		(width 0.1016)
		(layer "In2.Cu")
		(net 29)
	)
	(segment
		(start 151.660429 89.011661)
		(end 151.679693 89.023765)
		(width 0.1016)
		(layer "In2.Cu")
		(net 29)
	)
	(segment
		(start 151.478992 91.239347)
		(end 151.457518 91.246861)
		(width 0.1016)
		(layer "In2.Cu")
		(net 29)
	)
	(segment
		(start 151.438254 90.605034)
		(end 151.457518 90.617138)
		(width 0.1016)
		(layer "In2.Cu")
		(net 29)
	)
	(segment
		(start 151.4 88.833554)
		(end 151.4 88.9)
		(width 0.1016)
		(layer "In2.Cu")
		(net 29)
	)
	(segment
		(start 151.4 90.932)
		(end 151.402548 90.954608)
		(width 0.1016)
		(layer "In2.Cu")
		(net 29)
	)
	(segment
		(start 151.410062 90.569682)
		(end 151.422166 90.588946)
		(width 0.1016)
		(layer "In2.Cu")
		(net 29)
	)
	(segment
		(start 151.616346 91.2368)
		(end 151.5016 91.2368)
		(width 0.1016)
		(layer "In2.Cu")
		(net 29)
	)
	(segment
		(start 151.438254 89.633365)
		(end 151.422166 89.649453)
		(width 0.1016)
		(layer "In2.Cu")
		(net 29)
	)
	(segment
		(start 151.638955 89.816947)
		(end 151.660429 89.824461)
		(width 0.1016)
		(layer "In2.Cu")
		(net 29)
	)
	(segment
		(start 151.457518 90.210738)
		(end 151.478992 90.218252)
		(width 0.1016)
		(layer "In2.Cu")
		(net 29)
	)
	(segment
		(start 151.616346 89.408)
		(end 151.638955 89.410547)
		(width 0.1016)
		(layer "In2.Cu")
		(net 29)
	)
	(segment
		(start 151.5016 90.6272)
		(end 151.616346 90.6272)
		(width 0.1016)
		(layer "In2.Cu")
		(net 29)
	)
	(segment
		(start 151.715399 91.112591)
		(end 151.717946 91.1352)
		(width 0.1016)
		(layer "In2.Cu")
		(net 29)
	)
	(segment
		(start 152.825 84.21)
		(end 152.047599 84.987401)
		(width 0.1016)
		(layer "In2.Cu")
		(net 29)
	)
	(segment
		(start 151.402548 89.735408)
		(end 151.410062 89.756882)
		(width 0.1016)
		(layer "In2.Cu")
		(net 29)
	)
	(segment
		(start 151.478992 91.437452)
		(end 151.5016 91.44)
		(width 0.1016)
		(layer "In2.Cu")
		(net 29)
	)
	(segment
		(start 151.707885 89.960082)
		(end 151.695781 89.979346)
		(width 0.1016)
		(layer "In2.Cu")
		(net 29)
	)
	(segment
		(start 151.4 90.1192)
		(end 151.402548 90.141808)
		(width 0.1016)
		(layer "In2.Cu")
		(net 29)
	)
	(segment
		(start 151.478992 89.613747)
		(end 151.457518 89.621261)
		(width 0.1016)
		(layer "In2.Cu")
		(net 29)
	)
	(segment
		(start 151.438254 91.417834)
		(end 151.457518 91.429938)
		(width 0.1016)
		(layer "In2.Cu")
		(net 29)
	)
	(segment
		(start 151.4 89.3064)
		(end 151.402548 89.329008)
		(width 0.1016)
		(layer "In2.Cu")
		(net 29)
	)
	(segment
		(start 151.695781 90.792146)
		(end 151.679693 90.808234)
		(width 0.1016)
		(layer "In2.Cu")
		(net 29)
	)
	(segment
		(start 151.402548 89.690191)
		(end 151.4 89.7128)
		(width 0.1016)
		(layer "In2.Cu")
		(net 29)
	)
	(segment
		(start 151.707885 89.465517)
		(end 151.715399 89.486991)
		(width 0.1016)
		(layer "In2.Cu")
		(net 29)
	)
	(segment
		(start 151.638955 91.640652)
		(end 151.616346 91.6432)
		(width 0.1016)
		(layer "In2.Cu")
		(net 29)
	)
	(segment
		(start 151.438254 91.011434)
		(end 151.457518 91.023538)
		(width 0.1016)
		(layer "In2.Cu")
		(net 29)
	)
	(segment
		(start 151.660429 91.633138)
		(end 151.638955 91.640652)
		(width 0.1016)
		(layer "In2.Cu")
		(net 29)
	)
	(segment
		(start 151.402548 90.141808)
		(end 151.410062 90.163282)
		(width 0.1016)
		(layer "In2.Cu")
		(net 29)
	)
	(segment
		(start 151.402548 90.502991)
		(end 151.4 90.5256)
		(width 0.1016)
		(layer "In2.Cu")
		(net 29)
	)
	(segment
		(start 151.410062 89.668717)
		(end 151.402548 89.690191)
		(width 0.1016)
		(layer "In2.Cu")
		(net 29)
	)
	(segment
		(start 151.4 88.9)
		(end 151.402548 88.922608)
		(width 0.1016)
		(layer "In2.Cu")
		(net 29)
	)
	(segment
		(start 151.402548 90.548208)
		(end 151.410062 90.569682)
		(width 0.1016)
		(layer "In2.Cu")
		(net 29)
	)
	(segment
		(start 151.638955 90.015052)
		(end 151.616346 90.0176)
		(width 0.1016)
		(layer "In2.Cu")
		(net 29)
	)
	(segment
		(start 151.660429 90.413938)
		(end 151.638955 90.421452)
		(width 0.1016)
		(layer "In2.Cu")
		(net 29)
	)
	(segment
		(start 151.638955 89.410547)
		(end 151.660429 89.418061)
		(width 0.1016)
		(layer "In2.Cu")
		(net 29)
	)
	(segment
		(start 151.717946 91.5416)
		(end 151.715399 91.564208)
		(width 0.1016)
		(layer "In2.Cu")
		(net 29)
	)
	(segment
		(start 151.438254 91.258965)
		(end 151.422166 91.275053)
		(width 0.1016)
		(layer "In2.Cu")
		(net 29)
	)
	(segment
		(start 151.715399 90.706191)
		(end 151.717946 90.7288)
		(width 0.1016)
		(layer "In2.Cu")
		(net 29)
	)
	(segment
		(start 151.679693 89.430165)
		(end 151.695781 89.446253)
		(width 0.1016)
		(layer "In2.Cu")
		(net 29)
	)
	(segment
		(start 151.660429 90.820338)
		(end 151.638955 90.827852)
		(width 0.1016)
		(layer "In2.Cu")
		(net 29)
	)
	(segment
		(start 151.478992 89.405452)
		(end 151.5016 89.408)
		(width 0.1016)
		(layer "In2.Cu")
		(net 29)
	)
	(segment
		(start 151.438254 90.446165)
		(end 151.422166 90.462253)
		(width 0.1016)
		(layer "In2.Cu")
		(net 29)
	)
	(segment
		(start 151.717946 89.916)
		(end 151.715399 89.938608)
		(width 0.1016)
		(layer "In2.Cu")
		(net 29)
	)
	(segment
		(start 151.660429 90.637261)
		(end 151.679693 90.649365)
		(width 0.1016)
		(layer "In2.Cu")
		(net 29)
	)
	(segment
		(start 151.422166 90.868653)
		(end 151.410062 90.887917)
		(width 0.1016)
		(layer "In2.Cu")
		(net 29)
	)
	(segment
		(start 151.457518 90.434061)
		(end 151.438254 90.446165)
		(width 0.1016)
		(layer "In2.Cu")
		(net 29)
	)
	(segment
		(start 151.5016 89.2048)
		(end 151.478992 89.207347)
		(width 0.1016)
		(layer "In2.Cu")
		(net 29)
	)
	(segment
		(start 151.457518 91.653261)
		(end 151.438254 91.665365)
		(width 0.1016)
		(layer "In2.Cu")
		(net 29)
	)
	(segment
		(start 151.660429 91.043661)
		(end 151.679693 91.055765)
		(width 0.1016)
		(layer "In2.Cu")
		(net 29)
	)
	(segment
		(start 151.5016 90.424)
		(end 151.478992 90.426547)
		(width 0.1016)
		(layer "In2.Cu")
		(net 29)
	)
	(segment
		(start 151.5016 91.6432)
		(end 151.478992 91.645747)
		(width 0.1016)
		(layer "In2.Cu")
		(net 29)
	)
	(segment
		(start 151.717946 90.3224)
		(end 151.715399 90.345008)
		(width 0.1016)
		(layer "In2.Cu")
		(net 29)
	)
	(segment
		(start 151.5016 89.8144)
		(end 151.616346 89.8144)
		(width 0.1016)
		(layer "In2.Cu")
		(net 29)
	)
	(segment
		(start 151.616346 90.2208)
		(end 151.638955 90.223347)
		(width 0.1016)
		(layer "In2.Cu")
		(net 29)
	)
	(segment
		(start 151.660429 90.007538)
		(end 151.638955 90.015052)
		(width 0.1016)
		(layer "In2.Cu")
		(net 29)
	)
	(segment
		(start 151.679693 90.401834)
		(end 151.660429 90.413938)
		(width 0.1016)
		(layer "In2.Cu")
		(net 29)
	)
	(segment
		(start 151.638955 91.234252)
		(end 151.616346 91.2368)
		(width 0.1016)
		(layer "In2.Cu")
		(net 29)
	)
	(segment
		(start 151.616346 89.2048)
		(end 151.5016 89.2048)
		(width 0.1016)
		(layer "In2.Cu")
		(net 29)
	)
	(segment
		(start 151.457518 88.991538)
		(end 151.478992 88.999052)
		(width 0.1016)
		(layer "In2.Cu")
		(net 29)
	)
	(segment
		(start 151.660429 89.418061)
		(end 151.679693 89.430165)
		(width 0.1016)
		(layer "In2.Cu")
		(net 29)
	)
	(segment
		(start 151.438254 90.852565)
		(end 151.422166 90.868653)
		(width 0.1016)
		(layer "In2.Cu")
		(net 29)
	)
	(segment
		(start 151.478992 91.645747)
		(end 151.457518 91.653261)
		(width 0.1016)
		(layer "In2.Cu")
		(net 29)
	)
	(segment
		(start 151.457518 90.617138)
		(end 151.478992 90.624652)
		(width 0.1016)
		(layer "In2.Cu")
		(net 29)
	)
	(segment
		(start 151.410062 90.887917)
		(end 151.402548 90.909391)
		(width 0.1016)
		(layer "In2.Cu")
		(net 29)
	)
	(segment
		(start 151.402548 91.722191)
		(end 151.4 91.7448)
		(width 0.1016)
		(layer "In2.Cu")
		(net 29)
	)
	(segment
		(start 151.715399 89.938608)
		(end 151.707885 89.960082)
		(width 0.1016)
		(layer "In2.Cu")
		(net 29)
	)
	(segment
		(start 151.478992 89.811852)
		(end 151.5016 89.8144)
		(width 0.1016)
		(layer "In2.Cu")
		(net 29)
	)
	(segment
		(start 151.5016 89.0016)
		(end 151.616346 89.0016)
		(width 0.1016)
		(layer "In2.Cu")
		(net 29)
	)
	(segment
		(start 151.422166 88.963346)
		(end 151.438254 88.979434)
		(width 0.1016)
		(layer "In2.Cu")
		(net 29)
	)
	(segment
		(start 151.402548 90.096591)
		(end 151.4 90.1192)
		(width 0.1016)
		(layer "In2.Cu")
		(net 29)
	)
	(segment
		(start 151.478992 88.999052)
		(end 151.5016 89.0016)
		(width 0.1016)
		(layer "In2.Cu")
		(net 29)
	)
	(segment
		(start 151.638955 89.608652)
		(end 151.616346 89.6112)
		(width 0.1016)
		(layer "In2.Cu")
		(net 29)
	)
	(segment
		(start 151.438254 90.039765)
		(end 151.422166 90.055853)
		(width 0.1016)
		(layer "In2.Cu")
		(net 29)
	)
	(segment
		(start 151.707885 89.871917)
		(end 151.715399 89.893391)
		(width 0.1016)
		(layer "In2.Cu")
		(net 29)
	)
	(segment
		(start 151.478992 90.218252)
		(end 151.5016 90.2208)
		(width 0.1016)
		(layer "In2.Cu")
		(net 29)
	)
	(segment
		(start 151.715399 91.564208)
		(end 151.707885 91.585682)
		(width 0.1016)
		(layer "In2.Cu")
		(net 29)
	)
	(segment
		(start 151.715399 90.299791)
		(end 151.717946 90.3224)
		(width 0.1016)
		(layer "In2.Cu")
		(net 29)
	)
	(segment
		(start 151.422166 89.776146)
		(end 151.438254 89.792234)
		(width 0.1016)
		(layer "In2.Cu")
		(net 29)
	)
	(segment
		(start 151.679693 90.242965)
		(end 151.695781 90.259053)
		(width 0.1016)
		(layer "In2.Cu")
		(net 29)
	)
	(segment
		(start 151.638955 90.223347)
		(end 151.660429 90.230861)
		(width 0.1016)
		(layer "In2.Cu")
		(net 29)
	)
	(segment
		(start 151.638955 91.036147)
		(end 151.660429 91.043661)
		(width 0.1016)
		(layer "In2.Cu")
		(net 29)
	)
	(segment
		(start 151.478992 90.832947)
		(end 151.457518 90.840461)
		(width 0.1016)
		(layer "In2.Cu")
		(net 29)
	)
	(segment
		(start 151.402548 90.954608)
		(end 151.410062 90.976082)
		(width 0.1016)
		(layer "In2.Cu")
		(net 29)
	)
	(segment
		(start 152.047599 84.987401)
		(end 152.047599 88.185955)
		(width 0.1016)
		(layer "In2.Cu")
		(net 29)
	)
	(segment
		(start 151.707885 90.366482)
		(end 151.695781 90.385746)
		(width 0.1016)
		(layer "In2.Cu")
		(net 29)
	)
	(segment
		(start 151.438254 89.226965)
		(end 151.422166 89.243053)
		(width 0.1016)
		(layer "In2.Cu")
		(net 29)
	)
	(segment
		(start 151.616346 89.0016)
		(end 151.638955 89.004147)
		(width 0.1016)
		(layer "In2.Cu")
		(net 29)
	)
	(segment
		(start 151.695781 89.166546)
		(end 151.679693 89.182634)
		(width 0.1016)
		(layer "In2.Cu")
		(net 29)
	)
	(segment
		(start 151.402548 89.283791)
		(end 151.4 89.3064)
		(width 0.1016)
		(layer "In2.Cu")
		(net 29)
	)
	(segment
		(start 151.402548 91.361008)
		(end 151.410062 91.382482)
		(width 0.1016)
		(layer "In2.Cu")
		(net 29)
	)
	(segment
		(start 151.478992 90.020147)
		(end 151.457518 90.027661)
		(width 0.1016)
		(layer "In2.Cu")
		(net 29)
	)
	(segment
		(start 151.422166 89.243053)
		(end 151.410062 89.262317)
		(width 0.1016)
		(layer "In2.Cu")
		(net 29)
	)
	(segment
		(start 151.410062 89.756882)
		(end 151.422166 89.776146)
		(width 0.1016)
		(layer "In2.Cu")
		(net 29)
	)
	(segment
		(start 151.638955 91.442547)
		(end 151.660429 91.450061)
		(width 0.1016)
		(layer "In2.Cu")
		(net 29)
	)
	(segment
		(start 151.695781 91.071853)
		(end 151.707885 91.091117)
		(width 0.1016)
		(layer "In2.Cu")
		(net 29)
	)
	(segment
		(start 151.478992 90.426547)
		(end 151.457518 90.434061)
		(width 0.1016)
		(layer "In2.Cu")
		(net 29)
	)
	(segment
		(start 151.660429 89.824461)
		(end 151.679693 89.836565)
		(width 0.1016)
		(layer "In2.Cu")
		(net 29)
	)
	(segment
		(start 151.715399 91.157808)
		(end 151.707885 91.179282)
		(width 0.1016)
		(layer "In2.Cu")
		(net 29)
	)
	(segment
		(start 151.695781 90.665453)
		(end 151.707885 90.684717)
		(width 0.1016)
		(layer "In2.Cu")
		(net 29)
	)
	(segment
		(start 151.695781 89.446253)
		(end 151.707885 89.465517)
		(width 0.1016)
		(layer "In2.Cu")
		(net 29)
	)
	(segment
		(start 151.695781 91.198546)
		(end 151.679693 91.214634)
		(width 0.1016)
		(layer "In2.Cu")
		(net 29)
	)
	(segment
		(start 151.638955 90.421452)
		(end 151.616346 90.424)
		(width 0.1016)
		(layer "In2.Cu")
		(net 29)
	)
	(segment
		(start 151.5016 91.44)
		(end 151.616346 91.44)
		(width 0.1016)
		(layer "In2.Cu")
		(net 29)
	)
	(segment
		(start 151.616346 91.44)
		(end 151.638955 91.442547)
		(width 0.1016)
		(layer "In2.Cu")
		(net 29)
	)
	(segment
		(start 151.422166 89.649453)
		(end 151.410062 89.668717)
		(width 0.1016)
		(layer "In2.Cu")
		(net 29)
	)
	(segment
		(start 151.660429 91.450061)
		(end 151.679693 91.462165)
		(width 0.1016)
		(layer "In2.Cu")
		(net 29)
	)
	(segment
		(start 151.5016 90.0176)
		(end 151.478992 90.020147)
		(width 0.1016)
		(layer "In2.Cu")
		(net 29)
	)
	(segment
		(start 151.679693 91.055765)
		(end 151.695781 91.071853)
		(width 0.1016)
		(layer "In2.Cu")
		(net 29)
	)
	(segment
		(start 151.679693 91.214634)
		(end 151.660429 91.226738)
		(width 0.1016)
		(layer "In2.Cu")
		(net 29)
	)
	(segment
		(start 151.457518 91.246861)
		(end 151.438254 91.258965)
		(width 0.1016)
		(layer "In2.Cu")
		(net 29)
	)
	(segment
		(start 151.478992 89.207347)
		(end 151.457518 89.214861)
		(width 0.1016)
		(layer "In2.Cu")
		(net 29)
	)
	(segment
		(start 151.707885 90.684717)
		(end 151.715399 90.706191)
		(width 0.1016)
		(layer "In2.Cu")
		(net 29)
	)
	(segment
		(start 151.422166 91.275053)
		(end 151.410062 91.294317)
		(width 0.1016)
		(layer "In2.Cu")
		(net 29)
	)
	(segment
		(start 151.707885 89.147282)
		(end 151.695781 89.166546)
		(width 0.1016)
		(layer "In2.Cu")
		(net 29)
	)
	(segment
		(start 151.695781 90.259053)
		(end 151.707885 90.278317)
		(width 0.1016)
		(layer "In2.Cu")
		(net 29)
	)
	(segment
		(start 151.457518 91.429938)
		(end 151.478992 91.437452)
		(width 0.1016)
		(layer "In2.Cu")
		(net 29)
	)
	(segment
		(start 151.695781 89.852653)
		(end 151.707885 89.871917)
		(width 0.1016)
		(layer "In2.Cu")
		(net 29)
	)
	(segment
		(start 151.707885 91.179282)
		(end 151.695781 91.198546)
		(width 0.1016)
		(layer "In2.Cu")
		(net 29)
	)
	(segment
		(start 151.457518 91.023538)
		(end 151.478992 91.031052)
		(width 0.1016)
		(layer "In2.Cu")
		(net 29)
	)
	(segment
		(start 151.715399 89.532208)
		(end 151.707885 89.553682)
		(width 0.1016)
		(layer "In2.Cu")
		(net 29)
	)
	(segment
		(start 151.717946 91.1352)
		(end 151.715399 91.157808)
		(width 0.1016)
		(layer "In2.Cu")
		(net 29)
	)
	(segment
		(start 151.638955 89.004147)
		(end 151.660429 89.011661)
		(width 0.1016)
		(layer "In2.Cu")
		(net 29)
	)
	(segment
		(start 151.438254 89.792234)
		(end 151.457518 89.804338)
		(width 0.1016)
		(layer "In2.Cu")
		(net 29)
	)
	(segment
		(start 151.410062 88.944082)
		(end 151.422166 88.963346)
		(width 0.1016)
		(layer "In2.Cu")
		(net 29)
	)
	(segment
		(start 151.695781 91.478253)
		(end 151.707885 91.497517)
		(width 0.1016)
		(layer "In2.Cu")
		(net 29)
	)
	(segment
		(start 151.695781 91.604946)
		(end 151.679693 91.621034)
		(width 0.1016)
		(layer "In2.Cu")
		(net 29)
	)
	(segment
		(start 151.638955 90.629747)
		(end 151.660429 90.637261)
		(width 0.1016)
		(layer "In2.Cu")
		(net 29)
	)
	(segment
		(start 151.457518 89.214861)
		(end 151.438254 89.226965)
		(width 0.1016)
		(layer "In2.Cu")
		(net 29)
	)
	(segment
		(start 151.402548 88.922608)
		(end 151.410062 88.944082)
		(width 0.1016)
		(layer "In2.Cu")
		(net 29)
	)
	(segment
		(start 151.679693 90.649365)
		(end 151.695781 90.665453)
		(width 0.1016)
		(layer "In2.Cu")
		(net 29)
	)
	(segment
		(start 151.478992 90.624652)
		(end 151.5016 90.6272)
		(width 0.1016)
		(layer "In2.Cu")
		(net 29)
	)
	(segment
		(start 151.438254 88.979434)
		(end 151.457518 88.991538)
		(width 0.1016)
		(layer "In2.Cu")
		(net 29)
	)
	(segment
		(start 151.5016 89.6112)
		(end 151.478992 89.613747)
		(width 0.1016)
		(layer "In2.Cu")
		(net 29)
	)
	(segment
		(start 151.707885 90.772882)
		(end 151.695781 90.792146)
		(width 0.1016)
		(layer "In2.Cu")
		(net 29)
	)
	(segment
		(start 151.4 91.3384)
		(end 151.402548 91.361008)
		(width 0.1016)
		(layer "In2.Cu")
		(net 29)
	)
	(segment
		(start 151.422166 90.588946)
		(end 151.438254 90.605034)
		(width 0.1016)
		(layer "In2.Cu")
		(net 29)
	)
	(segment
		(start 151.707885 91.585682)
		(end 151.695781 91.604946)
		(width 0.1016)
		(layer "In2.Cu")
		(net 29)
	)
	(segment
		(start 151.679693 89.589034)
		(end 151.660429 89.601138)
		(width 0.1016)
		(layer "In2.Cu")
		(net 29)
	)
	(segment
		(start 151.616346 89.6112)
		(end 151.5016 89.6112)
		(width 0.1016)
		(layer "In2.Cu")
		(net 29)
	)
	(segment
		(start 151.707885 90.278317)
		(end 151.715399 90.299791)
		(width 0.1016)
		(layer "In2.Cu")
		(net 29)
	)
	(segment
		(start 151.402548 90.909391)
		(end 151.4 90.932)
		(width 0.1016)
		(layer "In2.Cu")
		(net 29)
	)
	(segment
		(start 151.457518 89.397938)
		(end 151.478992 89.405452)
		(width 0.1016)
		(layer "In2.Cu")
		(net 29)
	)
	(segment
		(start 152.047599 88.185955)
		(end 151.4 88.833554)
		(width 0.1016)
		(layer "In2.Cu")
		(net 29)
	)
	(segment
		(start 151.422166 90.462253)
		(end 151.410062 90.481517)
		(width 0.1016)
		(layer "In2.Cu")
		(net 29)
	)
	(segment
		(start 151.715399 89.125808)
		(end 151.707885 89.147282)
		(width 0.1016)
		(layer "In2.Cu")
		(net 29)
	)
	(segment
		(start 151.410062 89.262317)
		(end 151.402548 89.283791)
		(width 0.1016)
		(layer "In2.Cu")
		(net 29)
	)
	(segment
		(start 151.715399 89.080591)
		(end 151.717946 89.1032)
		(width 0.1016)
		(layer "In2.Cu")
		(net 29)
	)
	(segment
		(start 151.5016 91.0336)
		(end 151.616346 91.0336)
		(width 0.1016)
		(layer "In2.Cu")
		(net 29)
	)
	(segment
		(start 151.4 89.7128)
		(end 151.402548 89.735408)
		(width 0.1016)
		(layer "In2.Cu")
		(net 29)
	)
	(segment
		(start 151.410062 90.481517)
		(end 151.402548 90.502991)
		(width 0.1016)
		(layer "In2.Cu")
		(net 29)
	)
	(segment
		(start 151.616346 91.0336)
		(end 151.638955 91.036147)
		(width 0.1016)
		(layer "In2.Cu")
		(net 29)
	)
	(segment
		(start 151.715399 90.345008)
		(end 151.707885 90.366482)
		(width 0.1016)
		(layer "In2.Cu")
		(net 29)
	)
	(segment
		(start 151.715399 89.486991)
		(end 151.717946 89.5096)
		(width 0.1016)
		(layer "In2.Cu")
		(net 29)
	)
	(segment
		(start 152.825 87.65)
		(end 152.425 87.25)
		(width 0.2)
		(layer "F.Cu")
		(net 30)
	)
	(via
		(at 152 92.7)
		(size 0.45)
		(drill 0.15)
		(layers "F.Cu" "B.Cu")
		(net 30)
	)
	(via
		(at 152.425 87.25)
		(size 0.45)
		(drill 0.15)
		(layers "F.Cu" "B.Cu")
		(net 30)
	)
	(segment
		(start 152 92.7)
		(end 148.175 96.525)
		(width 0.145)
		(layer "B.Cu")
		(net 30)
	)
	(segment
		(start 148.175 96.525)
		(end 148.175 98.7)
		(width 0.145)
		(layer "B.Cu")
		(net 30)
	)
	(segment
		(start 152.423142 90.015052)
		(end 152.400533 90.0176)
		(width 0.1016)
		(layer "In2.Cu")
		(net 30)
	)
	(segment
		(start 152.46388 91.868565)
		(end 152.479968 91.884653)
		(width 0.1016)
		(layer "In2.Cu")
		(net 30)
	)
	(segment
		(start 152.46388 89.589034)
		(end 152.444616 89.601138)
		(width 0.1016)
		(layer "In2.Cu")
		(net 30)
	)
	(segment
		(start 152.022166 90.995346)
		(end 152.038254 91.011434)
		(width 0.1016)
		(layer "In2.Cu")
		(net 30)
	)
	(segment
		(start 152.010062 91.788882)
		(end 152.022166 91.808146)
		(width 0.1016)
		(layer "In2.Cu")
		(net 30)
	)
	(segment
		(start 152.400533 89.8144)
		(end 152.423142 89.816947)
		(width 0.1016)
		(layer "In2.Cu")
		(net 30)
	)
	(segment
		(start 152.400533 92.0496)
		(end 152.1016 92.0496)
		(width 0.1016)
		(layer "In2.Cu")
		(net 30)
	)
	(segment
		(start 152.479968 90.792146)
		(end 152.46388 90.808234)
		(width 0.1016)
		(layer "In2.Cu")
		(net 30)
	)
	(segment
		(start 152.400533 91.8464)
		(end 152.423142 91.848947)
		(width 0.1016)
		(layer "In2.Cu")
		(net 30)
	)
	(segment
		(start 152.002548 90.954608)
		(end 152.010062 90.976082)
		(width 0.1016)
		(layer "In2.Cu")
		(net 30)
	)
	(segment
		(start 152.078992 89.613747)
		(end 152.057518 89.621261)
		(width 0.1016)
		(layer "In2.Cu")
		(net 30)
	)
	(segment
		(start 152.444616 91.856461)
		(end 152.46388 91.868565)
		(width 0.1016)
		(layer "In2.Cu")
		(net 30)
	)
	(segment
		(start 152.46388 90.401834)
		(end 152.444616 90.413938)
		(width 0.1016)
		(layer "In2.Cu")
		(net 30)
	)
	(segment
		(start 152.002548 90.548208)
		(end 152.010062 90.569682)
		(width 0.1016)
		(layer "In2.Cu")
		(net 30)
	)
	(segment
		(start 152.022166 91.681453)
		(end 152.010062 91.700717)
		(width 0.1016)
		(layer "In2.Cu")
		(net 30)
	)
	(segment
		(start 152.423142 89.608652)
		(end 152.400533 89.6112)
		(width 0.1016)
		(layer "In2.Cu")
		(net 30)
	)
	(segment
		(start 152.492072 89.553682)
		(end 152.479968 89.572946)
		(width 0.1016)
		(layer "In2.Cu")
		(net 30)
	)
	(segment
		(start 152.444616 89.011661)
		(end 152.46388 89.023765)
		(width 0.1016)
		(layer "In2.Cu")
		(net 30)
	)
	(segment
		(start 152.423142 91.442547)
		(end 152.444616 91.450061)
		(width 0.1016)
		(layer "In2.Cu")
		(net 30)
	)
	(segment
		(start 152.022166 91.275053)
		(end 152.010062 91.294317)
		(width 0.1016)
		(layer "In2.Cu")
		(net 30)
	)
	(segment
		(start 152 89.7128)
		(end 152.002548 89.735408)
		(width 0.1016)
		(layer "In2.Cu")
		(net 30)
	)
	(segment
		(start 152.423142 91.640652)
		(end 152.400533 91.6432)
		(width 0.1016)
		(layer "In2.Cu")
		(net 30)
	)
	(segment
		(start 152.038254 90.605034)
		(end 152.057518 90.617138)
		(width 0.1016)
		(layer "In2.Cu")
		(net 30)
	)
	(segment
		(start 152.492072 90.772882)
		(end 152.479968 90.792146)
		(width 0.1016)
		(layer "In2.Cu")
		(net 30)
	)
	(segment
		(start 152.499586 89.893391)
		(end 152.502133 89.916)
		(width 0.1016)
		(layer "In2.Cu")
		(net 30)
	)
	(segment
		(start 152.499586 89.486991)
		(end 152.502133 89.5096)
		(width 0.1016)
		(layer "In2.Cu")
		(net 30)
	)
	(segment
		(start 152.010062 89.262317)
		(end 152.002548 89.283791)
		(width 0.1016)
		(layer "In2.Cu")
		(net 30)
	)
	(segment
		(start 152.038254 88.979434)
		(end 152.057518 88.991538)
		(width 0.1016)
		(layer "In2.Cu")
		(net 30)
	)
	(segment
		(start 152.010062 88.944082)
		(end 152.022166 88.963346)
		(width 0.1016)
		(layer "In2.Cu")
		(net 30)
	)
	(segment
		(start 152.502133 89.5096)
		(end 152.499586 89.532208)
		(width 0.1016)
		(layer "In2.Cu")
		(net 30)
	)
	(segment
		(start 152.078992 92.052147)
		(end 152.057518 92.059661)
		(width 0.1016)
		(layer "In2.Cu")
		(net 30)
	)
	(segment
		(start 152.038254 90.039765)
		(end 152.022166 90.055853)
		(width 0.1016)
		(layer "In2.Cu")
		(net 30)
	)
	(segment
		(start 152.444616 89.418061)
		(end 152.46388 89.430165)
		(width 0.1016)
		(layer "In2.Cu")
		(net 30)
	)
	(segment
		(start 152.078992 88.999052)
		(end 152.1016 89.0016)
		(width 0.1016)
		(layer "In2.Cu")
		(net 30)
	)
	(segment
		(start 152.423142 91.234252)
		(end 152.400533 91.2368)
		(width 0.1016)
		(layer "In2.Cu")
		(net 30)
	)
	(segment
		(start 152.400533 91.6432)
		(end 152.1016 91.6432)
		(width 0.1016)
		(layer "In2.Cu")
		(net 30)
	)
	(segment
		(start 152.038254 89.385834)
		(end 152.057518 89.397938)
		(width 0.1016)
		(layer "In2.Cu")
		(net 30)
	)
	(segment
		(start 152.400533 90.0176)
		(end 152.1016 90.0176)
		(width 0.1016)
		(layer "In2.Cu")
		(net 30)
	)
	(segment
		(start 152.057518 91.653261)
		(end 152.038254 91.665365)
		(width 0.1016)
		(layer "In2.Cu")
		(net 30)
	)
	(segment
		(start 152.46388 89.995434)
		(end 152.444616 90.007538)
		(width 0.1016)
		(layer "In2.Cu")
		(net 30)
	)
	(segment
		(start 152.400533 90.8304)
		(end 152.1016 90.8304)
		(width 0.1016)
		(layer "In2.Cu")
		(net 30)
	)
	(segment
		(start 152.057518 89.804338)
		(end 152.078992 89.811852)
		(width 0.1016)
		(layer "In2.Cu")
		(net 30)
	)
	(segment
		(start 152.057518 90.434061)
		(end 152.038254 90.446165)
		(width 0.1016)
		(layer "In2.Cu")
		(net 30)
	)
	(segment
		(start 152.400533 91.44)
		(end 152.423142 91.442547)
		(width 0.1016)
		(layer "In2.Cu")
		(net 30)
	)
	(segment
		(start 152.502133 91.1352)
		(end 152.499586 91.157808)
		(width 0.1016)
		(layer "In2.Cu")
		(net 30)
	)
	(segment
		(start 152.010062 90.887917)
		(end 152.002548 90.909391)
		(width 0.1016)
		(layer "In2.Cu")
		(net 30)
	)
	(segment
		(start 152.46388 89.836565)
		(end 152.479968 89.852653)
		(width 0.1016)
		(layer "In2.Cu")
		(net 30)
	)
	(segment
		(start 152 88.8)
		(end 152 88.9)
		(width 0.1016)
		(layer "In2.Cu")
		(net 30)
	)
	(segment
		(start 152.078992 90.020147)
		(end 152.057518 90.027661)
		(width 0.1016)
		(layer "In2.Cu")
		(net 30)
	)
	(segment
		(start 152.492072 90.684717)
		(end 152.499586 90.706191)
		(width 0.1016)
		(layer "In2.Cu")
		(net 30)
	)
	(segment
		(start 152.479968 91.884653)
		(end 152.492072 91.903917)
		(width 0.1016)
		(layer "In2.Cu")
		(net 30)
	)
	(segment
		(start 152.499586 89.532208)
		(end 152.492072 89.553682)
		(width 0.1016)
		(layer "In2.Cu")
		(net 30)
	)
	(segment
		(start 152.057518 90.027661)
		(end 152.038254 90.039765)
		(width 0.1016)
		(layer "In2.Cu")
		(net 30)
	)
	(segment
		(start 152.057518 92.059661)
		(end 152.038254 92.071765)
		(width 0.1016)
		(layer "In2.Cu")
		(net 30)
	)
	(segment
		(start 152.002548 91.767408)
		(end 152.010062 91.788882)
		(width 0.1016)
		(layer "In2.Cu")
		(net 30)
	)
	(segment
		(start 152.46388 89.430165)
		(end 152.479968 89.446253)
		(width 0.1016)
		(layer "In2.Cu")
		(net 30)
	)
	(segment
		(start 152.038254 91.417834)
		(end 152.057518 91.429938)
		(width 0.1016)
		(layer "In2.Cu")
		(net 30)
	)
	(segment
		(start 152.423142 90.827852)
		(end 152.400533 90.8304)
		(width 0.1016)
		(layer "In2.Cu")
		(net 30)
	)
	(segment
		(start 152.479968 91.478253)
		(end 152.492072 91.497517)
		(width 0.1016)
		(layer "In2.Cu")
		(net 30)
	)
	(segment
		(start 152.479968 90.385746)
		(end 152.46388 90.401834)
		(width 0.1016)
		(layer "In2.Cu")
		(net 30)
	)
	(segment
		(start 152.057518 90.210738)
		(end 152.078992 90.218252)
		(width 0.1016)
		(layer "In2.Cu")
		(net 30)
	)
	(segment
		(start 152.038254 89.792234)
		(end 152.057518 89.804338)
		(width 0.1016)
		(layer "In2.Cu")
		(net 30)
	)
	(segment
		(start 152.46388 89.023765)
		(end 152.479968 89.039853)
		(width 0.1016)
		(layer "In2.Cu")
		(net 30)
	)
	(segment
		(start 152.022166 89.649453)
		(end 152.010062 89.668717)
		(width 0.1016)
		(layer "In2.Cu")
		(net 30)
	)
	(segment
		(start 152.479968 89.166546)
		(end 152.46388 89.182634)
		(width 0.1016)
		(layer "In2.Cu")
		(net 30)
	)
	(segment
		(start 152.492072 89.871917)
		(end 152.499586 89.893391)
		(width 0.1016)
		(layer "In2.Cu")
		(net 30)
	)
	(segment
		(start 152.022166 92.087853)
		(end 152.010062 92.107117)
		(width 0.1016)
		(layer "In2.Cu")
		(net 30)
	)
	(segment
		(start 152.057518 91.023538)
		(end 152.078992 91.031052)
		(width 0.1016)
		(layer "In2.Cu")
		(net 30)
	)
	(segment
		(start 152.499586 89.125808)
		(end 152.492072 89.147282)
		(width 0.1016)
		(layer "In2.Cu")
		(net 30)
	)
	(segment
		(start 152.444616 91.450061)
		(end 152.46388 91.462165)
		(width 0.1016)
		(layer "In2.Cu")
		(net 30)
	)
	(segment
		(start 152.492072 91.497517)
		(end 152.499586 91.518991)
		(width 0.1016)
		(layer "In2.Cu")
		(net 30)
	)
	(segment
		(start 152.002548 90.502991)
		(end 152 90.5256)
		(width 0.1016)
		(layer "In2.Cu")
		(net 30)
	)
	(segment
		(start 152.1016 90.0176)
		(end 152.078992 90.020147)
		(width 0.1016)
		(layer "In2.Cu")
		(net 30)
	)
	(segment
		(start 152.057518 90.840461)
		(end 152.038254 90.852565)
		(width 0.1016)
		(layer "In2.Cu")
		(net 30)
	)
	(segment
		(start 152.479968 89.039853)
		(end 152.492072 89.059117)
		(width 0.1016)
		(layer "In2.Cu")
		(net 30)
	)
	(segment
		(start 152.444616 91.043661)
		(end 152.46388 91.055765)
		(width 0.1016)
		(layer "In2.Cu")
		(net 30)
	)
	(segment
		(start 152.479968 89.979346)
		(end 152.46388 89.995434)
		(width 0.1016)
		(layer "In2.Cu")
		(net 30)
	)
	(segment
		(start 152.1016 89.408)
		(end 152.400533 89.408)
		(width 0.1016)
		(layer "In2.Cu")
		(net 30)
	)
	(segment
		(start 152.1016 89.6112)
		(end 152.078992 89.613747)
		(width 0.1016)
		(layer "In2.Cu")
		(net 30)
	)
	(segment
		(start 152.078992 89.405452)
		(end 152.1016 89.408)
		(width 0.1016)
		(layer "In2.Cu")
		(net 30)
	)
	(segment
		(start 152.057518 91.836338)
		(end 152.078992 91.843852)
		(width 0.1016)
		(layer "In2.Cu")
		(net 30)
	)
	(segment
		(start 152.1016 90.2208)
		(end 152.400533 90.2208)
		(width 0.1016)
		(layer "In2.Cu")
		(net 30)
	)
	(segment
		(start 152.492072 91.179282)
		(end 152.479968 91.198546)
		(width 0.1016)
		(layer "In2.Cu")
		(net 30)
	)
	(segment
		(start 152.038254 91.665365)
		(end 152.022166 91.681453)
		(width 0.1016)
		(layer "In2.Cu")
		(net 30)
	)
	(segment
		(start 152.057518 91.246861)
		(end 152.038254 91.258965)
		(width 0.1016)
		(layer "In2.Cu")
		(net 30)
	)
	(segment
		(start 152.1016 90.8304)
		(end 152.078992 90.832947)
		(width 0.1016)
		(layer "In2.Cu")
		(net 30)
	)
	(segment
		(start 152.3 87.4)
		(end 152.3 88.5)
		(width 0.1016)
		(layer "In2.Cu")
		(net 30)
	)
	(segment
		(start 152.46388 91.055765)
		(end 152.479968 91.071853)
		(width 0.1016)
		(layer "In2.Cu")
		(net 30)
	)
	(segment
		(start 152.010062 90.569682)
		(end 152.022166 90.588946)
		(width 0.1016)
		(layer "In2.Cu")
		(net 30)
	)
	(segment
		(start 152.492072 89.059117)
		(end 152.499586 89.080591)
		(width 0.1016)
		(layer "In2.Cu")
		(net 30)
	)
	(segment
		(start 152.010062 91.294317)
		(end 152.002548 91.315791)
		(width 0.1016)
		(layer "In2.Cu")
		(net 30)
	)
	(segment
		(start 152.078992 89.207347)
		(end 152.057518 89.214861)
		(width 0.1016)
		(layer "In2.Cu")
		(net 30)
	)
	(segment
		(start 152.022166 90.055853)
		(end 152.010062 90.075117)
		(width 0.1016)
		(layer "In2.Cu")
		(net 30)
	)
	(segment
		(start 152.002548 90.141808)
		(end 152.010062 90.163282)
		(width 0.1016)
		(layer "In2.Cu")
		(net 30)
	)
	(segment
		(start 152.038254 91.824234)
		(end 152.057518 91.836338)
		(width 0.1016)
		(layer "In2.Cu")
		(net 30)
	)
	(segment
		(start 152.499586 91.970608)
		(end 152.492072 91.992082)
		(width 0.1016)
		(layer "In2.Cu")
		(net 30)
	)
	(segment
		(start 152.022166 90.588946)
		(end 152.038254 90.605034)
		(width 0.1016)
		(layer "In2.Cu")
		(net 30)
	)
	(segment
		(start 152.010062 90.075117)
		(end 152.002548 90.096591)
		(width 0.1016)
		(layer "In2.Cu")
		(net 30)
	)
	(segment
		(start 152.1016 92.0496)
		(end 152.078992 92.052147)
		(width 0.1016)
		(layer "In2.Cu")
		(net 30)
	)
	(segment
		(start 152.3 88.5)
		(end 152 88.8)
		(width 0.1016)
		(layer "In2.Cu")
		(net 30)
	)
	(segment
		(start 152.502133 89.1032)
		(end 152.499586 89.125808)
		(width 0.1016)
		(layer "In2.Cu")
		(net 30)
	)
	(segment
		(start 152.038254 91.258965)
		(end 152.022166 91.275053)
		(width 0.1016)
		(layer "In2.Cu")
		(net 30)
	)
	(segment
		(start 152.423142 89.816947)
		(end 152.444616 89.824461)
		(width 0.1016)
		(layer "In2.Cu")
		(net 30)
	)
	(segment
		(start 152.038254 90.198634)
		(end 152.057518 90.210738)
		(width 0.1016)
		(layer "In2.Cu")
		(net 30)
	)
	(segment
		(start 152.002548 88.922608)
		(end 152.010062 88.944082)
		(width 0.1016)
		(layer "In2.Cu")
		(net 30)
	)
	(segment
		(start 152.444616 89.824461)
		(end 152.46388 89.836565)
		(width 0.1016)
		(layer "In2.Cu")
		(net 30)
	)
	(segment
		(start 152.492072 90.278317)
		(end 152.499586 90.299791)
		(width 0.1016)
		(layer "In2.Cu")
		(net 30)
	)
	(segment
		(start 152 91.7448)
		(end 152.002548 91.767408)
		(width 0.1016)
		(layer "In2.Cu")
		(net 30)
	)
	(segment
		(start 152.010062 91.382482)
		(end 152.022166 91.401746)
		(width 0.1016)
		(layer "In2.Cu")
		(net 30)
	)
	(segment
		(start 152.002548 89.690191)
		(end 152 89.7128)
		(width 0.1016)
		(layer "In2.Cu")
		(net 30)
	)
	(segment
		(start 152.499586 91.925391)
		(end 152.502133 91.948)
		(width 0.1016)
		(layer "In2.Cu")
		(net 30)
	)
	(segment
		(start 152 91.3384)
		(end 152.002548 91.361008)
		(width 0.1016)
		(layer "In2.Cu")
		(net 30)
	)
	(segment
		(start 152 92.1512)
		(end 152 92.6512)
		(width 0.1016)
		(layer "In2.Cu")
		(net 30)
	)
	(segment
		(start 152.400533 91.0336)
		(end 152.423142 91.036147)
		(width 0.1016)
		(layer "In2.Cu")
		(net 30)
	)
	(segment
		(start 152.492072 91.992082)
		(end 152.479968 92.011346)
		(width 0.1016)
		(layer "In2.Cu")
		(net 30)
	)
	(segment
		(start 152.078992 90.426547)
		(end 152.057518 90.434061)
		(width 0.1016)
		(layer "In2.Cu")
		(net 30)
	)
	(segment
		(start 152.038254 90.446165)
		(end 152.022166 90.462253)
		(width 0.1016)
		(layer "In2.Cu")
		(net 30)
	)
	(segment
		(start 152.400533 89.6112)
		(end 152.1016 89.6112)
		(width 0.1016)
		(layer "In2.Cu")
		(net 30)
	)
	(segment
		(start 152.038254 90.852565)
		(end 152.022166 90.868653)
		(width 0.1016)
		(layer "In2.Cu")
		(net 30)
	)
	(segment
		(start 152.425 87.25)
		(end 152.425 87.275)
		(width 0.1016)
		(layer "In2.Cu")
		(net 30)
	)
	(segment
		(start 152.502133 90.7288)
		(end 152.499586 90.751408)
		(width 0.1016)
		(layer "In2.Cu")
		(net 30)
	)
	(segment
		(start 152.492072 89.465517)
		(end 152.499586 89.486991)
		(width 0.1016)
		(layer "In2.Cu")
		(net 30)
	)
	(segment
		(start 152.479968 91.071853)
		(end 152.492072 91.091117)
		(width 0.1016)
		(layer "In2.Cu")
		(net 30)
	)
	(segment
		(start 152.444616 91.226738)
		(end 152.423142 91.234252)
		(width 0.1016)
		(layer "In2.Cu")
		(net 30)
	)
	(segment
		(start 152.022166 89.369746)
		(end 152.038254 89.385834)
		(width 0.1016)
		(layer "In2.Cu")
		(net 30)
	)
	(segment
		(start 152.002548 92.128591)
		(end 152 92.1512)
		(width 0.1016)
		(layer "In2.Cu")
		(net 30)
	)
	(segment
		(start 152.444616 91.633138)
		(end 152.423142 91.640652)
		(width 0.1016)
		(layer "In2.Cu")
		(net 30)
	)
	(segment
		(start 152.022166 90.868653)
		(end 152.010062 90.887917)
		(width 0.1016)
		(layer "In2.Cu")
		(net 30)
	)
	(segment
		(start 152.423142 89.410547)
		(end 152.444616 89.418061)
		(width 0.1016)
		(layer "In2.Cu")
		(net 30)
	)
	(segment
		(start 152.022166 91.401746)
		(end 152.038254 91.417834)
		(width 0.1016)
		(layer "In2.Cu")
		(net 30)
	)
	(segment
		(start 152.002548 90.096591)
		(end 152 90.1192)
		(width 0.1016)
		(layer "In2.Cu")
		(net 30)
	)
	(segment
		(start 152.010062 90.481517)
		(end 152.002548 90.502991)
		(width 0.1016)
		(layer "In2.Cu")
		(net 30)
	)
	(segment
		(start 152.010062 90.163282)
		(end 152.022166 90.182546)
		(width 0.1016)
		(layer "In2.Cu")
		(net 30)
	)
	(segment
		(start 152.057518 90.617138)
		(end 152.078992 90.624652)
		(width 0.1016)
		(layer "In2.Cu")
		(net 30)
	)
	(segment
		(start 152.46388 89.182634)
		(end 152.444616 89.194738)
		(width 0.1016)
		(layer "In2.Cu")
		(net 30)
	)
	(segment
		(start 152.400533 89.0016)
		(end 152.423142 89.004147)
		(width 0.1016)
		(layer "In2.Cu")
		(net 30)
	)
	(segment
		(start 152.002548 91.315791)
		(end 152 91.3384)
		(width 0.1016)
		(layer "In2.Cu")
		(net 30)
	)
	(segment
		(start 152.479968 91.604946)
		(end 152.46388 91.621034)
		(width 0.1016)
		(layer "In2.Cu")
		(net 30)
	)
	(segment
		(start 152.078992 91.239347)
		(end 152.057518 91.246861)
		(width 0.1016)
		(layer "In2.Cu")
		(net 30)
	)
	(segment
		(start 152.038254 92.071765)
		(end 152.022166 92.087853)
		(width 0.1016)
		(layer "In2.Cu")
		(net 30)
	)
	(segment
		(start 152.038254 91.011434)
		(end 152.057518 91.023538)
		(width 0.1016)
		(layer "In2.Cu")
		(net 30)
	)
	(segment
		(start 152.479968 92.011346)
		(end 152.46388 92.027434)
		(width 0.1016)
		(layer "In2.Cu")
		(net 30)
	)
	(segment
		(start 152.1016 89.8144)
		(end 152.400533 89.8144)
		(width 0.1016)
		(layer "In2.Cu")
		(net 30)
	)
	(segment
		(start 152.078992 89.811852)
		(end 152.1016 89.8144)
		(width 0.1016)
		(layer "In2.Cu")
		(net 30)
	)
	(segment
		(start 152.1016 90.424)
		(end 152.078992 90.426547)
		(width 0.1016)
		(layer "In2.Cu")
		(net 30)
	)
	(segment
		(start 152.057518 88.991538)
		(end 152.078992 88.999052)
		(width 0.1016)
		(layer "In2.Cu")
		(net 30)
	)
	(segment
		(start 152.022166 88.963346)
		(end 152.038254 88.979434)
		(width 0.1016)
		(layer "In2.Cu")
		(net 30)
	)
	(segment
		(start 152.499586 89.080591)
		(end 152.502133 89.1032)
		(width 0.1016)
		(layer "In2.Cu")
		(net 30)
	)
	(segment
		(start 152.078992 90.218252)
		(end 152.1016 90.2208)
		(width 0.1016)
		(layer "In2.Cu")
		(net 30)
	)
	(segment
		(start 152.499586 90.751408)
		(end 152.492072 90.772882)
		(width 0.1016)
		(layer "In2.Cu")
		(net 30)
	)
	(segment
		(start 152.078992 91.645747)
		(end 152.057518 91.653261)
		(width 0.1016)
		(layer "In2.Cu")
		(net 30)
	)
	(segment
		(start 152.078992 91.843852)
		(end 152.1016 91.8464)
		(width 0.1016)
		(layer "In2.Cu")
		(net 30)
	)
	(segment
		(start 152.038254 89.226965)
		(end 152.022166 89.243053)
		(width 0.1016)
		(layer "In2.Cu")
		(net 30)
	)
	(segment
		(start 152.400533 89.408)
		(end 152.423142 89.410547)
		(width 0.1016)
		(layer "In2.Cu")
		(net 30)
	)
	(segment
		(start 152.057518 91.429938)
		(end 152.078992 91.437452)
		(width 0.1016)
		(layer "In2.Cu")
		(net 30)
	)
	(segment
		(start 152.002548 89.735408)
		(end 152.010062 89.756882)
		(width 0.1016)
		(layer "In2.Cu")
		(net 30)
	)
	(segment
		(start 152.423142 89.004147)
		(end 152.444616 89.011661)
		(width 0.1016)
		(layer "In2.Cu")
		(net 30)
	)
	(segment
		(start 152.46388 91.462165)
		(end 152.479968 91.478253)
		(width 0.1016)
		(layer "In2.Cu")
		(net 30)
	)
	(segment
		(start 152.46388 92.027434)
		(end 152.444616 92.039538)
		(width 0.1016)
		(layer "In2.Cu")
		(net 30)
	)
	(segment
		(start 152.022166 90.182546)
		(end 152.038254 90.198634)
		(width 0.1016)
		(layer "In2.Cu")
		(net 30)
	)
	(segment
		(start 152.002548 89.329008)
		(end 152.010062 89.350482)
		(width 0.1016)
		(layer "In2.Cu")
		(net 30)
	)
	(segment
		(start 152.444616 90.820338)
		(end 152.423142 90.827852)
		(width 0.1016)
		(layer "In2.Cu")
		(net 30)
	)
	(segment
		(start 152.444616 90.230861)
		(end 152.46388 90.242965)
		(width 0.1016)
		(layer "In2.Cu")
		(net 30)
	)
	(segment
		(start 152.492072 91.091117)
		(end 152.499586 91.112591)
		(width 0.1016)
		(layer "In2.Cu")
		(net 30)
	)
	(segment
		(start 152.022166 91.808146)
		(end 152.038254 91.824234)
		(width 0.1016)
		(layer "In2.Cu")
		(net 30)
	)
	(segment
		(start 152.492072 89.960082)
		(end 152.479968 89.979346)
		(width 0.1016)
		(layer "In2.Cu")
		(net 30)
	)
	(segment
		(start 152.010062 89.350482)
		(end 152.022166 89.369746)
		(width 0.1016)
		(layer "In2.Cu")
		(net 30)
	)
	(segment
		(start 152.502133 91.5416)
		(end 152.499586 91.564208)
		(width 0.1016)
		(layer "In2.Cu")
		(net 30)
	)
	(segment
		(start 152.1016 89.0016)
		(end 152.400533 89.0016)
		(width 0.1016)
		(layer "In2.Cu")
		(net 30)
	)
	(segment
		(start 152.423142 90.421452)
		(end 152.400533 90.424)
		(width 0.1016)
		(layer "In2.Cu")
		(net 30)
	)
	(segment
		(start 152.423142 89.202252)
		(end 152.400533 89.2048)
		(width 0.1016)
		(layer "In2.Cu")
		(net 30)
	)
	(segment
		(start 152.499586 91.564208)
		(end 152.492072 91.585682)
		(width 0.1016)
		(layer "In2.Cu")
		(net 30)
	)
	(segment
		(start 152.479968 90.259053)
		(end 152.492072 90.278317)
		(width 0.1016)
		(layer "In2.Cu")
		(net 30)
	)
	(segment
		(start 152.423142 91.848947)
		(end 152.444616 91.856461)
		(width 0.1016)
		(layer "In2.Cu")
		(net 30)
	)
	(segment
		(start 152.400533 90.2208)
		(end 152.423142 90.223347)
		(width 0.1016)
		(layer "In2.Cu")
		(net 30)
	)
	(segment
		(start 152.492072 90.366482)
		(end 152.479968 90.385746)
		(width 0.1016)
		(layer "In2.Cu")
		(net 30)
	)
	(segment
		(start 152.078992 91.437452)
		(end 152.1016 91.44)
		(width 0.1016)
		(layer "In2.Cu")
		(net 30)
	)
	(segment
		(start 152.46388 91.214634)
		(end 152.444616 91.226738)
		(width 0.1016)
		(layer "In2.Cu")
		(net 30)
	)
	(segment
		(start 152 89.3064)
		(end 152.002548 89.329008)
		(width 0.1016)
		(layer "In2.Cu")
		(net 30)
	)
	(segment
		(start 152.002548 89.283791)
		(end 152 89.3064)
		(width 0.1016)
		(layer "In2.Cu")
		(net 30)
	)
	(segment
		(start 152 90.932)
		(end 152.002548 90.954608)
		(width 0.1016)
		(layer "In2.Cu")
		(net 30)
	)
	(segment
		(start 152.423142 90.223347)
		(end 152.444616 90.230861)
		(width 0.1016)
		(layer "In2.Cu")
		(net 30)
	)
	(segment
		(start 152 90.1192)
		(end 152.002548 90.141808)
		(width 0.1016)
		(layer "In2.Cu")
		(net 30)
	)
	(segment
		(start 152.499586 91.112591)
		(end 152.502133 91.1352)
		(width 0.1016)
		(layer "In2.Cu")
		(net 30)
	)
	(segment
		(start 152.492072 91.585682)
		(end 152.479968 91.604946)
		(width 0.1016)
		(layer "In2.Cu")
		(net 30)
	)
	(segment
		(start 152.479968 89.852653)
		(end 152.492072 89.871917)
		(width 0.1016)
		(layer "In2.Cu")
		(net 30)
	)
	(segment
		(start 152.1016 89.2048)
		(end 152.078992 89.207347)
		(width 0.1016)
		(layer "In2.Cu")
		(net 30)
	)
	(segment
		(start 152.010062 89.756882)
		(end 152.022166 89.776146)
		(width 0.1016)
		(layer "In2.Cu")
		(net 30)
	)
	(segment
		(start 152.400533 90.424)
		(end 152.1016 90.424)
		(width 0.1016)
		(layer "In2.Cu")
		(net 30)
	)
	(segment
		(start 152.444616 90.007538)
		(end 152.423142 90.015052)
		(width 0.1016)
		(layer "In2.Cu")
		(net 30)
	)
	(segment
		(start 152.078992 91.031052)
		(end 152.1016 91.0336)
		(width 0.1016)
		(layer "In2.Cu")
		(net 30)
	)
	(segment
		(start 152.502133 90.3224)
		(end 152.499586 90.345008)
		(width 0.1016)
		(layer "In2.Cu")
		(net 30)
	)
	(segment
		(start 152.46388 90.649365)
		(end 152.479968 90.665453)
		(width 0.1016)
		(layer "In2.Cu")
		(net 30)
	)
	(segment
		(start 152.502133 91.948)
		(end 152.499586 91.970608)
		(width 0.1016)
		(layer "In2.Cu")
		(net 30)
	)
	(segment
		(start 152.010062 90.976082)
		(end 152.022166 90.995346)
		(width 0.1016)
		(layer "In2.Cu")
		(net 30)
	)
	(segment
		(start 152 90.5256)
		(end 152.002548 90.548208)
		(width 0.1016)
		(layer "In2.Cu")
		(net 30)
	)
	(segment
		(start 152.479968 89.446253)
		(end 152.492072 89.465517)
		(width 0.1016)
		(layer "In2.Cu")
		(net 30)
	)
	(segment
		(start 152.022166 89.243053)
		(end 152.010062 89.262317)
		(width 0.1016)
		(layer "In2.Cu")
		(net 30)
	)
	(segment
		(start 152.002548 91.361008)
		(end 152.010062 91.382482)
		(width 0.1016)
		(layer "In2.Cu")
		(net 30)
	)
	(segment
		(start 152.423142 90.629747)
		(end 152.444616 90.637261)
		(width 0.1016)
		(layer "In2.Cu")
		(net 30)
	)
	(segment
		(start 152.444616 89.601138)
		(end 152.423142 89.608652)
		(width 0.1016)
		(layer "In2.Cu")
		(net 30)
	)
	(segment
		(start 152.46388 91.621034)
		(end 152.444616 91.633138)
		(width 0.1016)
		(layer "In2.Cu")
		(net 30)
	)
	(segment
		(start 152 92.6512)
		(end 152 92.7)
		(width 0.1016)
		(layer "In2.Cu")
		(net 30)
	)
	(segment
		(start 152.1016 91.44)
		(end 152.400533 91.44)
		(width 0.1016)
		(layer "In2.Cu")
		(net 30)
	)
	(segment
		(start 152.002548 91.722191)
		(end 152 91.7448)
		(width 0.1016)
		(layer "In2.Cu")
		(net 30)
	)
	(segment
		(start 152.1016 91.6432)
		(end 152.078992 91.645747)
		(width 0.1016)
		(layer "In2.Cu")
		(net 30)
	)
	(segment
		(start 152.499586 91.157808)
		(end 152.492072 91.179282)
		(width 0.1016)
		(layer "In2.Cu")
		(net 30)
	)
	(segment
		(start 152.444616 89.194738)
		(end 152.423142 89.202252)
		(width 0.1016)
		(layer "In2.Cu")
		(net 30)
	)
	(segment
		(start 152.46388 90.808234)
		(end 152.444616 90.820338)
		(width 0.1016)
		(layer "In2.Cu")
		(net 30)
	)
	(segment
		(start 152.425 87.275)
		(end 152.3 87.4)
		(width 0.1016)
		(layer "In2.Cu")
		(net 30)
	)
	(segment
		(start 152.499586 91.518991)
		(end 152.502133 91.5416)
		(width 0.1016)
		(layer "In2.Cu")
		(net 30)
	)
	(segment
		(start 152.400533 90.6272)
		(end 152.423142 90.629747)
		(width 0.1016)
		(layer "In2.Cu")
		(net 30)
	)
	(segment
		(start 152.444616 92.039538)
		(end 152.423142 92.047052)
		(width 0.1016)
		(layer "In2.Cu")
		(net 30)
	)
	(segment
		(start 152.1016 91.8464)
		(end 152.400533 91.8464)
		(width 0.1016)
		(layer "In2.Cu")
		(net 30)
	)
	(segment
		(start 152.479968 89.572946)
		(end 152.46388 89.589034)
		(width 0.1016)
		(layer "In2.Cu")
		(net 30)
	)
	(segment
		(start 152.057518 89.621261)
		(end 152.038254 89.633365)
		(width 0.1016)
		(layer "In2.Cu")
		(net 30)
	)
	(segment
		(start 152.502133 89.916)
		(end 152.499586 89.938608)
		(width 0.1016)
		(layer "In2.Cu")
		(net 30)
	)
	(segment
		(start 152.499586 90.706191)
		(end 152.502133 90.7288)
		(width 0.1016)
		(layer "In2.Cu")
		(net 30)
	)
	(segment
		(start 152.444616 90.637261)
		(end 152.46388 90.649365)
		(width 0.1016)
		(layer "In2.Cu")
		(net 30)
	)
	(segment
		(start 152.492072 91.903917)
		(end 152.499586 91.925391)
		(width 0.1016)
		(layer "In2.Cu")
		(net 30)
	)
	(segment
		(start 152.400533 89.2048)
		(end 152.1016 89.2048)
		(width 0.1016)
		(layer "In2.Cu")
		(net 30)
	)
	(segment
		(start 152.423142 92.047052)
		(end 152.400533 92.0496)
		(width 0.1016)
		(layer "In2.Cu")
		(net 30)
	)
	(segment
		(start 152.479968 91.198546)
		(end 152.46388 91.214634)
		(width 0.1016)
		(layer "In2.Cu")
		(net 30)
	)
	(segment
		(start 152.010062 91.700717)
		(end 152.002548 91.722191)
		(width 0.1016)
		(layer "In2.Cu")
		(net 30)
	)
	(segment
		(start 152.002548 90.909391)
		(end 152 90.932)
		(width 0.1016)
		(layer "In2.Cu")
		(net 30)
	)
	(segment
		(start 152.057518 89.214861)
		(end 152.038254 89.226965)
		(width 0.1016)
		(layer "In2.Cu")
		(net 30)
	)
	(segment
		(start 152.499586 89.938608)
		(end 152.492072 89.960082)
		(width 0.1016)
		(layer "In2.Cu")
		(net 30)
	)
	(segment
		(start 152 88.9)
		(end 152.002548 88.922608)
		(width 0.1016)
		(layer "In2.Cu")
		(net 30)
	)
	(segment
		(start 152.444616 90.413938)
		(end 152.423142 90.421452)
		(width 0.1016)
		(layer "In2.Cu")
		(net 30)
	)
	(segment
		(start 152.400533 91.2368)
		(end 152.1016 91.2368)
		(width 0.1016)
		(layer "In2.Cu")
		(net 30)
	)
	(segment
		(start 152.010062 89.668717)
		(end 152.002548 89.690191)
		(width 0.1016)
		(layer "In2.Cu")
		(net 30)
	)
	(segment
		(start 152.499586 90.345008)
		(end 152.492072 90.366482)
		(width 0.1016)
		(layer "In2.Cu")
		(net 30)
	)
	(segment
		(start 152.423142 91.036147)
		(end 152.444616 91.043661)
		(width 0.1016)
		(layer "In2.Cu")
		(net 30)
	)
	(segment
		(start 152.1016 90.6272)
		(end 152.400533 90.6272)
		(width 0.1016)
		(layer "In2.Cu")
		(net 30)
	)
	(segment
		(start 152.499586 90.299791)
		(end 152.502133 90.3224)
		(width 0.1016)
		(layer "In2.Cu")
		(net 30)
	)
	(segment
		(start 152.1016 91.0336)
		(end 152.400533 91.0336)
		(width 0.1016)
		(layer "In2.Cu")
		(net 30)
	)
	(segment
		(start 152.022166 90.462253)
		(end 152.010062 90.481517)
		(width 0.1016)
		(layer "In2.Cu")
		(net 30)
	)
	(segment
		(start 152.078992 90.832947)
		(end 152.057518 90.840461)
		(width 0.1016)
		(layer "In2.Cu")
		(net 30)
	)
	(segment
		(start 152.1016 91.2368)
		(end 152.078992 91.239347)
		(width 0.1016)
		(layer "In2.Cu")
		(net 30)
	)
	(segment
		(start 152.022166 89.776146)
		(end 152.038254 89.792234)
		(width 0.1016)
		(layer "In2.Cu")
		(net 30)
	)
	(segment
		(start 152.46388 90.242965)
		(end 152.479968 90.259053)
		(width 0.1016)
		(layer "In2.Cu")
		(net 30)
	)
	(segment
		(start 152.479968 90.665453)
		(end 152.492072 90.684717)
		(width 0.1016)
		(layer "In2.Cu")
		(net 30)
	)
	(segment
		(start 152.057518 89.397938)
		(end 152.078992 89.405452)
		(width 0.1016)
		(layer "In2.Cu")
		(net 30)
	)
	(segment
		(start 152.492072 89.147282)
		(end 152.479968 89.166546)
		(width 0.1016)
		(layer "In2.Cu")
		(net 30)
	)
	(segment
		(start 152.010062 92.107117)
		(end 152.002548 92.128591)
		(width 0.1016)
		(layer "In2.Cu")
		(net 30)
	)
	(segment
		(start 152.038254 89.633365)
		(end 152.022166 89.649453)
		(width 0.1016)
		(layer "In2.Cu")
		(net 30)
	)
	(segment
		(start 152.078992 90.624652)
		(end 152.1016 90.6272)
		(width 0.1016)
		(layer "In2.Cu")
		(net 30)
	)
	(segment
		(start 153.215 83.24)
		(end 152.825 82.85)
		(width 0.145)
		(layer "F.Cu")
		(net 31)
	)
	(segment
		(start 153.22 83.24)
		(end 153.215 83.24)
		(width 0.145)
		(layer "F.Cu")
		(net 31)
	)
	(via
		(at 153.3 92.7)
		(size 0.45)
		(drill 0.15)
		(layers "F.Cu" "B.Cu")
		(net 31)
	)
	(via
		(at 153.22 83.24)
		(size 0.45)
		(drill 0.15)
		(layers "F.Cu" "B.Cu")
		(net 31)
	)
	(segment
		(start 153.3 92.7)
		(end 153.3 93.4)
		(width 0.145)
		(layer "B.Cu")
		(net 31)
	)
	(segment
		(start 153.3 93.4)
		(end 153.1 93.6)
		(width 0.145)
		(layer "B.Cu")
		(net 31)
	)
	(segment
		(start 149.675 96.225)
		(end 149.675 98.7)
		(width 0.145)
		(layer "B.Cu")
		(net 31)
	)
	(segment
		(start 152.3 93.6)
		(end 149.675 96.225)
		(width 0.145)
		(layer "B.Cu")
		(net 31)
	)
	(segment
		(start 153.1 93.6)
		(end 152.3 93.6)
		(width 0.145)
		(layer "B.Cu")
		(net 31)
	)
	(segment
		(start 153.22 83.6736)
		(end 153.22 83.291003)
		(width 0.1016)
		(layer "In2.Cu")
		(net 31)
	)
	(segment
		(start 153.602401 86.862401)
		(end 153.22 86.48)
		(width 0.1016)
		(layer "In2.Cu")
		(net 31)
	)
	(segment
		(start 153.3216 85.228)
		(end 153.298992 85.225452)
		(width 0.1016)
		(layer "In2.Cu")
		(net 31)
	)
	(segment
		(start 153.22 83.291003)
		(end 153.22 83.24)
		(width 0.1016)
		(layer "In2.Cu")
		(net 31)
	)
	(segment
		(start 153.242165 83.736946)
		(end 153.230061 83.717682)
		(width 0.1016)
		(layer "In2.Cu")
		(net 31)
	)
	(segment
		(start 153.565218 83.813453)
		(end 153.54913 83.797365)
		(width 0.1016)
		(layer "In2.Cu")
		(net 31)
	)
	(segment
		(start 153.222548 85.555408)
		(end 153.22 85.5328)
		(width 0.1016)
		(layer "In2.Cu")
		(net 31)
	)
	(segment
		(start 153.298992 85.027347)
		(end 153.3216 85.0248)
		(width 0.1016)
		(layer "In2.Cu")
		(net 31)
	)
	(segment
		(start 153.547835 85.266253)
		(end 153.531747 85.250165)
		(width 0.1016)
		(layer "In2.Cu")
		(net 31)
	)
	(segment
		(start 153.277518 85.847661)
		(end 153.298992 85.840147)
		(width 0.1016)
		(layer "In2.Cu")
		(net 31)
	)
	(segment
		(start 153.512483 85.644461)
		(end 153.491009 85.636947)
		(width 0.1016)
		(layer "In2.Cu")
		(net 31)
	)
	(segment
		(start 153.297599 92.697599)
		(end 153.297599 89.439838)
		(width 0.1016)
		(layer "In2.Cu")
		(net 31)
	)
	(segment
		(start 153.242166 85.469453)
		(end 153.258254 85.453365)
		(width 0.1016)
		(layer "In2.Cu")
		(net 31)
	)
	(segment
		(start 153.277517 83.988461)
		(end 153.298991 83.980947)
		(width 0.1016)
		(layer "In2.Cu")
		(net 31)
	)
	(segment
		(start 153.531747 85.815434)
		(end 153.547835 85.799346)
		(width 0.1016)
		(layer "In2.Cu")
		(net 31)
	)
	(segment
		(start 153.22 84.72)
		(end 153.22 84.08)
		(width 0.1016)
		(layer "In2.Cu")
		(net 31)
	)
	(segment
		(start 153.567453 84.900591)
		(end 153.559939 84.879117)
		(width 0.1016)
		(layer "In2.Cu")
		(net 31)
	)
	(segment
		(start 153.531747 85.250165)
		(end 153.512483 85.238061)
		(width 0.1016)
		(layer "In2.Cu")
		(net 31)
	)
	(segment
		(start 153.230062 84.764082)
		(end 153.222548 84.742608)
		(width 0.1016)
		(layer "In2.Cu")
		(net 31)
	)
	(segment
		(start 153.531747 85.409034)
		(end 153.547835 85.392946)
		(width 0.1016)
		(layer "In2.Cu")
		(net 31)
	)
	(segment
		(start 153.4684 85.0248)
		(end 153.491009 85.022252)
		(width 0.1016)
		(layer "In2.Cu")
		(net 31)
	)
	(segment
		(start 153.567453 85.306991)
		(end 153.559939 85.285517)
		(width 0.1016)
		(layer "In2.Cu")
		(net 31)
	)
	(segment
		(start 153.567453 85.713391)
		(end 153.559939 85.691917)
		(width 0.1016)
		(layer "In2.Cu")
		(net 31)
	)
	(segment
		(start 153.297599 89.439838)
		(end 153.602401 89.135036)
		(width 0.1016)
		(layer "In2.Cu")
		(net 31)
	)
	(segment
		(start 153.491009 85.835052)
		(end 153.512483 85.827538)
		(width 0.1016)
		(layer "In2.Cu")
		(net 31)
	)
	(segment
		(start 153.222548 85.510191)
		(end 153.230062 85.488717)
		(width 0.1016)
		(layer "In2.Cu")
		(net 31)
	)
	(segment
		(start 153.258253 83.753034)
		(end 153.242165 83.736946)
		(width 0.1016)
		(layer "In2.Cu")
		(net 31)
	)
	(segment
		(start 153.485784 83.7752)
		(end 153.3216 83.7752)
		(width 0.1016)
		(layer "In2.Cu")
		(net 31)
	)
	(segment
		(start 153.559939 85.373682)
		(end 153.567453 85.352208)
		(width 0.1016)
		(layer "In2.Cu")
		(net 31)
	)
	(segment
		(start 153.54913 83.956234)
		(end 153.565218 83.940146)
		(width 0.1016)
		(layer "In2.Cu")
		(net 31)
	)
	(segment
		(start 153.531747 85.656565)
		(end 153.512483 85.644461)
		(width 0.1016)
		(layer "In2.Cu")
		(net 31)
	)
	(segment
		(start 153.222547 84.057391)
		(end 153.230061 84.035917)
		(width 0.1016)
		(layer "In2.Cu")
		(net 31)
	)
	(segment
		(start 153.531747 84.843765)
		(end 153.512483 84.831661)
		(width 0.1016)
		(layer "In2.Cu")
		(net 31)
	)
	(segment
		(start 153.491009 85.230547)
		(end 153.4684 85.228)
		(width 0.1016)
		(layer "In2.Cu")
		(net 31)
	)
	(segment
		(start 153.559939 85.780082)
		(end 153.567453 85.758608)
		(width 0.1016)
		(layer "In2.Cu")
		(net 31)
	)
	(segment
		(start 153.298991 83.772652)
		(end 153.277517 83.765138)
		(width 0.1016)
		(layer "In2.Cu")
		(net 31)
	)
	(segment
		(start 153.565218 83.940146)
		(end 153.577322 83.920882)
		(width 0.1016)
		(layer "In2.Cu")
		(net 31)
	)
	(segment
		(start 153.4684 85.228)
		(end 153.3216 85.228)
		(width 0.1016)
		(layer "In2.Cu")
		(net 31)
	)
	(segment
		(start 153.547835 84.859853)
		(end 153.531747 84.843765)
		(width 0.1016)
		(layer "In2.Cu")
		(net 31)
	)
	(segment
		(start 153.559939 84.879117)
		(end 153.547835 84.859853)
		(width 0.1016)
		(layer "In2.Cu")
		(net 31)
	)
	(segment
		(start 153.242166 84.783346)
		(end 153.230062 84.764082)
		(width 0.1016)
		(layer "In2.Cu")
		(net 31)
	)
	(segment
		(start 153.4684 85.8376)
		(end 153.491009 85.835052)
		(width 0.1016)
		(layer "In2.Cu")
		(net 31)
	)
	(segment
		(start 153.491009 85.428652)
		(end 153.512483 85.421138)
		(width 0.1016)
		(layer "In2.Cu")
		(net 31)
	)
	(segment
		(start 153.508392 83.777747)
		(end 153.485784 83.7752)
		(width 0.1016)
		(layer "In2.Cu")
		(net 31)
	)
	(segment
		(start 153.3216 85.8376)
		(end 153.4684 85.8376)
		(width 0.1016)
		(layer "In2.Cu")
		(net 31)
	)
	(segment
		(start 153.242166 85.189746)
		(end 153.230062 85.170482)
		(width 0.1016)
		(layer "In2.Cu")
		(net 31)
	)
	(segment
		(start 153.277518 85.441261)
		(end 153.298992 85.433747)
		(width 0.1016)
		(layer "In2.Cu")
		(net 31)
	)
	(segment
		(start 153.3216 83.9784)
		(end 153.485784 83.9784)
		(width 0.1016)
		(layer "In2.Cu")
		(net 31)
	)
	(segment
		(start 153.57 85.736)
		(end 153.567453 85.713391)
		(width 0.1016)
		(layer "In2.Cu")
		(net 31)
	)
	(segment
		(start 153.3216 85.4312)
		(end 153.4684 85.4312)
		(width 0.1016)
		(layer "In2.Cu")
		(net 31)
	)
	(segment
		(start 153.491009 85.022252)
		(end 153.512483 85.014738)
		(width 0.1016)
		(layer "In2.Cu")
		(net 31)
	)
	(segment
		(start 153.547835 85.392946)
		(end 153.559939 85.373682)
		(width 0.1016)
		(layer "In2.Cu")
		(net 31)
	)
	(segment
		(start 153.298991 83.980947)
		(end 153.3216 83.9784)
		(width 0.1016)
		(layer "In2.Cu")
		(net 31)
	)
	(segment
		(start 153.258254 85.453365)
		(end 153.277518 85.441261)
		(width 0.1016)
		(layer "In2.Cu")
		(net 31)
	)
	(segment
		(start 153.258254 85.859765)
		(end 153.277518 85.847661)
		(width 0.1016)
		(layer "In2.Cu")
		(net 31)
	)
	(segment
		(start 153.587384 83.8768)
		(end 153.584836 83.854191)
		(width 0.1016)
		(layer "In2.Cu")
		(net 31)
	)
	(segment
		(start 153.298992 84.819052)
		(end 153.277518 84.811538)
		(width 0.1016)
		(layer "In2.Cu")
		(net 31)
	)
	(segment
		(start 153.298992 85.840147)
		(end 153.3216 85.8376)
		(width 0.1016)
		(layer "In2.Cu")
		(net 31)
	)
	(segment
		(start 153.559939 84.967282)
		(end 153.567453 84.945808)
		(width 0.1016)
		(layer "In2.Cu")
		(net 31)
	)
	(segment
		(start 153.3216 84.8216)
		(end 153.298992 84.819052)
		(width 0.1016)
		(layer "In2.Cu")
		(net 31)
	)
	(segment
		(start 153.529866 83.968338)
		(end 153.54913 83.956234)
		(width 0.1016)
		(layer "In2.Cu")
		(net 31)
	)
	(segment
		(start 153.512483 85.421138)
		(end 153.531747 85.409034)
		(width 0.1016)
		(layer "In2.Cu")
		(net 31)
	)
	(segment
		(start 153.242166 85.875853)
		(end 153.258254 85.859765)
		(width 0.1016)
		(layer "In2.Cu")
		(net 31)
	)
	(segment
		(start 153.54913 83.797365)
		(end 153.529866 83.785261)
		(width 0.1016)
		(layer "In2.Cu")
		(net 31)
	)
	(segment
		(start 153.512483 85.238061)
		(end 153.491009 85.230547)
		(width 0.1016)
		(layer "In2.Cu")
		(net 31)
	)
	(segment
		(start 153.567453 84.945808)
		(end 153.57 84.9232)
		(width 0.1016)
		(layer "In2.Cu")
		(net 31)
	)
	(segment
		(start 153.602401 89.135036)
		(end 153.602401 86.862401)
		(width 0.1016)
		(layer "In2.Cu")
		(net 31)
	)
	(segment
		(start 153.258253 84.000565)
		(end 153.277517 83.988461)
		(width 0.1016)
		(layer "In2.Cu")
		(net 31)
	)
	(segment
		(start 153.242166 85.063053)
		(end 153.258254 85.046965)
		(width 0.1016)
		(layer "In2.Cu")
		(net 31)
	)
	(segment
		(start 153.222547 83.696208)
		(end 153.22 83.6736)
		(width 0.1016)
		(layer "In2.Cu")
		(net 31)
	)
	(segment
		(start 153.3216 83.7752)
		(end 153.298991 83.772652)
		(width 0.1016)
		(layer "In2.Cu")
		(net 31)
	)
	(segment
		(start 153.22 85.1264)
		(end 153.222548 85.103791)
		(width 0.1016)
		(layer "In2.Cu")
		(net 31)
	)
	(segment
		(start 153.4684 85.6344)
		(end 153.3216 85.6344)
		(width 0.1016)
		(layer "In2.Cu")
		(net 31)
	)
	(segment
		(start 153.4684 84.8216)
		(end 153.3216 84.8216)
		(width 0.1016)
		(layer "In2.Cu")
		(net 31)
	)
	(segment
		(start 153.559939 85.691917)
		(end 153.547835 85.672653)
		(width 0.1016)
		(layer "In2.Cu")
		(net 31)
	)
	(segment
		(start 153.485784 83.9784)
		(end 153.508392 83.975852)
		(width 0.1016)
		(layer "In2.Cu")
		(net 31)
	)
	(segment
		(start 153.559939 85.285517)
		(end 153.547835 85.266253)
		(width 0.1016)
		(layer "In2.Cu")
		(net 31)
	)
	(segment
		(start 153.230062 85.576882)
		(end 153.222548 85.555408)
		(width 0.1016)
		(layer "In2.Cu")
		(net 31)
	)
	(segment
		(start 153.277518 85.034861)
		(end 153.298992 85.027347)
		(width 0.1016)
		(layer "In2.Cu")
		(net 31)
	)
	(segment
		(start 153.258254 85.046965)
		(end 153.277518 85.034861)
		(width 0.1016)
		(layer "In2.Cu")
		(net 31)
	)
	(segment
		(start 153.258254 84.799434)
		(end 153.242166 84.783346)
		(width 0.1016)
		(layer "In2.Cu")
		(net 31)
	)
	(segment
		(start 153.567453 85.352208)
		(end 153.57 85.3296)
		(width 0.1016)
		(layer "In2.Cu")
		(net 31)
	)
	(segment
		(start 153.230062 85.170482)
		(end 153.222548 85.149008)
		(width 0.1016)
		(layer "In2.Cu")
		(net 31)
	)
	(segment
		(start 153.230062 85.082317)
		(end 153.242166 85.063053)
		(width 0.1016)
		(layer "In2.Cu")
		(net 31)
	)
	(segment
		(start 153.4684 85.4312)
		(end 153.491009 85.428652)
		(width 0.1016)
		(layer "In2.Cu")
		(net 31)
	)
	(segment
		(start 153.3216 85.6344)
		(end 153.298992 85.631852)
		(width 0.1016)
		(layer "In2.Cu")
		(net 31)
	)
	(segment
		(start 153.298992 85.433747)
		(end 153.3216 85.4312)
		(width 0.1016)
		(layer "In2.Cu")
		(net 31)
	)
	(segment
		(start 153.577322 83.832717)
		(end 153.565218 83.813453)
		(width 0.1016)
		(layer "In2.Cu")
		(net 31)
	)
	(segment
		(start 153.222548 85.103791)
		(end 153.230062 85.082317)
		(width 0.1016)
		(layer "In2.Cu")
		(net 31)
	)
	(segment
		(start 153.547835 85.799346)
		(end 153.559939 85.780082)
		(width 0.1016)
		(layer "In2.Cu")
		(net 31)
	)
	(segment
		(start 153.512483 84.831661)
		(end 153.491009 84.824147)
		(width 0.1016)
		(layer "In2.Cu")
		(net 31)
	)
	(segment
		(start 153.57 84.9232)
		(end 153.567453 84.900591)
		(width 0.1016)
		(layer "In2.Cu")
		(net 31)
	)
	(segment
		(start 153.22 85.5328)
		(end 153.222548 85.510191)
		(width 0.1016)
		(layer "In2.Cu")
		(net 31)
	)
	(segment
		(start 153.508392 83.975852)
		(end 153.529866 83.968338)
		(width 0.1016)
		(layer "In2.Cu")
		(net 31)
	)
	(segment
		(start 153.258254 85.612234)
		(end 153.242166 85.596146)
		(width 0.1016)
		(layer "In2.Cu")
		(net 31)
	)
	(segment
		(start 153.22 84.08)
		(end 153.222547 84.057391)
		(width 0.1016)
		(layer "In2.Cu")
		(net 31)
	)
	(segment
		(start 153.298992 85.225452)
		(end 153.277518 85.217938)
		(width 0.1016)
		(layer "In2.Cu")
		(net 31)
	)
	(segment
		(start 153.567453 85.758608)
		(end 153.57 85.736)
		(width 0.1016)
		(layer "In2.Cu")
		(net 31)
	)
	(segment
		(start 153.584836 83.899408)
		(end 153.587384 83.8768)
		(width 0.1016)
		(layer "In2.Cu")
		(net 31)
	)
	(segment
		(start 153.3216 85.0248)
		(end 153.4684 85.0248)
		(width 0.1016)
		(layer "In2.Cu")
		(net 31)
	)
	(segment
		(start 153.22 85.9392)
		(end 153.222548 85.916591)
		(width 0.1016)
		(layer "In2.Cu")
		(net 31)
	)
	(segment
		(start 153.512483 85.014738)
		(end 153.531747 85.002634)
		(width 0.1016)
		(layer "In2.Cu")
		(net 31)
	)
	(segment
		(start 153.230062 85.895117)
		(end 153.242166 85.875853)
		(width 0.1016)
		(layer "In2.Cu")
		(net 31)
	)
	(segment
		(start 153.3 92.7)
		(end 153.297599 92.697599)
		(width 0.1016)
		(layer "In2.Cu")
		(net 31)
	)
	(segment
		(start 153.277518 84.811538)
		(end 153.258254 84.799434)
		(width 0.1016)
		(layer "In2.Cu")
		(net 31)
	)
	(segment
		(start 153.512483 85.827538)
		(end 153.531747 85.815434)
		(width 0.1016)
		(layer "In2.Cu")
		(net 31)
	)
	(segment
		(start 153.242165 84.016653)
		(end 153.258253 84.000565)
		(width 0.1016)
		(layer "In2.Cu")
		(net 31)
	)
	(segment
		(start 153.277518 85.217938)
		(end 153.258254 85.205834)
		(width 0.1016)
		(layer "In2.Cu")
		(net 31)
	)
	(segment
		(start 153.547835 85.672653)
		(end 153.531747 85.656565)
		(width 0.1016)
		(layer "In2.Cu")
		(net 31)
	)
	(segment
		(start 153.277518 85.624338)
		(end 153.258254 85.612234)
		(width 0.1016)
		(layer "In2.Cu")
		(net 31)
	)
	(segment
		(start 153.584836 83.854191)
		(end 153.577322 83.832717)
		(width 0.1016)
		(layer "In2.Cu")
		(net 31)
	)
	(segment
		(start 153.230062 85.488717)
		(end 153.242166 85.469453)
		(width 0.1016)
		(layer "In2.Cu")
		(net 31)
	)
	(segment
		(start 153.258254 85.205834)
		(end 153.242166 85.189746)
		(width 0.1016)
		(layer "In2.Cu")
		(net 31)
	)
	(segment
		(start 153.242166 85.596146)
		(end 153.230062 85.576882)
		(width 0.1016)
		(layer "In2.Cu")
		(net 31)
	)
	(segment
		(start 153.529866 83.785261)
		(end 153.508392 83.777747)
		(width 0.1016)
		(layer "In2.Cu")
		(net 31)
	)
	(segment
		(start 153.230061 84.035917)
		(end 153.242165 84.016653)
		(width 0.1016)
		(layer "In2.Cu")
		(net 31)
	)
	(segment
		(start 153.222548 85.916591)
		(end 153.230062 85.895117)
		(width 0.1016)
		(layer "In2.Cu")
		(net 31)
	)
	(segment
		(start 153.577322 83.920882)
		(end 153.584836 83.899408)
		(width 0.1016)
		(layer "In2.Cu")
		(net 31)
	)
	(segment
		(start 153.22 86.48)
		(end 153.22 85.9392)
		(width 0.1016)
		(layer "In2.Cu")
		(net 31)
	)
	(segment
		(start 153.491009 85.636947)
		(end 153.4684 85.6344)
		(width 0.1016)
		(layer "In2.Cu")
		(net 31)
	)
	(segment
		(start 153.491009 84.824147)
		(end 153.4684 84.8216)
		(width 0.1016)
		(layer "In2.Cu")
		(net 31)
	)
	(segment
		(start 153.531747 85.002634)
		(end 153.547835 84.986546)
		(width 0.1016)
		(layer "In2.Cu")
		(net 31)
	)
	(segment
		(start 153.222548 85.149008)
		(end 153.22 85.1264)
		(width 0.1016)
		(layer "In2.Cu")
		(net 31)
	)
	(segment
		(start 153.57 85.3296)
		(end 153.567453 85.306991)
		(width 0.1016)
		(layer "In2.Cu")
		(net 31)
	)
	(segment
		(start 153.547835 84.986546)
		(end 153.559939 84.967282)
		(width 0.1016)
		(layer "In2.Cu")
		(net 31)
	)
	(segment
		(start 153.298992 85.631852)
		(end 153.277518 85.624338)
		(width 0.1016)
		(layer "In2.Cu")
		(net 31)
	)
	(segment
		(start 153.222548 84.742608)
		(end 153.22 84.72)
		(width 0.1016)
		(layer "In2.Cu")
		(net 31)
	)
	(segment
		(start 153.277517 83.765138)
		(end 153.258253 83.753034)
		(width 0.1016)
		(layer "In2.Cu")
		(net 31)
	)
	(segment
		(start 153.230061 83.717682)
		(end 153.222547 83.696208)
		(width 0.1016)
		(layer "In2.Cu")
		(net 31)
	)
	(segment
		(start 144.425 96.625)
		(end 143.175 95.375)
		(width 0.145)
		(layer "F.Cu")
		(net 32)
	)
	(segment
		(start 147.225 82.85)
		(end 147.625 83.25)
		(width 0.145)
		(layer "F.Cu")
		(net 32)
	)
	(segment
		(start 144.425 98.7)
		(end 144.425 96.625)
		(width 0.145)
		(layer "F.Cu")
		(net 32)
	)
	(segment
		(start 143.175 95.375)
		(end 143.175 92.7)
		(width 0.145)
		(layer "F.Cu")
		(net 32)
	)
	(via
		(at 143.175 92.7)
		(size 0.45)
		(drill 0.15)
		(layers "F.Cu" "B.Cu")
		(net 32)
	)
	(via
		(at 147.625 83.25)
		(size 0.45)
		(drill 0.15)
		(layers "F.Cu" "B.Cu")
		(net 32)
	)
	(segment
		(start 143.228806 91.807529)
		(end 143.259605 91.804058)
		(width 0.1016)
		(layer "In2.Cu")
		(net 32)
	)
	(segment
		(start 143.259605 90.579064)
		(end 143.274233 90.573946)
		(width 0.1016)
		(layer "In2.Cu")
		(net 32)
	)
	(segment
		(start 143.062645 91.175301)
		(end 143.051687 91.164343)
		(width 0.1016)
		(layer "In2.Cu")
		(net 32)
	)
	(segment
		(start 143.306558 90.823178)
		(end 143.298313 90.810056)
		(width 0.1016)
		(layer "In2.Cu")
		(net 32)
	)
	(segment
		(start 143.311676 91.751987)
		(end 143.313412 91.736588)
		(width 0.1016)
		(layer "In2.Cu")
		(net 32)
	)
	(segment
		(start 143.298313 91.779737)
		(end 143.306558 91.766615)
		(width 0.1016)
		(layer "In2.Cu")
		(net 32)
	)
	(segment
		(start 143.306558 90.541621)
		(end 143.311676 90.526993)
		(width 0.1016)
		(layer "In2.Cu")
		(net 32)
	)
	(segment
		(start 143.062645 91.002298)
		(end 143.075767 90.994053)
		(width 0.1016)
		(layer "In2.Cu")
		(net 32)
	)
	(segment
		(start 143.274233 90.573946)
		(end 143.287355 90.565701)
		(width 0.1016)
		(layer "In2.Cu")
		(net 32)
	)
	(segment
		(start 143.298313 91.367543)
		(end 143.306558 91.354421)
		(width 0.1016)
		(layer "In2.Cu")
		(net 32)
	)
	(segment
		(start 143.051687 91.164343)
		(end 143.043442 91.151221)
		(width 0.1016)
		(layer "In2.Cu")
		(net 32)
	)
	(segment
		(start 143.036588 91.527594)
		(end 143.036588 91.462806)
		(width 0.1016)
		(layer "In2.Cu")
		(net 32)
	)
	(segment
		(start 143.105794 90.9872)
		(end 143.244206 90.9872)
		(width 0.1016)
		(layer "In2.Cu")
		(net 32)
	)
	(segment
		(start 143.311676 90.837806)
		(end 143.306558 90.823178)
		(width 0.1016)
		(layer "In2.Cu")
		(net 32)
	)
	(segment
		(start 143.298313 90.554743)
		(end 143.306558 90.541621)
		(width 0.1016)
		(layer "In2.Cu")
		(net 32)
	)
	(segment
		(start 143.59105 84.73395)
		(end 147.375 84.73395)
		(width 0.1016)
		(layer "In2.Cu")
		(net 32)
	)
	(segment
		(start 143.043442 91.432778)
		(end 143.051687 91.419656)
		(width 0.1016)
		(layer "In2.Cu")
		(net 32)
	)
	(segment
		(start 143.311676 91.339793)
		(end 143.313412 91.324394)
		(width 0.1016)
		(layer "In2.Cu")
		(net 32)
	)
	(segment
		(start 143.306558 90.948021)
		(end 143.311676 90.933393)
		(width 0.1016)
		(layer "In2.Cu")
		(net 32)
	)
	(segment
		(start 143.051687 91.570743)
		(end 143.043442 91.557621)
		(width 0.1016)
		(layer "In2.Cu")
		(net 32)
	)
	(segment
		(start 143.259605 90.379335)
		(end 143.228806 90.375864)
		(width 0.1016)
		(layer "In2.Cu")
		(net 32)
	)
	(segment
		(start 143.306558 91.229578)
		(end 143.298313 91.216456)
		(width 0.1016)
		(layer "In2.Cu")
		(net 32)
	)
	(segment
		(start 143.062645 90.768901)
		(end 143.051687 90.757943)
		(width 0.1016)
		(layer "In2.Cu")
		(net 32)
	)
	(segment
		(start 143.105794 91.5968)
		(end 143.090395 91.595064)
		(width 0.1016)
		(layer "In2.Cu")
		(net 32)
	)
	(segment
		(start 143.313412 90.446806)
		(end 143.311676 90.431406)
		(width 0.1016)
		(layer "In2.Cu")
		(net 32)
	)
	(segment
		(start 143.274233 91.386746)
		(end 143.287355 91.378501)
		(width 0.1016)
		(layer "In2.Cu")
		(net 32)
	)
	(segment
		(start 143.259605 91.391864)
		(end 143.274233 91.386746)
		(width 0.1016)
		(layer "In2.Cu")
		(net 32)
	)
	(segment
		(start 143.062645 91.408698)
		(end 143.075767 91.400453)
		(width 0.1016)
		(layer "In2.Cu")
		(net 32)
	)
	(segment
		(start 143.036588 90.714794)
		(end 143.036588 90.650006)
		(width 0.1016)
		(layer "In2.Cu")
		(net 32)
	)
	(segment
		(start 143.244206 90.784)
		(end 143.105794 90.784)
		(width 0.1016)
		(layer "In2.Cu")
		(net 32)
	)
	(segment
		(start 143.259605 91.192135)
		(end 143.244206 91.1904)
		(width 0.1016)
		(layer "In2.Cu")
		(net 32)
	)
	(segment
		(start 143.036588 91.056406)
		(end 143.038324 91.041006)
		(width 0.1016)
		(layer "In2.Cu")
		(net 32)
	)
	(segment
		(start 143.306558 91.354421)
		(end 143.311676 91.339793)
		(width 0.1016)
		(layer "In2.Cu")
		(net 32)
	)
	(segment
		(start 143.298313 91.216456)
		(end 143.287355 91.205498)
		(width 0.1016)
		(layer "In2.Cu")
		(net 32)
	)
	(segment
		(start 143.274233 90.384453)
		(end 143.259605 90.379335)
		(width 0.1016)
		(layer "In2.Cu")
		(net 32)
	)
	(segment
		(start 143.287355 90.972101)
		(end 143.298313 90.961143)
		(width 0.1016)
		(layer "In2.Cu")
		(net 32)
	)
	(segment
		(start 143.287355 90.565701)
		(end 143.298313 90.554743)
		(width 0.1016)
		(layer "In2.Cu")
		(net 32)
	)
	(segment
		(start 143.244206 90.9872)
		(end 143.259605 90.985464)
		(width 0.1016)
		(layer "In2.Cu")
		(net 32)
	)
	(segment
		(start 143.313412 90.917994)
		(end 143.313412 90.853206)
		(width 0.1016)
		(layer "In2.Cu")
		(net 32)
	)
	(segment
		(start 143.190098 90.351543)
		(end 143.181853 90.338421)
		(width 0.1016)
		(layer "In2.Cu")
		(net 32)
	)
	(segment
		(start 143.051687 90.757943)
		(end 143.043442 90.744821)
		(width 0.1016)
		(layer "In2.Cu")
		(net 32)
	)
	(segment
		(start 143.176735 90.323793)
		(end 143.175 90.308394)
		(width 0.1016)
		(layer "In2.Cu")
		(net 32)
	)
	(segment
		(start 143.038324 91.447406)
		(end 143.043442 91.432778)
		(width 0.1016)
		(layer "In2.Cu")
		(net 32)
	)
	(segment
		(start 143.313412 91.324394)
		(end 143.313412 91.259606)
		(width 0.1016)
		(layer "In2.Cu")
		(net 32)
	)
	(segment
		(start 143.090395 91.395335)
		(end 143.105794 91.3936)
		(width 0.1016)
		(layer "In2.Cu")
		(net 32)
	)
	(segment
		(start 143.298313 90.810056)
		(end 143.287355 90.799098)
		(width 0.1016)
		(layer "In2.Cu")
		(net 32)
	)
	(segment
		(start 143.274233 91.79894)
		(end 143.287355 91.790695)
		(width 0.1016)
		(layer "In2.Cu")
		(net 32)
	)
	(segment
		(start 143.051687 90.606856)
		(end 143.062645 90.595898)
		(width 0.1016)
		(layer "In2.Cu")
		(net 32)
	)
	(segment
		(start 143.313412 91.6718)
		(end 143.311676 91.6564)
		(width 0.1016)
		(layer "In2.Cu")
		(net 32)
	)
	(segment
		(start 143.259605 91.604329)
		(end 143.244206 91.602594)
		(width 0.1016)
		(layer "In2.Cu")
		(net 32)
	)
	(segment
		(start 143.175 91.602594)
		(end 143.175 91.5968)
		(width 0.1016)
		(layer "In2.Cu")
		(net 32)
	)
	(segment
		(start 143.190098 91.83185)
		(end 143.201056 91.820892)
		(width 0.1016)
		(layer "In2.Cu")
		(net 32)
	)
	(segment
		(start 143.274233 91.197253)
		(end 143.259605 91.192135)
		(width 0.1016)
		(layer "In2.Cu")
		(net 32)
	)
	(segment
		(start 143.311676 91.244206)
		(end 143.306558 91.229578)
		(width 0.1016)
		(layer "In2.Cu")
		(net 32)
	)
	(segment
		(start 143.075767 90.994053)
		(end 143.090395 90.988935)
		(width 0.1016)
		(layer "In2.Cu")
		(net 32)
	)
	(segment
		(start 143.306558 91.766615)
		(end 143.311676 91.751987)
		(width 0.1016)
		(layer "In2.Cu")
		(net 32)
	)
	(segment
		(start 143.038324 90.634606)
		(end 143.043442 90.619978)
		(width 0.1016)
		(layer "In2.Cu")
		(net 32)
	)
	(segment
		(start 143.287355 91.790695)
		(end 143.298313 91.779737)
		(width 0.1016)
		(layer "In2.Cu")
		(net 32)
	)
	(segment
		(start 143.075767 90.777146)
		(end 143.062645 90.768901)
		(width 0.1016)
		(layer "In2.Cu")
		(net 32)
	)
	(segment
		(start 143.287355 91.205498)
		(end 143.274233 91.197253)
		(width 0.1016)
		(layer "In2.Cu")
		(net 32)
	)
	(segment
		(start 143.298313 90.961143)
		(end 143.306558 90.948021)
		(width 0.1016)
		(layer "In2.Cu")
		(net 32)
	)
	(segment
		(start 143.176735 91.8596)
		(end 143.181853 91.844972)
		(width 0.1016)
		(layer "In2.Cu")
		(net 32)
	)
	(segment
		(start 143.313412 90.511594)
		(end 143.313412 90.446806)
		(width 0.1016)
		(layer "In2.Cu")
		(net 32)
	)
	(segment
		(start 143.038324 91.136593)
		(end 143.036588 91.121194)
		(width 0.1016)
		(layer "In2.Cu")
		(net 32)
	)
	(segment
		(start 143.075767 91.183546)
		(end 143.062645 91.175301)
		(width 0.1016)
		(layer "In2.Cu")
		(net 32)
	)
	(segment
		(start 143.051687 91.013256)
		(end 143.062645 91.002298)
		(width 0.1016)
		(layer "In2.Cu")
		(net 32)
	)
	(segment
		(start 143.038324 90.730193)
		(end 143.036588 90.714794)
		(width 0.1016)
		(layer "In2.Cu")
		(net 32)
	)
	(segment
		(start 143.244206 90.5808)
		(end 143.259605 90.579064)
		(width 0.1016)
		(layer "In2.Cu")
		(net 32)
	)
	(segment
		(start 143.043442 91.557621)
		(end 143.038324 91.542993)
		(width 0.1016)
		(layer "In2.Cu")
		(net 32)
	)
	(segment
		(start 143.311676 90.431406)
		(end 143.306558 90.416778)
		(width 0.1016)
		(layer "In2.Cu")
		(net 32)
	)
	(segment
		(start 143.259605 90.985464)
		(end 143.274233 90.980346)
		(width 0.1016)
		(layer "In2.Cu")
		(net 32)
	)
	(segment
		(start 143.036588 90.650006)
		(end 143.038324 90.634606)
		(width 0.1016)
		(layer "In2.Cu")
		(net 32)
	)
	(segment
		(start 143.038324 91.542993)
		(end 143.036588 91.527594)
		(width 0.1016)
		(layer "In2.Cu")
		(net 32)
	)
	(segment
		(start 143.259605 90.785735)
		(end 143.244206 90.784)
		(width 0.1016)
		(layer "In2.Cu")
		(net 32)
	)
	(segment
		(start 143.043442 90.744821)
		(end 143.038324 90.730193)
		(width 0.1016)
		(layer "In2.Cu")
		(net 32)
	)
	(segment
		(start 147.375 84.73395)
		(end 147.625 84.48395)
		(width 0.1016)
		(layer "In2.Cu")
		(net 32)
	)
	(segment
		(start 143.038324 91.041006)
		(end 143.043442 91.026378)
		(width 0.1016)
		(layer "In2.Cu")
		(net 32)
	)
	(segment
		(start 143.214178 90.370746)
		(end 143.201056 90.362501)
		(width 0.1016)
		(layer "In2.Cu")
		(net 32)
	)
	(segment
		(start 143.181853 91.844972)
		(end 143.190098 91.83185)
		(width 0.1016)
		(layer "In2.Cu")
		(net 32)
	)
	(segment
		(start 143.244206 91.1904)
		(end 143.105794 91.1904)
		(width 0.1016)
		(layer "In2.Cu")
		(net 32)
	)
	(segment
		(start 143.306558 90.416778)
		(end 143.298313 90.403656)
		(width 0.1016)
		(layer "In2.Cu")
		(net 32)
	)
	(segment
		(start 143.201056 91.820892)
		(end 143.214178 91.812647)
		(width 0.1016)
		(layer "In2.Cu")
		(net 32)
	)
	(segment
		(start 143.306558 91.641772)
		(end 143.298313 91.62865)
		(width 0.1016)
		(layer "In2.Cu")
		(net 32)
	)
	(segment
		(start 143.287355 90.799098)
		(end 143.274233 90.790853)
		(width 0.1016)
		(layer "In2.Cu")
		(net 32)
	)
	(segment
		(start 143.043442 91.151221)
		(end 143.038324 91.136593)
		(width 0.1016)
		(layer "In2.Cu")
		(net 32)
	)
	(segment
		(start 143.090395 90.582535)
		(end 143.105794 90.5808)
		(width 0.1016)
		(layer "In2.Cu")
		(net 32)
	)
	(segment
		(start 143.274233 90.980346)
		(end 143.287355 90.972101)
		(width 0.1016)
		(layer "In2.Cu")
		(net 32)
	)
	(segment
		(start 143.244206 91.3936)
		(end 143.259605 91.391864)
		(width 0.1016)
		(layer "In2.Cu")
		(net 32)
	)
	(segment
		(start 143.214178 91.812647)
		(end 143.228806 91.807529)
		(width 0.1016)
		(layer "In2.Cu")
		(net 32)
	)
	(segment
		(start 143.298313 90.403656)
		(end 143.287355 90.392698)
		(width 0.1016)
		(layer "In2.Cu")
		(net 32)
	)
	(segment
		(start 143.105794 90.5808)
		(end 143.244206 90.5808)
		(width 0.1016)
		(layer "In2.Cu")
		(net 32)
	)
	(segment
		(start 143.036588 91.121194)
		(end 143.036588 91.056406)
		(width 0.1016)
		(layer "In2.Cu")
		(net 32)
	)
	(segment
		(start 143.175 90.308394)
		(end 143.175 85.15)
		(width 0.1016)
		(layer "In2.Cu")
		(net 32)
	)
	(segment
		(start 143.075767 90.587653)
		(end 143.090395 90.582535)
		(width 0.1016)
		(layer "In2.Cu")
		(net 32)
	)
	(segment
		(start 143.201056 90.362501)
		(end 143.190098 90.351543)
		(width 0.1016)
		(layer "In2.Cu")
		(net 32)
	)
	(segment
		(start 147.625 84.48395)
		(end 147.625 83.25)
		(width 0.1016)
		(layer "In2.Cu")
		(net 32)
	)
	(segment
		(start 143.036588 91.462806)
		(end 143.038324 91.447406)
		(width 0.1016)
		(layer "In2.Cu")
		(net 32)
	)
	(segment
		(start 143.313412 90.853206)
		(end 143.311676 90.837806)
		(width 0.1016)
		(layer "In2.Cu")
		(net 32)
	)
	(segment
		(start 143.311676 90.526993)
		(end 143.313412 90.511594)
		(width 0.1016)
		(layer "In2.Cu")
		(net 32)
	)
	(segment
		(start 143.244206 91.602594)
		(end 143.175 91.602594)
		(width 0.1016)
		(layer "In2.Cu")
		(net 32)
	)
	(segment
		(start 143.105794 91.1904)
		(end 143.090395 91.188664)
		(width 0.1016)
		(layer "In2.Cu")
		(net 32)
	)
	(segment
		(start 143.287355 91.617692)
		(end 143.274233 91.609447)
		(width 0.1016)
		(layer "In2.Cu")
		(net 32)
	)
	(segment
		(start 143.062645 91.581701)
		(end 143.051687 91.570743)
		(width 0.1016)
		(layer "In2.Cu")
		(net 32)
	)
	(segment
		(start 143.075767 91.400453)
		(end 143.090395 91.395335)
		(width 0.1016)
		(layer "In2.Cu")
		(net 32)
	)
	(segment
		(start 143.090395 91.595064)
		(end 143.075767 91.589946)
		(width 0.1016)
		(layer "In2.Cu")
		(net 32)
	)
	(segment
		(start 143.043442 91.026378)
		(end 143.051687 91.013256)
		(width 0.1016)
		(layer "In2.Cu")
		(net 32)
	)
	(segment
		(start 143.311676 90.933393)
		(end 143.313412 90.917994)
		(width 0.1016)
		(layer "In2.Cu")
		(net 32)
	)
	(segment
		(start 143.075767 91.589946)
		(end 143.062645 91.581701)
		(width 0.1016)
		(layer "In2.Cu")
		(net 32)
	)
	(segment
		(start 143.090395 90.782264)
		(end 143.075767 90.777146)
		(width 0.1016)
		(layer "In2.Cu")
		(net 32)
	)
	(segment
		(start 143.313412 91.736588)
		(end 143.313412 91.6718)
		(width 0.1016)
		(layer "In2.Cu")
		(net 32)
	)
	(segment
		(start 143.062645 90.595898)
		(end 143.075767 90.587653)
		(width 0.1016)
		(layer "In2.Cu")
		(net 32)
	)
	(segment
		(start 143.105794 90.784)
		(end 143.090395 90.782264)
		(width 0.1016)
		(layer "In2.Cu")
		(net 32)
	)
	(segment
		(start 143.175 91.875)
		(end 143.176735 91.8596)
		(width 0.1016)
		(layer "In2.Cu")
		(net 32)
	)
	(segment
		(start 143.298313 91.62865)
		(end 143.287355 91.617692)
		(width 0.1016)
		(layer "In2.Cu")
		(net 32)
	)
	(segment
		(start 143.105794 91.3936)
		(end 143.244206 91.3936)
		(width 0.1016)
		(layer "In2.Cu")
		(net 32)
	)
	(segment
		(start 143.287355 90.392698)
		(end 143.274233 90.384453)
		(width 0.1016)
		(layer "In2.Cu")
		(net 32)
	)
	(segment
		(start 143.175 85.15)
		(end 143.59105 84.73395)
		(width 0.1016)
		(layer "In2.Cu")
		(net 32)
	)
	(segment
		(start 143.175 91.5968)
		(end 143.105794 91.5968)
		(width 0.1016)
		(layer "In2.Cu")
		(net 32)
	)
	(segment
		(start 143.043442 90.619978)
		(end 143.051687 90.606856)
		(width 0.1016)
		(layer "In2.Cu")
		(net 32)
	)
	(segment
		(start 143.181853 90.338421)
		(end 143.176735 90.323793)
		(width 0.1016)
		(layer "In2.Cu")
		(net 32)
	)
	(segment
		(start 143.259605 91.804058)
		(end 143.274233 91.79894)
		(width 0.1016)
		(layer "In2.Cu")
		(net 32)
	)
	(segment
		(start 143.175 92.7)
		(end 143.175 91.875)
		(width 0.1016)
		(layer "In2.Cu")
		(net 32)
	)
	(segment
		(start 143.274233 91.609447)
		(end 143.259605 91.604329)
		(width 0.1016)
		(layer "In2.Cu")
		(net 32)
	)
	(segment
		(start 143.090395 91.188664)
		(end 143.075767 91.183546)
		(width 0.1016)
		(layer "In2.Cu")
		(net 32)
	)
	(segment
		(start 143.311676 91.6564)
		(end 143.306558 91.641772)
		(width 0.1016)
		(layer "In2.Cu")
		(net 32)
	)
	(segment
		(start 143.090395 90.988935)
		(end 143.105794 90.9872)
		(width 0.1016)
		(layer "In2.Cu")
		(net 32)
	)
	(segment
		(start 143.287355 91.378501)
		(end 143.298313 91.367543)
		(width 0.1016)
		(layer "In2.Cu")
		(net 32)
	)
	(segment
		(start 143.313412 91.259606)
		(end 143.311676 91.244206)
		(width 0.1016)
		(layer "In2.Cu")
		(net 32)
	)
	(segment
		(start 143.228806 90.375864)
		(end 143.214178 90.370746)
		(width 0.1016)
		(layer "In2.Cu")
		(net 32)
	)
	(segment
		(start 143.274233 90.790853)
		(end 143.259605 90.785735)
		(width 0.1016)
		(layer "In2.Cu")
		(net 32)
	)
	(segment
		(start 143.051687 91.419656)
		(end 143.062645 91.408698)
		(width 0.1016)
		(layer "In2.Cu")
		(net 32)
	)
	(segment
		(start 145.575 94.175)
		(end 146.8 95.4)
		(width 0.145)
		(layer "F.Cu")
		(net 33)
	)
	(segment
		(start 148.775899 96.075899)
		(end 148.775899 96.941569)
		(width 0.145)
		(layer "F.Cu")
		(net 33)
	)
	(segment
		(start 146.8 95.4)
		(end 148.1 95.4)
		(width 0.145)
		(layer "F.Cu")
		(net 33)
	)
	(segment
		(start 148.1 95.4)
		(end 148.775899 96.075899)
		(width 0.145)
		(layer "F.Cu")
		(net 33)
	)
	(segment
		(start 145.575 92.7)
		(end 145.575 94.175)
		(width 0.145)
		(layer "F.Cu")
		(net 33)
	)
	(segment
		(start 148.925 97.09067)
		(end 148.925 98.7)
		(width 0.145)
		(layer "F.Cu")
		(net 33)
	)
	(segment
		(start 147.225 87.65)
		(end 146.825 87.25)
		(width 0.2)
		(layer "F.Cu")
		(net 33)
	)
	(segment
		(start 148.775899 96.941569)
		(end 148.925 97.09067)
		(width 0.145)
		(layer "F.Cu")
		(net 33)
	)
	(via
		(at 145.575 92.7)
		(size 0.45)
		(drill 0.15)
		(layers "F.Cu" "B.Cu")
		(net 33)
	)
	(via
		(at 146.825 87.25)
		(size 0.45)
		(drill 0.15)
		(layers "F.Cu" "B.Cu")
		(net 33)
	)
	(segment
		(start 145.425 91.321954)
		(end 145.42688 91.305264)
		(width 0.1016)
		(layer "In2.Cu")
		(net 33)
	)
	(segment
		(start 145.708638 89.593115)
		(end 145.717573 89.578895)
		(width 0.1016)
		(layer "In2.Cu")
		(net 33)
	)
	(segment
		(start 145.72312 89.070064)
		(end 145.717573 89.054212)
		(width 0.1016)
		(layer "In2.Cu")
		(net 33)
	)
	(segment
		(start 145.5 89.621354)
		(end 145.65 89.621354)
		(width 0.1016)
		(layer "In2.Cu")
		(net 33)
	)
	(segment
		(start 145.48331 91.655234)
		(end 145.5 91.653354)
		(width 0.1016)
		(layer "In2.Cu")
		(net 33)
	)
	(segment
		(start 146.2596 86.447305)
		(end 146.282208 86.449853)
		(width 0.1016)
		(layer "In2.Cu")
		(net 33)
	)
	(segment
		(start 146.147938 87.192483)
		(end 146.155452 87.171009)
		(width 0.1016)
		(layer "In2.Cu")
		(net 33)
	)
	(segment
		(start 145.717573 91.899012)
		(end 145.708638 91.884792)
		(width 0.1016)
		(layer "In2.Cu")
		(net 33)
	)
	(segment
		(start 145.65 90.027754)
		(end 145.66669 90.025873)
		(width 0.1016)
		(layer "In2.Cu")
		(net 33)
	)
	(segment
		(start 145.725 90.359154)
		(end 145.725 90.305954)
		(width 0.1016)
		(layer "In2.Cu")
		(net 33)
	)
	(segment
		(start 145.42688 90.898864)
		(end 145.432427 90.883012)
		(width 0.1016)
		(layer "In2.Cu")
		(net 33)
	)
	(segment
		(start 145.467458 91.254381)
		(end 145.48331 91.248834)
		(width 0.1016)
		(layer "In2.Cu")
		(net 33)
	)
	(segment
		(start 145.441362 91.828315)
		(end 145.432427 91.814095)
		(width 0.1016)
		(layer "In2.Cu")
		(net 33)
	)
	(segment
		(start 145.66669 91.452034)
		(end 145.65 91.450154)
		(width 0.1016)
		(layer "In2.Cu")
		(net 33)
	)
	(segment
		(start 145.441362 88.836792)
		(end 145.453238 88.824916)
		(width 0.1016)
		(layer "In2.Cu")
		(net 33)
	)
	(segment
		(start 145.932634 86.485559)
		(end 145.944738 86.504823)
		(width 0.1016)
		(layer "In2.Cu")
		(net 33)
	)
	(segment
		(start 145.682542 89.425581)
		(end 145.66669 89.420034)
		(width 0.1016)
		(layer "In2.Cu")
		(net 33)
	)
	(segment
		(start 146.399453 87.227835)
		(end 146.418717 87.239939)
		(width 0.1016)
		(layer "In2.Cu")
		(net 33)
	)
	(segment
		(start 145.65 89.621354)
		(end 145.66669 89.619473)
		(width 0.1016)
		(layer "In2.Cu")
		(net 33)
	)
	(segment
		(start 145.682542 89.831981)
		(end 145.66669 89.826434)
		(width 0.1016)
		(layer "In2.Cu")
		(net 33)
	)
	(segment
		(start 146.358652 86.526297)
		(end 146.3612 86.548905)
		(width 0.1016)
		(layer "In2.Cu")
		(net 33)
	)
	(segment
		(start 146.383365 87.211747)
		(end 146.399453 87.227835)
		(width 0.1016)
		(layer "In2.Cu")
		(net 33)
	)
	(segment
		(start 145.432427 91.814095)
		(end 145.42688 91.798243)
		(width 0.1016)
		(layer "In2.Cu")
		(net 33)
	)
	(segment
		(start 146.339034 86.485559)
		(end 146.351138 86.504823)
		(width 0.1016)
		(layer "In2.Cu")
		(net 33)
	)
	(segment
		(start 145.5 89.824554)
		(end 145.48331 89.822673)
		(width 0.1016)
		(layer "In2.Cu")
		(net 33)
	)
	(segment
		(start 145.425 88.883554)
		(end 145.42688 88.866864)
		(width 0.1016)
		(layer "In2.Cu")
		(net 33)
	)
	(segment
		(start 145.425 89.696354)
		(end 145.42688 89.679664)
		(width 0.1016)
		(layer "In2.Cu")
		(net 33)
	)
	(segment
		(start 145.467458 90.223526)
		(end 145.453238 90.214591)
		(width 0.1016)
		(layer "In2.Cu")
		(net 33)
	)
	(segment
		(start 145.65 89.214954)
		(end 145.66669 89.213073)
		(width 0.1016)
		(layer "In2.Cu")
		(net 33)
	)
	(segment
		(start 145.708638 89.852792)
		(end 145.696762 89.840916)
		(width 0.1016)
		(layer "In2.Cu")
		(net 33)
	)
	(segment
		(start 145.717573 89.578895)
		(end 145.72312 89.563043)
		(width 0.1016)
		(layer "In2.Cu")
		(net 33)
	)
	(segment
		(start 145.591363 92.087992)
		(end 145.603239 92.076116)
		(width 0.1016)
		(layer "In2.Cu")
		(net 33)
	)
	(segment
		(start 146.033791 87.247453)
		(end 146.0564 87.25)
		(width 0.1016)
		(layer "In2.Cu")
		(net 33)
	)
	(segment
		(start 145.5 91.450154)
		(end 145.48331 91.448273)
		(width 0.1016)
		(layer "In2.Cu")
		(net 33)
	)
	(segment
		(start 145.441362 90.609115)
		(end 145.432427 90.594895)
		(width 0.1016)
		(layer "In2.Cu")
		(net 33)
	)
	(segment
		(start 145.717573 91.086212)
		(end 145.708638 91.071992)
		(width 0.1016)
		(layer "In2.Cu")
		(net 33)
	)
	(segment
		(start 145.5 91.043754)
		(end 145.48331 91.041873)
		(width 0.1016)
		(layer "In2.Cu")
		(net 33)
	)
	(segment
		(start 145.48331 90.635473)
		(end 145.467458 90.629926)
		(width 0.1016)
		(layer "In2.Cu")
		(net 33)
	)
	(segment
		(start 146.215517 86.457367)
		(end 146.236991 86.449853)
		(width 0.1016)
		(layer "In2.Cu")
		(net 33)
	)
	(segment
		(start 145.717573 89.172495)
		(end 145.72312 89.156643)
		(width 0.1016)
		(layer "In2.Cu")
		(net 33)
	)
	(segment
		(start 145.453238 91.433791)
		(end 145.441362 91.421915)
		(width 0.1016)
		(layer "In2.Cu")
		(net 33)
	)
	(segment
		(start 146.158 87.1484)
		(end 146.158 86.548905)
		(width 0.1016)
		(layer "In2.Cu")
		(net 33)
	)
	(segment
		(start 145.467458 90.629926)
		(end 145.453238 90.620991)
		(width 0.1016)
		(layer "In2.Cu")
		(net 33)
	)
	(segment
		(start 145.789853 86.469471)
		(end 145.809117 86.457367)
		(width 0.1016)
		(layer "In2.Cu")
		(net 33)
	)
	(segment
		(start 145.42688 90.492464)
		(end 145.432427 90.476612)
		(width 0.1016)
		(layer "In2.Cu")
		(net 33)
	)
	(segment
		(start 145.696762 89.198591)
		(end 145.708638 89.186715)
		(width 0.1016)
		(layer "In2.Cu")
		(net 33)
	)
	(segment
		(start 145.5 90.230954)
		(end 145.48331 90.229073)
		(width 0.1016)
		(layer "In2.Cu")
		(net 33)
	)
	(segment
		(start 145.65 90.637354)
		(end 145.5 90.637354)
		(width 0.1016)
		(layer "In2.Cu")
		(net 33)
	)
	(segment
		(start 145.432427 90.594895)
		(end 145.42688 90.579043)
		(width 0.1016)
		(layer "In2.Cu")
		(net 33)
	)
	(segment
		(start 145.48331 89.009873)
		(end 145.467458 89.004326)
		(width 0.1016)
		(layer "In2.Cu")
		(net 33)
	)
	(segment
		(start 145.453238 91.669716)
		(end 145.467458 91.660781)
		(width 0.1016)
		(layer "In2.Cu")
		(net 33)
	)
	(segment
		(start 146.371261 87.192483)
		(end 146.383365 87.211747)
		(width 0.1016)
		(layer "In2.Cu")
		(net 33)
	)
	(segment
		(start 145.42688 91.798243)
		(end 145.425 91.781554)
		(width 0.1016)
		(layer "In2.Cu")
		(net 33)
	)
	(segment
		(start 145.467458 91.442726)
		(end 145.453238 91.433791)
		(width 0.1016)
		(layer "In2.Cu")
		(net 33)
	)
	(segment
		(start 145.717573 91.610895)
		(end 145.72312 91.595043)
		(width 0.1016)
		(layer "In2.Cu")
		(net 33)
	)
	(segment
		(start 145.432427 89.257412)
		(end 145.441362 89.243192)
		(width 0.1016)
		(layer "In2.Cu")
		(net 33)
	)
	(segment
		(start 145.708638 90.405915)
		(end 145.717573 90.391695)
		(width 0.1016)
		(layer "In2.Cu")
		(net 33)
	)
	(segment
		(start 145.441362 91.681592)
		(end 145.453238 91.669716)
		(width 0.1016)
		(layer "In2.Cu")
		(net 33)
	)
	(segment
		(start 145.48331 91.854673)
		(end 145.467458 91.849126)
		(width 0.1016)
		(layer "In2.Cu")
		(net 33)
	)
	(segment
		(start 145.72312 91.914864)
		(end 145.717573 91.899012)
		(width 0.1016)
		(layer "In2.Cu")
		(net 33)
	)
	(segment
		(start 145.725 91.171954)
		(end 145.725 91.118754)
		(width 0.1016)
		(layer "In2.Cu")
		(net 33)
	)
	(segment
		(start 145.453238 89.231316)
		(end 145.467458 89.222381)
		(width 0.1016)
		(layer "In2.Cu")
		(net 33)
	)
	(segment
		(start 145.682542 91.051181)
		(end 145.66669 91.045634)
		(width 0.1016)
		(layer "In2.Cu")
		(net 33)
	)
	(segment
		(start 145.558637 88.780315)
		(end 145.567572 88.766095)
		(width 0.1016)
		(layer "In2.Cu")
		(net 33)
	)
	(segment
		(start 145.72312 91.508464)
		(end 145.717573 91.492612)
		(width 0.1016)
		(layer "In2.Cu")
		(net 33)
	)
	(segment
		(start 145.467458 89.222381)
		(end 145.48331 89.216834)
		(width 0.1016)
		(layer "In2.Cu")
		(net 33)
	)
	(segment
		(start 145.546761 88.792191)
		(end 145.558637 88.780315)
		(width 0.1016)
		(layer "In2.Cu")
		(net 33)
	)
	(segment
		(start 145.993053 87.227835)
		(end 146.012317 87.239939)
		(width 0.1016)
		(layer "In2.Cu")
		(net 33)
	)
	(segment
		(start 145.9548 87.1484)
		(end 145.957347 87.171009)
		(width 0.1016)
		(layer "In2.Cu")
		(net 33)
	)
	(segment
		(start 145.425 89.289954)
		(end 145.42688 89.273264)
		(width 0.1016)
		(layer "In2.Cu")
		(net 33)
	)
	(segment
		(start 145.453238 90.856916)
		(end 145.467458 90.847981)
		(width 0.1016)
		(layer "In2.Cu")
		(net 33)
	)
	(segment
		(start 145.696762 90.011391)
		(end 145.708638 89.999515)
		(width 0.1016)
		(layer "In2.Cu")
		(net 33)
	)
	(segment
		(start 145.682542 90.833126)
		(end 145.696762 90.824191)
		(width 0.1016)
		(layer "In2.Cu")
		(net 33)
	)
	(segment
		(start 145.708638 90.812315)
		(end 145.717573 90.798095)
		(width 0.1016)
		(layer "In2.Cu")
		(net 33)
	)
	(segment
		(start 145.425 91.781554)
		(end 145.425 91.728354)
		(width 0.1016)
		(layer "In2.Cu")
		(net 33)
	)
	(segment
		(start 145.717573 89.460612)
		(end 145.708638 89.446392)
		(width 0.1016)
		(layer "In2.Cu")
		(net 33)
	)
	(segment
		(start 145.5 90.027754)
		(end 145.65 90.027754)
		(width 0.1016)
		(layer "In2.Cu")
		(net 33)
	)
	(segment
		(start 145.567572 88.766095)
		(end 145.573119 88.750243)
		(width 0.1016)
		(layer "In2.Cu")
		(net 33)
	)
	(segment
		(start 145.696762 91.636991)
		(end 145.708638 91.625115)
		(width 0.1016)
		(layer "In2.Cu")
		(net 33)
	)
	(segment
		(start 145.432427 88.851012)
		(end 145.441362 88.836792)
		(width 0.1016)
		(layer "In2.Cu")
		(net 33)
	)
	(segment
		(start 145.42688 89.273264)
		(end 145.432427 89.257412)
		(width 0.1016)
		(layer "In2.Cu")
		(net 33)
	)
	(segment
		(start 145.467458 89.410726)
		(end 145.453238 89.401791)
		(width 0.1016)
		(layer "In2.Cu")
		(net 33)
	)
	(segment
		(start 145.66669 89.213073)
		(end 145.682542 89.207526)
		(width 0.1016)
		(layer "In2.Cu")
		(net 33)
	)
	(segment
		(start 145.976965 87.211747)
		(end 145.993053 87.227835)
		(width 0.1016)
		(layer "In2.Cu")
		(net 33)
	)
	(segment
		(start 146.236991 86.449853)
		(end 146.2596 86.447305)
		(width 0.1016)
		(layer "In2.Cu")
		(net 33)
	)
	(segment
		(start 145.65 89.418154)
		(end 145.5 89.418154)
		(width 0.1016)
		(layer "In2.Cu")
		(net 33)
	)
	(segment
		(start 145.708638 89.186715)
		(end 145.717573 89.172495)
		(width 0.1016)
		(layer "In2.Cu")
		(net 33)
	)
	(segment
		(start 145.696762 89.840916)
		(end 145.682542 89.831981)
		(width 0.1016)
		(layer "In2.Cu")
		(net 33)
	)
	(segment
		(start 145.72312 89.156643)
		(end 145.725 89.139954)
		(width 0.1016)
		(layer "In2.Cu")
		(net 33)
	)
	(segment
		(start 145.696762 90.417791)
		(end 145.708638 90.405915)
		(width 0.1016)
		(layer "In2.Cu")
		(net 33)
	)
	(segment
		(start 145.72312 89.476464)
		(end 145.717573 89.460612)
		(width 0.1016)
		(layer "In2.Cu")
		(net 33)
	)
	(segment
		(start 145.432427 91.407695)
		(end 145.42688 91.391843)
		(width 0.1016)
		(layer "In2.Cu")
		(net 33)
	)
	(segment
		(start 145.72312 91.102064)
		(end 145.717573 91.086212)
		(width 0.1016)
		(layer "In2.Cu")
		(net 33)
	)
	(segment
		(start 145.441362 89.243192)
		(end 145.453238 89.231316)
		(width 0.1016)
		(layer "In2.Cu")
		(net 33)
	)
	(segment
		(start 145.725 90.305954)
		(end 145.72312 90.289264)
		(width 0.1016)
		(layer "In2.Cu")
		(net 33)
	)
	(segment
		(start 145.42688 90.172643)
		(end 145.425 90.155954)
		(width 0.1016)
		(layer "In2.Cu")
		(net 33)
	)
	(segment
		(start 146.0564 87.25)
		(end 146.079008 87.247453)
		(width 0.1016)
		(layer "In2.Cu")
		(net 33)
	)
	(segment
		(start 145.5 91.246954)
		(end 145.65 91.246954)
		(width 0.1016)
		(layer "In2.Cu")
		(net 33)
	)
	(segment
		(start 145.696762 91.060116)
		(end 145.682542 91.051181)
		(width 0.1016)
		(layer "In2.Cu")
		(net 33)
	)
	(segment
		(start 145.725 89.086754)
		(end 145.72312 89.070064)
		(width 0.1016)
		(layer "In2.Cu")
		(net 33)
	)
	(segment
		(start 145.467458 91.660781)
		(end 145.48331 91.655234)
		(width 0.1016)
		(layer "In2.Cu")
		(net 33)
	)
	(segment
		(start 145.964861 87.192483)
		(end 145.976965 87.211747)
		(width 0.1016)
		(layer "In2.Cu")
		(net 33)
	)
	(segment
		(start 145.432427 88.969295)
		(end 145.42688 88.953443)
		(width 0.1016)
		(layer "In2.Cu")
		(net 33)
	)
	(segment
		(start 145.441362 90.055992)
		(end 145.453238 90.044116)
		(width 0.1016)
		(layer "In2.Cu")
		(net 33)
	)
	(segment
		(start 145.72312 90.782243)
		(end 145.725 90.765554)
		(width 0.1016)
		(layer "In2.Cu")
		(net 33)
	)
	(segment
		(start 145.467458 89.004326)
		(end 145.453238 88.995391)
		(width 0.1016)
		(layer "In2.Cu")
		(net 33)
	)
	(segment
		(start 145.708638 89.446392)
		(end 145.696762 89.434516)
		(width 0.1016)
		(layer "In2.Cu")
		(net 33)
	)
	(segment
		(start 145.696762 90.824191)
		(end 145.708638 90.812315)
		(width 0.1016)
		(layer "In2.Cu")
		(net 33)
	)
	(segment
		(start 145.467458 91.849126)
		(end 145.453238 91.840191)
		(width 0.1016)
		(layer "In2.Cu")
		(net 33)
	)
	(segment
		(start 145.725 91.578354)
		(end 145.725 91.525154)
		(width 0.1016)
		(layer "In2.Cu")
		(net 33)
	)
	(segment
		(start 145.425 90.102754)
		(end 145.42688 90.086064)
		(width 0.1016)
		(layer "In2.Cu")
		(net 33)
	)
	(segment
		(start 145.717573 89.985295)
		(end 145.72312 89.969443)
		(width 0.1016)
		(layer "In2.Cu")
		(net 33)
	)
	(segment
		(start 145.65 90.230954)
		(end 145.5 90.230954)
		(width 0.1016)
		(layer "In2.Cu")
		(net 33)
	)
	(segment
		(start 145.48331 89.623234)
		(end 145.5 89.621354)
		(width 0.1016)
		(layer "In2.Cu")
		(net 33)
	)
	(segment
		(start 145.809117 86.457367)
		(end 145.830591 86.449853)
		(width 0.1016)
		(layer "In2.Cu")
		(net 33)
	)
	(segment
		(start 145.66669 89.619473)
		(end 145.682542 89.613926)
		(width 0.1016)
		(layer "In2.Cu")
		(net 33)
	)
	(segment
		(start 145.725 91.931554)
		(end 145.72312 91.914864)
		(width 0.1016)
		(layer "In2.Cu")
		(net 33)
	)
	(segment
		(start 145.42688 91.305264)
		(end 145.432427 91.289412)
		(width 0.1016)
		(layer "In2.Cu")
		(net 33)
	)
	(segment
		(start 146.155452 87.171009)
		(end 146.158 87.1484)
		(width 0.1016)
		(layer "In2.Cu")
		(net 33)
	)
	(segment
		(start 145.72312 90.695664)
		(end 145.717573 90.679812)
		(width 0.1016)
		(layer "In2.Cu")
		(net 33)
	)
	(segment
		(start 145.682542 91.645926)
		(end 145.696762 91.636991)
		(width 0.1016)
		(layer "In2.Cu")
		(net 33)
	)
	(segment
		(start 145.66669 91.045634)
		(end 145.65 91.043754)
		(width 0.1016)
		(layer "In2.Cu")
		(net 33)
	)
	(segment
		(start 145.467458 90.035181)
		(end 145.48331 90.029634)
		(width 0.1016)
		(layer "In2.Cu")
		(net 33)
	)
	(segment
		(start 146.079008 87.247453)
		(end 146.100482 87.239939)
		(width 0.1016)
		(layer "In2.Cu")
		(net 33)
	)
	(segment
		(start 145.453238 91.840191)
		(end 145.441362 91.828315)
		(width 0.1016)
		(layer "In2.Cu")
		(net 33)
	)
	(segment
		(start 145.696762 89.604991)
		(end 145.708638 89.593115)
		(width 0.1016)
		(layer "In2.Cu")
		(net 33)
	)
	(segment
		(start 145.48331 89.822673)
		(end 145.467458 89.817126)
		(width 0.1016)
		(layer "In2.Cu")
		(net 33)
	)
	(segment
		(start 145.717573 91.492612)
		(end 145.708638 91.478392)
		(width 0.1016)
		(layer "In2.Cu")
		(net 33)
	)
	(segment
		(start 145.66669 90.838673)
		(end 145.682542 90.833126)
		(width 0.1016)
		(layer "In2.Cu")
		(net 33)
	)
	(segment
		(start 145.682542 92.052326)
		(end 145.696762 92.043391)
		(width 0.1016)
		(layer "In2.Cu")
		(net 33)
	)
	(segment
		(start 145.472599 88.631153)
		(end 145.472599 87.427401)
		(width 0.1016)
		(layer "In2.Cu")
		(net 33)
	)
	(segment
		(start 145.717573 90.391695)
		(end 145.72312 90.375843)
		(width 0.1016)
		(layer "In2.Cu")
		(net 33)
	)
	(segment
		(start 145.432427 90.188495)
		(end 145.42688 90.172643)
		(width 0.1016)
		(layer "In2.Cu")
		(net 33)
	)
	(segment
		(start 145.575 88.733554)
		(end 145.472599 88.631153)
		(width 0.1016)
		(layer "In2.Cu")
		(net 33)
	)
	(segment
		(start 146.135834 87.211747)
		(end 146.147938 87.192483)
		(width 0.1016)
		(layer "In2.Cu")
		(net 33)
	)
	(segment
		(start 145.944738 86.504823)
		(end 145.952252 86.526297)
		(width 0.1016)
		(layer "In2.Cu")
		(net 33)
	)
	(segment
		(start 145.72312 89.969443)
		(end 145.725 89.952754)
		(width 0.1016)
		(layer "In2.Cu")
		(net 33)
	)
	(segment
		(start 145.708638 91.218715)
		(end 145.717573 91.204495)
		(width 0.1016)
		(layer "In2.Cu")
		(net 33)
	)
	(segment
		(start 145.5 91.856554)
		(end 145.48331 91.854673)
		(width 0.1016)
		(layer "In2.Cu")
		(net 33)
	)
	(segment
		(start 145.725 89.899554)
		(end 145.72312 89.882864)
		(width 0.1016)
		(layer "In2.Cu")
		(net 33)
	)
	(segment
		(start 145.717573 91.204495)
		(end 145.72312 91.188643)
		(width 0.1016)
		(layer "In2.Cu")
		(net 33)
	)
	(segment
		(start 145.717573 92.017295)
		(end 145.72312 92.001443)
		(width 0.1016)
		(layer "In2.Cu")
		(net 33)
	)
	(segment
		(start 145.441362 91.015515)
		(end 145.432427 91.001295)
		(width 0.1016)
		(layer "In2.Cu")
		(net 33)
	)
	(segment
		(start 145.5 89.214954)
		(end 145.65 89.214954)
		(width 0.1016)
		(layer "In2.Cu")
		(net 33)
	)
	(segment
		(start 145.65 91.043754)
		(end 145.5 91.043754)
		(width 0.1016)
		(layer "In2.Cu")
		(net 33)
	)
	(segment
		(start 145.432427 90.476612)
		(end 145.441362 90.462392)
		(width 0.1016)
		(layer "In2.Cu")
		(net 33)
	)
	(segment
		(start 145.8532 86.447305)
		(end 145.875808 86.449853)
		(width 0.1016)
		(layer "In2.Cu")
		(net 33)
	)
	(segment
		(start 145.708638 91.625115)
		(end 145.717573 91.610895)
		(width 0.1016)
		(layer "In2.Cu")
		(net 33)
	)
	(segment
		(start 145.696762 92.043391)
		(end 145.708638 92.031515)
		(width 0.1016)
		(layer "In2.Cu")
		(net 33)
	)
	(segment
		(start 145.66669 91.651473)
		(end 145.682542 91.645926)
		(width 0.1016)
		(layer "In2.Cu")
		(net 33)
	)
	(segment
		(start 145.708638 90.665592)
		(end 145.696762 90.653716)
		(width 0.1016)
		(layer "In2.Cu")
		(net 33)
	)
	(segment
		(start 145.754147 86.526297)
		(end 145.761661 86.504823)
		(width 0.1016)
		(layer "In2.Cu")
		(net 33)
	)
	(segment
		(start 145.66669 90.232834)
		(end 145.65 90.230954)
		(width 0.1016)
		(layer "In2.Cu")
		(net 33)
	)
	(segment
		(start 145.717573 90.798095)
		(end 145.72312 90.782243)
		(width 0.1016)
		(layer "In2.Cu")
		(net 33)
	)
	(segment
		(start 145.72312 90.289264)
		(end 145.717573 90.273412)
		(width 0.1016)
		(layer "In2.Cu")
		(net 33)
	)
	(segment
		(start 145.65 89.011754)
		(end 145.5 89.011754)
		(width 0.1016)
		(layer "In2.Cu")
		(net 33)
	)
	(segment
		(start 145.66669 92.057873)
		(end 145.682542 92.052326)
		(width 0.1016)
		(layer "In2.Cu")
		(net 33)
	)
	(segment
		(start 146.012317 87.239939)
		(end 146.033791 87.247453)
		(width 0.1016)
		(layer "In2.Cu")
		(net 33)
	)
	(segment
		(start 146.282208 86.449853)
		(end 146.303682 86.457367)
		(width 0.1016)
		(layer "In2.Cu")
		(net 33)
	)
	(segment
		(start 145.66669 91.245073)
		(end 145.682542 91.239526)
		(width 0.1016)
		(layer "In2.Cu")
		(net 33)
	)
	(segment
		(start 145.453238 89.637716)
		(end 145.467458 89.628781)
		(width 0.1016)
		(layer "In2.Cu")
		(net 33)
	)
	(segment
		(start 145.425 90.562354)
		(end 145.425 90.509154)
		(width 0.1016)
		(layer "In2.Cu")
		(net 33)
	)
	(segment
		(start 145.48331 91.041873)
		(end 145.467458 91.036326)
		(width 0.1016)
		(layer "In2.Cu")
		(net 33)
	)
	(segment
		(start 145.467458 90.441581)
		(end 145.48331 90.436034)
		(width 0.1016)
		(layer "In2.Cu")
		(net 33)
	)
	(segment
		(start 145.48331 89.416273)
		(end 145.467458 89.410726)
		(width 0.1016)
		(layer "In2.Cu")
		(net 33)
	)
	(segment
		(start 145.453238 88.995391)
		(end 145.441362 88.983515)
		(width 0.1016)
		(layer "In2.Cu")
		(net 33)
	)
	(segment
		(start 145.532541 88.801126)
		(end 145.546761 88.792191)
		(width 0.1016)
		(layer "In2.Cu")
		(net 33)
	)
	(segment
		(start 145.682542 89.613926)
		(end 145.696762 89.604991)
		(width 0.1016)
		(layer "In2.Cu")
		(net 33)
	)
	(segment
		(start 145.441362 89.796315)
		(end 145.432427 89.782095)
		(width 0.1016)
		(layer "In2.Cu")
		(net 33)
	)
	(segment
		(start 145.617459 92.067181)
		(end 145.633311 92.061634)
		(width 0.1016)
		(layer "In2.Cu")
		(net 33)
	)
	(segment
		(start 145.875808 86.449853)
		(end 145.897282 86.457367)
		(width 0.1016)
		(layer "In2.Cu")
		(net 33)
	)
	(segment
		(start 145.66669 90.432273)
		(end 145.682542 90.426726)
		(width 0.1016)
		(layer "In2.Cu")
		(net 33)
	)
	(segment
		(start 145.5 90.434154)
		(end 145.65 90.434154)
		(width 0.1016)
		(layer "In2.Cu")
		(net 33)
	)
	(segment
		(start 145.425 89.749554)
		(end 145.425 89.696354)
		(width 0.1016)
		(layer "In2.Cu")
		(net 33)
	)
	(segment
		(start 146.418717 87.239939)
		(end 146.440191 87.247453)
		(width 0.1016)
		(layer "In2.Cu")
		(net 33)
	)
	(segment
		(start 146.119746 87.227835)
		(end 146.135834 87.211747)
		(width 0.1016)
		(layer "In2.Cu")
		(net 33)
	)
	(segment
		(start 145.453238 91.263316)
		(end 145.467458 91.254381)
		(width 0.1016)
		(layer "In2.Cu")
		(net 33)
	)
	(segment
		(start 145.432427 89.663812)
		(end 145.441362 89.649592)
		(width 0.1016)
		(layer "In2.Cu")
		(net 33)
	)
	(segment
		(start 146.303682 86.457367)
		(end 146.322946 86.469471)
		(width 0.1016)
		(layer "In2.Cu")
		(net 33)
	)
	(segment
		(start 145.42688 88.866864)
		(end 145.432427 88.851012)
		(width 0.1016)
		(layer "In2.Cu")
		(net 33)
	)
	(segment
		(start 145.5 90.840554)
		(end 145.65 90.840554)
		(width 0.1016)
		(layer "In2.Cu")
		(net 33)
	)
	(segment
		(start 145.5 89.011754)
		(end 145.48331 89.009873)
		(width 0.1016)
		(layer "In2.Cu")
		(net 33)
	)
	(segment
		(start 146.100482 87.239939)
		(end 146.119746 87.227835)
		(width 0.1016)
		(layer "In2.Cu")
		(net 33)
	)
	(segment
		(start 146.180165 86.485559)
		(end 146.196253 86.469471)
		(width 0.1016)
		(layer "In2.Cu")
		(net 33)
	)
	(segment
		(start 146.168061 86.504823)
		(end 146.180165 86.485559)
		(width 0.1016)
		(layer "In2.Cu")
		(net 33)
	)
	(segment
		(start 145.425 90.155954)
		(end 145.425 90.102754)
		(width 0.1016)
		(layer "In2.Cu")
		(net 33)
	)
	(segment
		(start 145.696762 89.434516)
		(end 145.682542 89.425581)
		(width 0.1016)
		(layer "In2.Cu")
		(net 33)
	)
	(segment
		(start 145.725 89.952754)
		(end 145.725 89.899554)
		(width 0.1016)
		(layer "In2.Cu")
		(net 33)
	)
	(segment
		(start 145.516689 88.806673)
		(end 145.532541 88.801126)
		(width 0.1016)
		(layer "In2.Cu")
		(net 33)
	)
	(segment
		(start 145.761661 86.504823)
		(end 145.773765 86.485559)
		(width 0.1016)
		(layer "In2.Cu")
		(net 33)
	)
	(segment
		(start 145.467458 88.815981)
		(end 145.48331 88.810434)
		(width 0.1016)
		(layer "In2.Cu")
		(net 33)
	)
	(segment
		(start 145.5 90.637354)
		(end 145.48331 90.635473)
		(width 0.1016)
		(layer "In2.Cu")
		(net 33)
	)
	(segment
		(start 145.425 90.509154)
		(end 145.42688 90.492464)
		(width 0.1016)
		(layer "In2.Cu")
		(net 33)
	)
	(segment
		(start 145.708638 89.999515)
		(end 145.717573 89.985295)
		(width 0.1016)
		(layer "In2.Cu")
		(net 33)
	)
	(segment
		(start 145.66669 90.025873)
		(end 145.682542 90.020326)
		(width 0.1016)
		(layer "In2.Cu")
		(net 33)
	)
	(segment
		(start 145.425 91.375154)
		(end 145.425 91.321954)
		(width 0.1016)
		(layer "In2.Cu")
		(net 33)
	)
	(segment
		(start 145.66669 91.858434)
		(end 145.65 91.856554)
		(width 0.1016)
		(layer "In2.Cu")
		(net 33)
	)
	(segment
		(start 145.582428 92.102212)
		(end 145.591363 92.087992)
		(width 0.1016)
		(layer "In2.Cu")
		(net 33)
	)
	(segment
		(start 145.42688 91.711664)
		(end 145.432427 91.695812)
		(width 0.1016)
		(layer "In2.Cu")
		(net 33)
	)
	(segment
		(start 145.729434 87.211747)
		(end 145.741538 87.192483)
		(width 0.1016)
		(layer "In2.Cu")
		(net 33)
	)
	(segment
		(start 145.65 90.840554)
		(end 145.66669 90.838673)
		(width 0.1016)
		(layer "In2.Cu")
		(net 33)
	)
	(segment
		(start 145.48331 89.216834)
		(end 145.5 89.214954)
		(width 0.1016)
		(layer "In2.Cu")
		(net 33)
	)
	(segment
		(start 145.48331 90.842434)
		(end 145.5 90.840554)
		(width 0.1016)
		(layer "In2.Cu")
		(net 33)
	)
	(segment
		(start 145.952252 86.526297)
		(end 145.9548 86.548905)
		(width 0.1016)
		(layer "In2.Cu")
		(net 33)
	)
	(segment
		(start 146.3612 87.1484)
		(end 146.363747 87.171009)
		(width 0.1016)
		(layer "In2.Cu")
		(net 33)
	)
	(segment
		(start 145.441362 91.421915)
		(end 145.432427 91.407695)
		(width 0.1016)
		(layer "In2.Cu")
		(net 33)
	)
	(segment
		(start 146.3612 86.548905)
		(end 146.3612 87.1484)
		(width 0.1016)
		(layer "In2.Cu")
		(net 33)
	)
	(segment
		(start 145.682542 91.239526)
		(end 145.696762 91.230591)
		(width 0.1016)
		(layer "In2.Cu")
		(net 33)
	)
	(segment
		(start 145.717573 90.679812)
		(end 145.708638 90.665592)
		(width 0.1016)
		(layer "In2.Cu")
		(net 33)
	)
	(segment
		(start 145.425 88.936754)
		(end 145.425 88.883554)
		(width 0.1016)
		(layer "In2.Cu")
		(net 33)
	)
	(segment
		(start 145.696762 90.247316)
		(end 145.682542 90.238381)
		(width 0.1016)
		(layer "In2.Cu")
		(net 33)
	)
	(segment
		(start 145.453238 90.450516)
		(end 145.467458 90.441581)
		(width 0.1016)
		(layer "In2.Cu")
		(net 33)
	)
	(segment
		(start 145.66669 89.013634)
		(end 145.65 89.011754)
		(width 0.1016)
		(layer "In2.Cu")
		(net 33)
	)
	(segment
		(start 145.65 91.450154)
		(end 145.5 91.450154)
		(width 0.1016)
		(layer "In2.Cu")
		(net 33)
	)
	(segment
		(start 145.48331 90.229073)
		(end 145.467458 90.223526)
		(width 0.1016)
		(layer "In2.Cu")
		(net 33)
	)
	(segment
		(start 145.713346 87.227835)
		(end 145.729434 87.211747)
		(width 0.1016)
		(layer "In2.Cu")
		(net 33)
	)
	(segment
		(start 145.717573 89.054212)
		(end 145.708638 89.039992)
		(width 0.1016)
		(layer "In2.Cu")
		(net 33)
	)
	(segment
		(start 145.453238 89.808191)
		(end 145.441362 89.796315)
		(width 0.1016)
		(layer "In2.Cu")
		(net 33)
	)
	(segment
		(start 145.432427 91.001295)
		(end 145.42688 90.985443)
		(width 0.1016)
		(layer "In2.Cu")
		(net 33)
	)
	(segment
		(start 145.432427 90.883012)
		(end 145.441362 90.868792)
		(width 0.1016)
		(layer "In2.Cu")
		(net 33)
	)
	(segment
		(start 145.603239 92.076116)
		(end 145.617459 92.067181)
		(width 0.1016)
		(layer "In2.Cu")
		(net 33)
	)
	(segment
		(start 145.682542 91.863981)
		(end 145.66669 91.858434)
		(width 0.1016)
		(layer "In2.Cu")
		(net 33)
	)
	(segment
		(start 145.66669 89.420034)
		(end 145.65 89.418154)
		(width 0.1016)
		(layer "In2.Cu")
		(net 33)
	)
	(segment
		(start 145.48331 91.248834)
		(end 145.5 91.246954)
		(width 0.1016)
		(layer "In2.Cu")
		(net 33)
	)
	(segment
		(start 145.696762 89.028116)
		(end 145.682542 89.019181)
		(width 0.1016)
		(layer "In2.Cu")
		(net 33)
	)
	(segment
		(start 145.453238 89.401791)
		(end 145.441362 89.389915)
		(width 0.1016)
		(layer "In2.Cu")
		(net 33)
	)
	(segment
		(start 146.4628 87.25)
		(end 146.8128 87.25)
		(width 0.1016)
		(layer "In2.Cu")
		(net 33)
	)
	(segment
		(start 145.773765 86.485559)
		(end 145.789853 86.469471)
		(width 0.1016)
		(layer "In2.Cu")
		(net 33)
	)
	(segment
		(start 145.48331 90.436034)
		(end 145.5 90.434154)
		(width 0.1016)
		(layer "In2.Cu")
		(net 33)
	)
	(segment
		(start 145.72312 91.188643)
		(end 145.725 91.171954)
		(width 0.1016)
		(layer "In2.Cu")
		(net 33)
	)
	(segment
		(start 145.7516 87.1484)
		(end 145.7516 86.548905)
		(width 0.1016)
		(layer "In2.Cu")
		(net 33)
	)
	(segment
		(start 146.158 86.548905)
		(end 146.160547 86.526297)
		(width 0.1016)
		(layer "In2.Cu")
		(net 33)
	)
	(segment
		(start 145.425 90.968754)
		(end 145.425 90.915554)
		(width 0.1016)
		(layer "In2.Cu")
		(net 33)
	)
	(segment
		(start 145.5 89.418154)
		(end 145.48331 89.416273)
		(width 0.1016)
		(layer "In2.Cu")
		(net 33)
	)
	(segment
		(start 145.453238 90.620991)
		(end 145.441362 90.609115)
		(width 0.1016)
		(layer "In2.Cu")
		(net 33)
	)
	(segment
		(start 145.425 90.915554)
		(end 145.42688 90.898864)
		(width 0.1016)
		(layer "In2.Cu")
		(net 33)
	)
	(segment
		(start 145.432427 91.695812)
		(end 145.441362 91.681592)
		(width 0.1016)
		(layer "In2.Cu")
		(net 33)
	)
	(segment
		(start 145.441362 90.868792)
		(end 145.453238 90.856916)
		(width 0.1016)
		(layer "In2.Cu")
		(net 33)
	)
	(segment
		(start 145.575 92.7)
		(end 145.575 92.134754)
		(width 0.1016)
		(layer "In2.Cu")
		(net 33)
	)
	(segment
		(start 145.7516 86.548905)
		(end 145.754147 86.526297)
		(width 0.1016)
		(layer "In2.Cu")
		(net 33)
	)
	(segment
		(start 145.708638 91.884792)
		(end 145.696762 91.872916)
		(width 0.1016)
		(layer "In2.Cu")
		(net 33)
	)
	(segment
		(start 145.672608 87.247453)
		(end 145.694082 87.239939)
		(width 0.1016)
		(layer "In2.Cu")
		(net 33)
	)
	(segment
		(start 145.725 90.712354)
		(end 145.72312 90.695664)
		(width 0.1016)
		(layer "In2.Cu")
		(net 33)
	)
	(segment
		(start 145.441362 91.275192)
		(end 145.453238 91.263316)
		(width 0.1016)
		(layer "In2.Cu")
		(net 33)
	)
	(segment
		(start 145.467458 90.847981)
		(end 145.48331 90.842434)
		(width 0.1016)
		(layer "In2.Cu")
		(net 33)
	)
	(segment
		(start 145.682542 90.426726)
		(end 145.696762 90.417791)
		(width 0.1016)
		(layer "In2.Cu")
		(net 33)
	)
	(segment
		(start 145.708638 90.259192)
		(end 145.696762 90.247316)
		(width 0.1016)
		(layer "In2.Cu")
		(net 33)
	)
	(segment
		(start 145.42688 89.679664)
		(end 145.432427 89.663812)
		(width 0.1016)
		(layer "In2.Cu")
		(net 33)
	)
	(segment
		(start 145.725 91.984754)
		(end 145.725 91.931554)
		(width 0.1016)
		(layer "In2.Cu")
		(net 33)
	)
	(segment
		(start 145.65 87.25)
		(end 145.672608 87.247453)
		(width 0.1016)
		(layer "In2.Cu")
		(net 33)
	)
	(segment
		(start 145.725 89.139954)
		(end 145.725 89.086754)
		(width 0.1016)
		(layer "In2.Cu")
		(net 33)
	)
	(segment
		(start 145.708638 91.071992)
		(end 145.696762 91.060116)
		(width 0.1016)
		(layer "In2.Cu")
		(net 33)
	)
	(segment
		(start 145.717573 90.273412)
		(end 145.708638 90.259192)
		(width 0.1016)
		(layer "In2.Cu")
		(net 33)
	)
	(segment
		(start 146.8128 87.25)
		(end 146.825 87.25)
		(width 0.1016)
		(layer "In2.Cu")
		(net 33)
	)
	(segment
		(start 145.72312 90.375843)
		(end 145.725 90.359154)
		(width 0.1016)
		(layer "In2.Cu")
		(net 33)
	)
	(segment
		(start 146.196253 86.469471)
		(end 146.215517 86.457367)
		(width 0.1016)
		(layer "In2.Cu")
		(net 33)
	)
	(segment
		(start 145.725 90.765554)
		(end 145.725 90.712354)
		(width 0.1016)
		(layer "In2.Cu")
		(net 33)
	)
	(segment
		(start 145.42688 91.391843)
		(end 145.425 91.375154)
		(width 0.1016)
		(layer "In2.Cu")
		(net 33)
	)
	(segment
		(start 145.72312 91.595043)
		(end 145.725 91.578354)
		(width 0.1016)
		(layer "In2.Cu")
		(net 33)
	)
	(segment
		(start 145.42688 90.985443)
		(end 145.425 90.968754)
		(width 0.1016)
		(layer "In2.Cu")
		(net 33)
	)
	(segment
		(start 145.432427 89.782095)
		(end 145.42688 89.766243)
		(width 0.1016)
		(layer "In2.Cu")
		(net 33)
	)
	(segment
		(start 145.749052 87.171009)
		(end 145.7516 87.1484)
		(width 0.1016)
		(layer "In2.Cu")
		(net 33)
	)
	(segment
		(start 145.48331 91.448273)
		(end 145.467458 91.442726)
		(width 0.1016)
		(layer "In2.Cu")
		(net 33)
	)
	(segment
		(start 145.432427 91.289412)
		(end 145.441362 91.275192)
		(width 0.1016)
		(layer "In2.Cu")
		(net 33)
	)
	(segment
		(start 145.453238 91.027391)
		(end 145.441362 91.015515)
		(width 0.1016)
		(layer "In2.Cu")
		(net 33)
	)
	(segment
		(start 145.725 89.493154)
		(end 145.72312 89.476464)
		(width 0.1016)
		(layer "In2.Cu")
		(net 33)
	)
	(segment
		(start 146.160547 86.526297)
		(end 146.168061 86.504823)
		(width 0.1016)
		(layer "In2.Cu")
		(net 33)
	)
	(segment
		(start 145.741538 87.192483)
		(end 145.749052 87.171009)
		(width 0.1016)
		(layer "In2.Cu")
		(net 33)
	)
	(segment
		(start 145.72312 89.563043)
		(end 145.725 89.546354)
		(width 0.1016)
		(layer "In2.Cu")
		(net 33)
	)
	(segment
		(start 145.725 91.525154)
		(end 145.72312 91.508464)
		(width 0.1016)
		(layer "In2.Cu")
		(net 33)
	)
	(segment
		(start 145.453238 90.214591)
		(end 145.441362 90.202715)
		(width 0.1016)
		(layer "In2.Cu")
		(net 33)
	)
	(segment
		(start 145.725 89.546354)
		(end 145.725 89.493154)
		(width 0.1016)
		(layer "In2.Cu")
		(net 33)
	)
	(segment
		(start 145.696762 90.653716)
		(end 145.682542 90.644781)
		(width 0.1016)
		(layer "In2.Cu")
		(net 33)
	)
	(segment
		(start 145.65 91.856554)
		(end 145.5 91.856554)
		(width 0.1016)
		(layer "In2.Cu")
		(net 33)
	)
	(segment
		(start 145.9548 86.548905)
		(end 145.9548 87.1484)
		(width 0.1016)
		(layer "In2.Cu")
		(net 33)
	)
	(segment
		(start 145.696762 91.230591)
		(end 145.708638 91.218715)
		(width 0.1016)
		(layer "In2.Cu")
		(net 33)
	)
	(segment
		(start 145.432427 90.070212)
		(end 145.441362 90.055992)
		(width 0.1016)
		(layer "In2.Cu")
		(net 33)
	)
	(segment
		(start 145.682542 89.019181)
		(end 145.66669 89.013634)
		(width 0.1016)
		(layer "In2.Cu")
		(net 33)
	)
	(segment
		(start 145.472599 87.427401)
		(end 145.65 87.25)
		(width 0.1016)
		(layer "In2.Cu")
		(net 33)
	)
	(segment
		(start 146.440191 87.247453)
		(end 146.4628 87.25)
		(width 0.1016)
		(layer "In2.Cu")
		(net 33)
	)
	(segment
		(start 145.441362 88.983515)
		(end 145.432427 88.969295)
		(width 0.1016)
		(layer "In2.Cu")
		(net 33)
	)
	(segment
		(start 145.453238 88.824916)
		(end 145.467458 88.815981)
		(width 0.1016)
		(layer "In2.Cu")
		(net 33)
	)
	(segment
		(start 145.725 91.118754)
		(end 145.72312 91.102064)
		(width 0.1016)
		(layer "In2.Cu")
		(net 33)
	)
	(segment
		(start 145.42688 90.086064)
		(end 145.432427 90.070212)
		(width 0.1016)
		(layer "In2.Cu")
		(net 33)
	)
	(segment
		(start 145.65 91.653354)
		(end 145.66669 91.651473)
		(width 0.1016)
		(layer "In2.Cu")
		(net 33)
	)
	(segment
		(start 145.467458 89.628781)
		(end 145.48331 89.623234)
		(width 0.1016)
		(layer "In2.Cu")
		(net 33)
	)
	(segment
		(start 145.717573 89.867012)
		(end 145.708638 89.852792)
		(width 0.1016)
		(layer "In2.Cu")
		(net 33)
	)
	(segment
		(start 145.696762 91.466516)
		(end 145.682542 91.457581)
		(width 0.1016)
		(layer "In2.Cu")
		(net 33)
	)
	(segment
		(start 145.682542 90.238381)
		(end 145.66669 90.232834)
		(width 0.1016)
		(layer "In2.Cu")
		(net 33)
	)
	(segment
		(start 145.576881 92.118064)
		(end 145.582428 92.102212)
		(width 0.1016)
		(layer "In2.Cu")
		(net 33)
	)
	(segment
		(start 145.72312 89.882864)
		(end 145.717573 89.867012)
		(width 0.1016)
		(layer "In2.Cu")
		(net 33)
	)
	(segment
		(start 145.897282 86.457367)
		(end 145.916546 86.469471)
		(width 0.1016)
		(layer "In2.Cu")
		(net 33)
	)
	(segment
		(start 145.5 91.653354)
		(end 145.65 91.653354)
		(width 0.1016)
		(layer "In2.Cu")
		(net 33)
	)
	(segment
		(start 145.441362 89.649592)
		(end 145.453238 89.637716)
		(width 0.1016)
		(layer "In2.Cu")
		(net 33)
	)
	(segment
		(start 145.467458 89.817126)
		(end 145.453238 89.808191)
		(width 0.1016)
		(layer "In2.Cu")
		(net 33)
	)
	(segment
		(start 145.72312 92.001443)
		(end 145.725 91.984754)
		(width 0.1016)
		(layer "In2.Cu")
		(net 33)
	)
	(segment
		(start 146.351138 86.504823)
		(end 146.358652 86.526297)
		(width 0.1016)
		(layer "In2.Cu")
		(net 33)
	)
	(segment
		(start 145.65 89.824554)
		(end 145.5 89.824554)
		(width 0.1016)
		(layer "In2.Cu")
		(net 33)
	)
	(segment
		(start 145.682542 90.644781)
		(end 145.66669 90.639234)
		(width 0.1016)
		(layer "In2.Cu")
		(net 33)
	)
	(segment
		(start 145.575 92.134754)
		(end 145.576881 92.118064)
		(width 0.1016)
		(layer "In2.Cu")
		(net 33)
	)
	(segment
		(start 145.65 90.434154)
		(end 145.66669 90.432273)
		(width 0.1016)
		(layer "In2.Cu")
		(net 33)
	)
	(segment
		(start 145.65 91.246954)
		(end 145.66669 91.245073)
		(width 0.1016)
		(layer "In2.Cu")
		(net 33)
	)
	(segment
		(start 145.467458 91.036326)
		(end 145.453238 91.027391)
		(width 0.1016)
		(layer "In2.Cu")
		(net 33)
	)
	(segment
		(start 145.708638 91.478392)
		(end 145.696762 91.466516)
		(width 0.1016)
		(layer "In2.Cu")
		(net 33)
	)
	(segment
		(start 145.42688 90.579043)
		(end 145.425 90.562354)
		(width 0.1016)
		(layer "In2.Cu")
		(net 33)
	)
	(segment
		(start 145.441362 90.462392)
		(end 145.453238 90.450516)
		(width 0.1016)
		(layer "In2.Cu")
		(net 33)
	)
	(segment
		(start 145.48331 90.029634)
		(end 145.5 90.027754)
		(width 0.1016)
		(layer "In2.Cu")
		(net 33)
	)
	(segment
		(start 145.633311 92.061634)
		(end 145.66669 92.057873)
		(width 0.1016)
		(layer "In2.Cu")
		(net 33)
	)
	(segment
		(start 145.42688 89.359843)
		(end 145.425 89.343154)
		(width 0.1016)
		(layer "In2.Cu")
		(net 33)
	)
	(segment
		(start 145.42688 89.766243)
		(end 145.425 89.749554)
		(width 0.1016)
		(layer "In2.Cu")
		(net 33)
	)
	(segment
		(start 145.432427 89.375695)
		(end 145.42688 89.359843)
		(width 0.1016)
		(layer "In2.Cu")
		(net 33)
	)
	(segment
		(start 145.48331 88.810434)
		(end 145.516689 88.806673)
		(width 0.1016)
		(layer "In2.Cu")
		(net 33)
	)
	(segment
		(start 145.573119 88.750243)
		(end 145.575 88.733554)
		(width 0.1016)
		(layer "In2.Cu")
		(net 33)
	)
	(segment
		(start 145.830591 86.449853)
		(end 145.8532 86.447305)
		(width 0.1016)
		(layer "In2.Cu")
		(net 33)
	)
	(segment
		(start 145.425 89.343154)
		(end 145.425 89.289954)
		(width 0.1016)
		(layer "In2.Cu")
		(net 33)
	)
	(segment
		(start 145.66669 90.639234)
		(end 145.65 90.637354)
		(width 0.1016)
		(layer "In2.Cu")
		(net 33)
	)
	(segment
		(start 145.708638 89.039992)
		(end 145.696762 89.028116)
		(width 0.1016)
		(layer "In2.Cu")
		(net 33)
	)
	(segment
		(start 145.441362 89.389915)
		(end 145.432427 89.375695)
		(width 0.1016)
		(layer "In2.Cu")
		(net 33)
	)
	(segment
		(start 146.363747 87.171009)
		(end 146.371261 87.192483)
		(width 0.1016)
		(layer "In2.Cu")
		(net 33)
	)
	(segment
		(start 145.916546 86.469471)
		(end 145.932634 86.485559)
		(width 0.1016)
		(layer "In2.Cu")
		(net 33)
	)
	(segment
		(start 145.441362 90.202715)
		(end 145.432427 90.188495)
		(width 0.1016)
		(layer "In2.Cu")
		(net 33)
	)
	(segment
		(start 145.66669 89.826434)
		(end 145.65 89.824554)
		(width 0.1016)
		(layer "In2.Cu")
		(net 33)
	)
	(segment
		(start 145.682542 91.457581)
		(end 145.66669 91.452034)
		(width 0.1016)
		(layer "In2.Cu")
		(net 33)
	)
	(segment
		(start 145.42688 88.953443)
		(end 145.425 88.936754)
		(width 0.1016)
		(layer "In2.Cu")
		(net 33)
	)
	(segment
		(start 145.696762 91.872916)
		(end 145.682542 91.863981)
		(width 0.1016)
		(layer "In2.Cu")
		(net 33)
	)
	(segment
		(start 145.682542 89.207526)
		(end 145.696762 89.198591)
		(width 0.1016)
		(layer "In2.Cu")
		(net 33)
	)
	(segment
		(start 145.453238 90.044116)
		(end 145.467458 90.035181)
		(width 0.1016)
		(layer "In2.Cu")
		(net 33)
	)
	(segment
		(start 145.425 91.728354)
		(end 145.42688 91.711664)
		(width 0.1016)
		(layer "In2.Cu")
		(net 33)
	)
	(segment
		(start 145.694082 87.239939)
		(end 145.713346 87.227835)
		(width 0.1016)
		(layer "In2.Cu")
		(net 33)
	)
	(segment
		(start 145.957347 87.171009)
		(end 145.964861 87.192483)
		(width 0.1016)
		(layer "In2.Cu")
		(net 33)
	)
	(segment
		(start 145.708638 92.031515)
		(end 145.717573 92.017295)
		(width 0.1016)
		(layer "In2.Cu")
		(net 33)
	)
	(segment
		(start 145.682542 90.020326)
		(end 145.696762 90.011391)
		(width 0.1016)
		(layer "In2.Cu")
		(net 33)
	)
	(segment
		(start 146.322946 86.469471)
		(end 146.339034 86.485559)
		(width 0.1016)
		(layer "In2.Cu")
		(net 33)
	)
	(segment
		(start 147.225 83.65)
		(end 147.225 84.21)
		(width 0.145)
		(layer "F.Cu")
		(net 34)
	)
	(segment
		(start 142.775899 92.300899)
		(end 142.775 92.3)
		(width 0.145)
		(layer "F.Cu")
		(net 34)
	)
	(segment
		(start 142.775899 95.524658)
		(end 142.775899 92.300899)
		(width 0.145)
		(layer "F.Cu")
		(net 34)
	)
	(segment
		(start 143.925 96.673759)
		(end 142.775899 95.524658)
		(width 0.145)
		(layer "F.Cu")
		(net 34)
	)
	(segment
		(start 143.925 98.7)
		(end 143.925 96.673759)
		(width 0.145)
		(layer "F.Cu")
		(net 34)
	)
	(via
		(at 142.775 92.3)
		(size 0.45)
		(drill 0.15)
		(layers "F.Cu" "B.Cu")
		(net 34)
	)
	(via
		(at 147.225 84.21)
		(size 0.45)
		(drill 0.15)
		(layers "F.Cu" "B.Cu")
		(net 34)
	)
	(segment
		(start 142.775 92.3)
		(end 142.775 84.95)
		(width 0.1016)
		(layer "In2.Cu")
		(net 34)
	)
	(segment
		(start 142.775 84.95)
		(end 143.19426 84.53074)
		(width 0.1016)
		(layer "In2.Cu")
		(net 34)
	)
	(segment
		(start 143.19426 84.53074)
		(end 146.90426 84.53074)
		(width 0.1016)
		(layer "In2.Cu")
		(net 34)
	)
	(segment
		(start 146.90426 84.53074)
		(end 147.225 84.21)
		(width 0.1016)
		(layer "In2.Cu")
		(net 34)
	)
	(segment
		(start 147.225 86.85)
		(end 147.225 86.29)
		(width 0.145)
		(layer "F.Cu")
		(net 35)
	)
	(segment
		(start 149.6 96.91567)
		(end 149.6 96.2)
		(width 0.145)
		(layer "F.Cu")
		(net 35)
	)
	(segment
		(start 149.425 98.7)
		(end 149.425 97.09067)
		(width 0.145)
		(layer "F.Cu")
		(net 35)
	)
	(segment
		(start 149.425 97.09067)
		(end 149.6 96.91567)
		(width 0.145)
		(layer "F.Cu")
		(net 35)
	)
	(segment
		(start 147 95)
		(end 146.8 94.8)
		(width 0.145)
		(layer "F.Cu")
		(net 35)
	)
	(segment
		(start 149.6 96.2)
		(end 148.4 95)
		(width 0.145)
		(layer "F.Cu")
		(net 35)
	)
	(segment
		(start 145.975 93.975)
		(end 146.8 94.8)
		(width 0.145)
		(layer "F.Cu")
		(net 35)
	)
	(segment
		(start 145.975 92.3)
		(end 145.975 93.975)
		(width 0.145)
		(layer "F.Cu")
		(net 35)
	)
	(segment
		(start 148.4 95)
		(end 147 95)
		(width 0.145)
		(layer "F.Cu")
		(net 35)
	)
	(via
		(at 147.225 86.29)
		(size 0.45)
		(drill 0.15)
		(layers "F.Cu" "B.Cu")
		(net 35)
	)
	(via
		(at 145.975 92.3)
		(size 0.45)
		(drill 0.15)
		(layers "F.Cu" "B.Cu")
		(net 35)
	)
	(segment
		(start 147.100801 87.654001)
		(end 146.354001 87.654001)
		(width 0.1016)
		(layer "In2.Cu")
		(net 35)
	)
	(segment
		(start 147.123409 87.651453)
		(end 147.100801 87.654001)
		(width 0.1016)
		(layer "In2.Cu")
		(net 35)
	)
	(segment
		(start 147.180235 88.301854)
		(end 147.192339 88.321118)
		(width 0.1016)
		(layer "In2.Cu")
		(net 35)
	)
	(segment
		(start 147.180235 87.895454)
		(end 147.192339 87.914718)
		(width 0.1016)
		(layer "In2.Cu")
		(net 35)
	)
	(segment
		(start 147.199853 87.981409)
		(end 147.192339 88.002883)
		(width 0.1016)
		(layer "In2.Cu")
		(net 35)
	)
	(segment
		(start 147.199853 88.342592)
		(end 147.202401 88.365201)
		(width 0.1016)
		(layer "In2.Cu")
		(net 35)
	)
	(segment
		(start 146.204948 88.184609)
		(end 146.212462 88.206083)
		(width 0.1016)
		(layer "In2.Cu")
		(net 35)
	)
	(segment
		(start 146.274566 87.692254)
		(end 146.262462 87.711518)
		(width 0.1016)
		(layer "In2.Cu")
		(net 35)
	)
	(segment
		(start 147.123409 88.057853)
		(end 147.100801 88.060401)
		(width 0.1016)
		(layer "In2.Cu")
		(net 35)
	)
	(segment
		(start 146.304001 88.060401)
		(end 146.281392 88.062948)
		(width 0.1016)
		(layer "In2.Cu")
		(net 35)
	)
	(segment
		(start 147.192339 87.914718)
		(end 147.199853 87.936192)
		(width 0.1016)
		(layer "In2.Cu")
		(net 35)
	)
	(segment
		(start 147.199853 87.936192)
		(end 147.202401 87.958801)
		(width 0.1016)
		(layer "In2.Cu")
		(net 35)
	)
	(segment
		(start 147.192339 88.002883)
		(end 147.180235 88.022147)
		(width 0.1016)
		(layer "In2.Cu")
		(net 35)
	)
	(segment
		(start 147.1 88.8)
		(end 146.2 88.8)
		(width 0.1016)
		(layer "In2.Cu")
		(net 35)
	)
	(segment
		(start 147.100801 88.060401)
		(end 146.304001 88.060401)
		(width 0.1016)
		(layer "In2.Cu")
		(net 35)
	)
	(segment
		(start 146.274566 87.818947)
		(end 146.290654 87.835035)
		(width 0.1016)
		(layer "In2.Cu")
		(net 35)
	)
	(segment
		(start 147.100801 87.857201)
		(end 147.123409 87.859748)
		(width 0.1016)
		(layer "In2.Cu")
		(net 35)
	)
	(segment
		(start 146.259918 88.253539)
		(end 146.281392 88.261053)
		(width 0.1016)
		(layer "In2.Cu")
		(net 35)
	)
	(segment
		(start 147.144883 88.050339)
		(end 147.123409 88.057853)
		(width 0.1016)
		(layer "In2.Cu")
		(net 35)
	)
	(segment
		(start 146.281392 88.261053)
		(end 146.304001 88.263601)
		(width 0.1016)
		(layer "In2.Cu")
		(net 35)
	)
	(segment
		(start 147.180235 88.022147)
		(end 147.164147 88.038235)
		(width 0.1016)
		(layer "In2.Cu")
		(net 35)
	)
	(segment
		(start 147.199853 87.575009)
		(end 147.192339 87.596483)
		(width 0.1016)
		(layer "In2.Cu")
		(net 35)
	)
	(segment
		(start 146.309918 87.664062)
		(end 146.290654 87.676166)
		(width 0.1016)
		(layer "In2.Cu")
		(net 35)
	)
	(segment
		(start 145.975 89.025)
		(end 145.975 92.3)
		(width 0.1016)
		(layer "In2.Cu")
		(net 35)
	)
	(segment
		(start 146.212462 88.117918)
		(end 146.204948 88.139392)
		(width 0.1016)
		(layer "In2.Cu")
		(net 35)
	)
	(segment
		(start 146.254948 87.778209)
		(end 146.262462 87.799683)
		(width 0.1016)
		(layer "In2.Cu")
		(net 35)
	)
	(segment
		(start 147.144883 87.643939)
		(end 147.123409 87.651453)
		(width 0.1016)
		(layer "In2.Cu")
		(net 35)
	)
	(segment
		(start 147.100801 88.263601)
		(end 147.123409 88.266148)
		(width 0.1016)
		(layer "In2.Cu")
		(net 35)
	)
	(segment
		(start 147.192339 87.596483)
		(end 147.180235 87.615747)
		(width 0.1016)
		(layer "In2.Cu")
		(net 35)
	)
	(segment
		(start 147.164147 87.631835)
		(end 147.144883 87.643939)
		(width 0.1016)
		(layer "In2.Cu")
		(net 35)
	)
	(segment
		(start 146.2 88.8)
		(end 145.975 89.025)
		(width 0.1016)
		(layer "In2.Cu")
		(net 35)
	)
	(segment
		(start 147.144883 88.273662)
		(end 147.164147 88.285766)
		(width 0.1016)
		(layer "In2.Cu")
		(net 35)
	)
	(segment
		(start 147.225 86.29)
		(end 147.202401 86.312599)
		(width 0.1016)
		(layer "In2.Cu")
		(net 35)
	)
	(segment
		(start 147.192339 88.321118)
		(end 147.199853 88.342592)
		(width 0.1016)
		(layer "In2.Cu")
		(net 35)
	)
	(segment
		(start 146.354001 87.857201)
		(end 147.100801 87.857201)
		(width 0.1016)
		(layer "In2.Cu")
		(net 35)
	)
	(segment
		(start 146.304001 88.263601)
		(end 147.100801 88.263601)
		(width 0.1016)
		(layer "In2.Cu")
		(net 35)
	)
	(segment
		(start 146.259918 88.070462)
		(end 146.240654 88.082566)
		(width 0.1016)
		(layer "In2.Cu")
		(net 35)
	)
	(segment
		(start 146.252401 87.755601)
		(end 146.254948 87.778209)
		(width 0.1016)
		(layer "In2.Cu")
		(net 35)
	)
	(segment
		(start 146.290654 87.676166)
		(end 146.274566 87.692254)
		(width 0.1016)
		(layer "In2.Cu")
		(net 35)
	)
	(segment
		(start 147.202401 86.312599)
		(end 147.202401 87.552401)
		(width 0.1016)
		(layer "In2.Cu")
		(net 35)
	)
	(segment
		(start 147.202401 88.697599)
		(end 147.1 88.8)
		(width 0.1016)
		(layer "In2.Cu")
		(net 35)
	)
	(segment
		(start 147.164147 88.285766)
		(end 147.180235 88.301854)
		(width 0.1016)
		(layer "In2.Cu")
		(net 35)
	)
	(segment
		(start 146.281392 88.062948)
		(end 146.259918 88.070462)
		(width 0.1016)
		(layer "In2.Cu")
		(net 35)
	)
	(segment
		(start 147.164147 88.038235)
		(end 147.144883 88.050339)
		(width 0.1016)
		(layer "In2.Cu")
		(net 35)
	)
	(segment
		(start 147.123409 88.266148)
		(end 147.144883 88.273662)
		(width 0.1016)
		(layer "In2.Cu")
		(net 35)
	)
	(segment
		(start 146.309918 87.847139)
		(end 146.331392 87.854653)
		(width 0.1016)
		(layer "In2.Cu")
		(net 35)
	)
	(segment
		(start 146.354001 87.654001)
		(end 146.331392 87.656548)
		(width 0.1016)
		(layer "In2.Cu")
		(net 35)
	)
	(segment
		(start 146.331392 87.854653)
		(end 146.354001 87.857201)
		(width 0.1016)
		(layer "In2.Cu")
		(net 35)
	)
	(segment
		(start 146.240654 88.241435)
		(end 146.259918 88.253539)
		(width 0.1016)
		(layer "In2.Cu")
		(net 35)
	)
	(segment
		(start 146.204948 88.139392)
		(end 146.202401 88.162001)
		(width 0.1016)
		(layer "In2.Cu")
		(net 35)
	)
	(segment
		(start 146.262462 87.711518)
		(end 146.254948 87.732992)
		(width 0.1016)
		(layer "In2.Cu")
		(net 35)
	)
	(segment
		(start 146.254948 87.732992)
		(end 146.252401 87.755601)
		(width 0.1016)
		(layer "In2.Cu")
		(net 35)
	)
	(segment
		(start 147.202401 87.552401)
		(end 147.199853 87.575009)
		(width 0.1016)
		(layer "In2.Cu")
		(net 35)
	)
	(segment
		(start 146.202401 88.162001)
		(end 146.204948 88.184609)
		(width 0.1016)
		(layer "In2.Cu")
		(net 35)
	)
	(segment
		(start 146.212462 88.206083)
		(end 146.224566 88.225347)
		(width 0.1016)
		(layer "In2.Cu")
		(net 35)
	)
	(segment
		(start 147.164147 87.879366)
		(end 147.180235 87.895454)
		(width 0.1016)
		(layer "In2.Cu")
		(net 35)
	)
	(segment
		(start 147.202401 87.958801)
		(end 147.199853 87.981409)
		(width 0.1016)
		(layer "In2.Cu")
		(net 35)
	)
	(segment
		(start 147.202401 88.365201)
		(end 147.202401 88.697599)
		(width 0.1016)
		(layer "In2.Cu")
		(net 35)
	)
	(segment
		(start 146.331392 87.656548)
		(end 146.309918 87.664062)
		(width 0.1016)
		(layer "In2.Cu")
		(net 35)
	)
	(segment
		(start 146.290654 87.835035)
		(end 146.309918 87.847139)
		(width 0.1016)
		(layer "In2.Cu")
		(net 35)
	)
	(segment
		(start 147.123409 87.859748)
		(end 147.144883 87.867262)
		(width 0.1016)
		(layer "In2.Cu")
		(net 35)
	)
	(segment
		(start 146.224566 88.098654)
		(end 146.212462 88.117918)
		(width 0.1016)
		(layer "In2.Cu")
		(net 35)
	)
	(segment
		(start 146.224566 88.225347)
		(end 146.240654 88.241435)
		(width 0.1016)
		(layer "In2.Cu")
		(net 35)
	)
	(segment
		(start 146.240654 88.082566)
		(end 146.224566 88.098654)
		(width 0.1016)
		(layer "In2.Cu")
		(net 35)
	)
	(segment
		(start 146.262462 87.799683)
		(end 146.274566 87.818947)
		(width 0.1016)
		(layer "In2.Cu")
		(net 35)
	)
	(segment
		(start 147.180235 87.615747)
		(end 147.164147 87.631835)
		(width 0.1016)
		(layer "In2.Cu")
		(net 35)
	)
	(segment
		(start 147.144883 87.867262)
		(end 147.164147 87.879366)
		(width 0.1016)
		(layer "In2.Cu")
		(net 35)
	)
	(segment
		(start 157.820407 90.818365)
		(end 157.792914 90.83564)
		(width 0.145)
		(layer "F.Cu")
		(net 36)
	)
	(segment
		(start 157.287734 90.273635)
		(end 157.257086 90.284359)
		(width 0.145)
		(layer "F.Cu")
		(net 36)
	)
	(segment
		(start 157.175 90.415)
		(end 157.178635 90.447265)
		(width 0.145)
		(layer "F.Cu")
		(net 36)
	)
	(segment
		(start 155.984172 94.514536)
		(end 155.963927 94.539921)
		(width 0.145)
		(layer "F.Cu")
		(net 36)
	)
	(segment
		(start 155.73988 95.454976)
		(end 155.719636 95.480363)
		(width 0.145)
		(layer "F.Cu")
		(net 36)
	)
	(segment
		(start 157.206634 92.644593)
		(end 157.189359 92.672086)
		(width 0.145)
		(layer "F.Cu")
		(net 36)
	)
	(segment
		(start 157.762266 92.006364)
		(end 157.73 92.01)
		(width 0.145)
		(layer "F.Cu")
		(net 36)
	)
	(segment
		(start 157.38 90.27)
		(end 157.32 90.27)
		(width 0.145)
		(layer "F.Cu")
		(net 36)
	)
	(segment
		(start 156.599354 94.104415)
		(end 156.573968 94.08417)
		(width 0.145)
		(layer "F.Cu")
		(net 36)
	)
	(segment
		(start 157.871365 91.897265)
		(end 157.860641 91.927913)
		(width 0.145)
		(layer "F.Cu")
		(net 36)
	)
	(segment
		(start 157.206634 90.505406)
		(end 157.229593 90.528365)
		(width 0.145)
		(layer "F.Cu")
		(net 36)
	)
	(segment
		(start 157.32 92.59)
		(end 157.287734 92.593635)
		(width 0.145)
		(layer "F.Cu")
		(net 36)
	)
	(segment
		(start 157.843366 92.354593)
		(end 157.860641 92.382086)
		(width 0.145)
		(layer "F.Cu")
		(net 36)
	)
	(segment
		(start 157.792914 91.41564)
		(end 157.762266 91.426364)
		(width 0.145)
		(layer "F.Cu")
		(net 36)
	)
	(segment
		(start 157.792914 91.99564)
		(end 157.762266 92.006364)
		(width 0.145)
		(layer "F.Cu")
		(net 36)
	)
	(segment
		(start 156.010992 95.111799)
		(end 155.979337 95.104574)
		(width 0.145)
		(layer "F.Cu")
		(net 36)
	)
	(segment
		(start 157.178635 91.607265)
		(end 157.189359 91.637913)
		(width 0.145)
		(layer "F.Cu")
		(net 36)
	)
	(segment
		(start 157.871365 91.317265)
		(end 157.860641 91.347913)
		(width 0.145)
		(layer "F.Cu")
		(net 36)
	)
	(segment
		(start 156.57421 94.509699)
		(end 156.581435 94.541355)
		(width 0.145)
		(layer "F.Cu")
		(net 36)
	)
	(segment
		(start 156.448933 94.070082)
		(end 156.419679 94.08417)
		(width 0.145)
		(layer "F.Cu")
		(net 36)
	)
	(segment
		(start 157.73 91.43)
		(end 157.32 91.43)
		(width 0.145)
		(layer "F.Cu")
		(net 36)
	)
	(segment
		(start 155.963927 94.694211)
		(end 155.984172 94.719596)
		(width 0.145)
		(layer "F.Cu")
		(net 36)
	)
	(segment
		(start 157.762266 91.143635)
		(end 157.792914 91.154359)
		(width 0.145)
		(layer "F.Cu")
		(net 36)
	)
	(segment
		(start 157.229593 92.621634)
		(end 157.206634 92.644593)
		(width 0.145)
		(layer "F.Cu")
		(net 36)
	)
	(segment
		(start 155.532493 95.043422)
		(end 155.539718 95.075077)
		(width 0.145)
		(layer "F.Cu")
		(net 36)
	)
	(segment
		(start 155.761193 95.361597)
		(end 155.761193 95.394067)
		(width 0.145)
		(layer "F.Cu")
		(net 36)
	)
	(segment
		(start 157.257086 92.024359)
		(end 157.229593 92.041634)
		(width 0.145)
		(layer "F.Cu")
		(net 36)
	)
	(segment
		(start 157.871365 92.412734)
		(end 157.875 92.445)
		(width 0.145)
		(layer "F.Cu")
		(net 36)
	)
	(segment
		(start 157.257086 90.864359)
		(end 157.229593 90.881634)
		(width 0.145)
		(layer "F.Cu")
		(net 36)
	)
	(segment
		(start 157.843366 91.955406)
		(end 157.820407 91.978365)
		(width 0.145)
		(layer "F.Cu")
		(net 36)
	)
	(segment
		(start 157.871365 92.992734)
		(end 157.875 93.025)
		(width 0.145)
		(layer "F.Cu")
		(net 36)
	)
	(segment
		(start 157.637735 93.173635)
		(end 157.607087 93.184359)
		(width 0.145)
		(layer "F.Cu")
		(net 36)
	)
	(segment
		(start 156.513058 94.062857)
		(end 156.480588 94.062857)
		(width 0.145)
		(layer "F.Cu")
		(net 36)
	)
	(segment
		(start 156.560122 94.634734)
		(end 156.539879 94.660121)
		(width 0.145)
		(layer "F.Cu")
		(net 36)
	)
	(segment
		(start 157.287734 91.136364)
		(end 157.32 91.14)
		(width 0.145)
		(layer "F.Cu")
		(net 36)
	)
	(segment
		(start 157.875 91.285)
		(end 157.871365 91.317265)
		(width 0.145)
		(layer "F.Cu")
		(net 36)
	)
	(segment
		(start 155.553806 95.104332)
		(end 155.574051 95.129717)
		(width 0.145)
		(layer "F.Cu")
		(net 36)
	)
	(segment
		(start 157.860641 91.802086)
		(end 157.871365 91.832734)
		(width 0.145)
		(layer "F.Cu")
		(net 36)
	)
	(segment
		(start 157.871365 91.252734)
		(end 157.875 91.285)
		(width 0.145)
		(layer "F.Cu")
		(net 36)
	)
	(segment
		(start 156.164089 94.91982)
		(end 156.171314 94.951476)
		(width 0.145)
		(layer "F.Cu")
		(net 36)
	)
	(segment
		(start 157.762266 91.426364)
		(end 157.73 91.43)
		(width 0.145)
		(layer "F.Cu")
		(net 36)
	)
	(segment
		(start 156.581435 94.541355)
		(end 156.581435 94.573825)
		(width 0.145)
		(layer "F.Cu")
		(net 36)
	)
	(segment
		(start 157.843366 92.535406)
		(end 157.820407 92.558365)
		(width 0.145)
		(layer "F.Cu")
		(net 36)
	)
	(segment
		(start 156.104372 95.090486)
		(end 156.075117 95.104574)
		(width 0.145)
		(layer "F.Cu")
		(net 36)
	)
	(segment
		(start 157.257086 92.28564)
		(end 157.287734 92.296364)
		(width 0.145)
		(layer "F.Cu")
		(net 36)
	)
	(segment
		(start 156.352735 94.22318)
		(end 156.35996 94.254835)
		(width 0.145)
		(layer "F.Cu")
		(net 36)
	)
	(segment
		(start 157.178635 90.447265)
		(end 157.189359 90.477913)
		(width 0.145)
		(layer "F.Cu")
		(net 36)
	)
	(segment
		(start 157.229593 92.041634)
		(end 157.206634 92.064593)
		(width 0.145)
		(layer "F.Cu")
		(net 36)
	)
	(segment
		(start 157.820407 91.171634)
		(end 157.843366 91.194593)
		(width 0.145)
		(layer "F.Cu")
		(net 36)
	)
	(segment
		(start 157.287734 90.853635)
		(end 157.257086 90.864359)
		(width 0.145)
		(layer "F.Cu")
		(net 36)
	)
	(segment
		(start 157.860641 92.507913)
		(end 157.843366 92.535406)
		(width 0.145)
		(layer "F.Cu")
		(net 36)
	)
	(segment
		(start 157.607087 93.184359)
		(end 157.579594 93.201634)
		(width 0.145)
		(layer "F.Cu")
		(net 36)
	)
	(segment
		(start 155.539718 94.979297)
		(end 155.532493 95.010952)
		(width 0.145)
		(layer "F.Cu")
		(net 36)
	)
	(segment
		(start 156.150001 95.044855)
		(end 156.129758 95.070242)
		(width 0.145)
		(layer "F.Cu")
		(net 36)
	)
	(segment
		(start 155.949839 94.569176)
		(end 155.942614 94.600831)
		(width 0.145)
		(layer "F.Cu")
		(net 36)
	)
	(segment
		(start 157.762266 90.563635)
		(end 157.792914 90.574359)
		(width 0.145)
		(layer "F.Cu")
		(net 36)
	)
	(segment
		(start 156.539877 94.455059)
		(end 156.560122 94.480445)
		(width 0.145)
		(layer "F.Cu")
		(net 36)
	)
	(segment
		(start 156.485238 94.694453)
		(end 156.453583 94.701678)
		(width 0.145)
		(layer "F.Cu")
		(net 36)
	)
	(segment
		(start 157.287734 92.013635)
		(end 157.257086 92.024359)
		(width 0.145)
		(layer "F.Cu")
		(net 36)
	)
	(segment
		(start 157.860641 91.347913)
		(end 157.843366 91.375406)
		(width 0.145)
		(layer "F.Cu")
		(net 36)
	)
	(segment
		(start 155.949839 94.664956)
		(end 155.963927 94.694211)
		(width 0.145)
		(layer "F.Cu")
		(net 36)
	)
	(segment
		(start 155.942614 94.633301)
		(end 155.949839 94.664956)
		(width 0.145)
		(layer "F.Cu")
		(net 36)
	)
	(segment
		(start 155.753968 95.425722)
		(end 155.73988 95.454976)
		(width 0.145)
		(layer "F.Cu")
		(net 36)
	)
	(segment
		(start 157.287734 92.593635)
		(end 157.257086 92.604359)
		(width 0.145)
		(layer "F.Cu")
		(net 36)
	)
	(segment
		(start 156.453583 94.701678)
		(end 156.421113 94.701678)
		(width 0.145)
		(layer "F.Cu")
		(net 36)
	)
	(segment
		(start 157.51064 90.187913)
		(end 157.493365 90.215406)
		(width 0.145)
		(layer "F.Cu")
		(net 36)
	)
	(segment
		(start 157.189359 90.932086)
		(end 157.178635 90.962734)
		(width 0.145)
		(layer "F.Cu")
		(net 36)
	)
	(segment
		(start 157.189359 92.672086)
		(end 157.178635 92.702734)
		(width 0.145)
		(layer "F.Cu")
		(net 36)
	)
	(segment
		(start 157.762266 91.723635)
		(end 157.792914 91.734359)
		(width 0.145)
		(layer "F.Cu")
		(net 36)
	)
	(segment
		(start 155.73988 95.300687)
		(end 155.753968 95.329941)
		(width 0.145)
		(layer "F.Cu")
		(net 36)
	)
	(segment
		(start 156.95 94.25)
		(end 156.924614 94.270244)
		(width 0.145)
		(layer "F.Cu")
		(net 36)
	)
	(segment
		(start 157.762266 92.586364)
		(end 157.73 92.59)
		(width 0.145)
		(layer "F.Cu")
		(net 36)
	)
	(segment
		(start 157.860641 92.382086)
		(end 157.871365 92.412734)
		(width 0.145)
		(layer "F.Cu")
		(net 36)
	)
	(segment
		(start 157.206634 92.245406)
		(end 157.229593 92.268365)
		(width 0.145)
		(layer "F.Cu")
		(net 36)
	)
	(segment
		(start 155.761193 95.394067)
		(end 155.753968 95.425722)
		(width 0.145)
		(layer "F.Cu")
		(net 36)
	)
	(segment
		(start 155.753726 94.904412)
		(end 155.724472 94.890324)
		(width 0.145)
		(layer "F.Cu")
		(net 36)
	)
	(segment
		(start 156.394293 94.104415)
		(end 156.374048 94.1298)
		(width 0.145)
		(layer "F.Cu")
		(net 36)
	)
	(segment
		(start 156.374048 94.1298)
		(end 156.35996 94.159055)
		(width 0.145)
		(layer "F.Cu")
		(net 36)
	)
	(segment
		(start 157.843366 91.774593)
		(end 157.860641 91.802086)
		(width 0.145)
		(layer "F.Cu")
		(net 36)
	)
	(segment
		(start 157.178635 91.542734)
		(end 157.175 91.575)
		(width 0.145)
		(layer "F.Cu")
		(net 36)
	)
	(segment
		(start 156.075117 95.104574)
		(end 156.043462 95.111799)
		(width 0.145)
		(layer "F.Cu")
		(net 36)
	)
	(segment
		(start 157.32 91.43)
		(end 157.287734 91.433635)
		(width 0.145)
		(layer "F.Cu")
		(net 36)
	)
	(segment
		(start 156.171314 94.951476)
		(end 156.171314 94.983946)
		(width 0.145)
		(layer "F.Cu")
		(net 36)
	)
	(segment
		(start 157.860641 90.642086)
		(end 157.871365 90.672734)
		(width 0.145)
		(layer "F.Cu")
		(net 36)
	)
	(segment
		(start 157.32 90.56)
		(end 157.73 90.56)
		(width 0.145)
		(layer "F.Cu")
		(net 36)
	)
	(segment
		(start 157.843366 91.375406)
		(end 157.820407 91.398365)
		(width 0.145)
		(layer "F.Cu")
		(net 36)
	)
	(segment
		(start 157.287734 92.876364)
		(end 157.32 92.88)
		(width 0.145)
		(layer "F.Cu")
		(net 36)
	)
	(segment
		(start 156.352735 94.19071)
		(end 156.352735 94.22318)
		(width 0.145)
		(layer "F.Cu")
		(net 36)
	)
	(segment
		(start 157.229593 90.301634)
		(end 157.206634 90.324593)
		(width 0.145)
		(layer "F.Cu")
		(net 36)
	)
	(segment
		(start 155.963927 94.539921)
		(end 155.949839 94.569176)
		(width 0.145)
		(layer "F.Cu")
		(net 36)
	)
	(segment
		(start 157.287734 91.433635)
		(end 157.257086 91.444359)
		(width 0.145)
		(layer "F.Cu")
		(net 36)
	)
	(segment
		(start 156.924614 94.270244)
		(end 156.895359 94.284332)
		(width 0.145)
		(layer "F.Cu")
		(net 36)
	)
	(segment
		(start 156.35996 94.254835)
		(end 156.374048 94.28409)
		(width 0.145)
		(layer "F.Cu")
		(net 36)
	)
	(segment
		(start 157.175 91.575)
		(end 157.178635 91.607265)
		(width 0.145)
		(layer "F.Cu")
		(net 36)
	)
	(segment
		(start 157.287734 91.716364)
		(end 157.32 91.72)
		(width 0.145)
		(layer "F.Cu")
		(net 36)
	)
	(segment
		(start 157.73 93.17)
		(end 157.67 93.17)
		(width 0.145)
		(layer "F.Cu")
		(net 36)
	)
	(segment
		(start 157.178635 91.027265)
		(end 157.189359 91.057913)
		(width 0.145)
		(layer "F.Cu")
		(net 36)
	)
	(segment
		(start 155.660346 94.883099)
		(end 155.628691 94.890324)
		(width 0.145)
		(layer "F.Cu")
		(net 36)
	)
	(segment
		(start 156.171314 94.983946)
		(end 156.164089 95.015601)
		(width 0.145)
		(layer "F.Cu")
		(net 36)
	)
	(segment
		(start 157.875 90.705)
		(end 157.871365 90.737265)
		(width 0.145)
		(layer "F.Cu")
		(net 36)
	)
	(segment
		(start 155.719636 95.480363)
		(end 154.925 96.275)
		(width 0.145)
		(layer "F.Cu")
		(net 36)
	)
	(segment
		(start 155.692816 94.883099)
		(end 155.660346 94.883099)
		(width 0.145)
		(layer "F.Cu")
		(net 36)
	)
	(segment
		(start 157.843366 90.614593)
		(end 157.860641 90.642086)
		(width 0.145)
		(layer "F.Cu")
		(net 36)
	)
	(segment
		(start 157.792914 91.734359)
		(end 157.820407 91.751634)
		(width 0.145)
		(layer "F.Cu")
		(net 36)
	)
	(segment
		(start 157.871365 91.832734)
		(end 157.875 91.865)
		(width 0.145)
		(layer "F.Cu")
		(net 36)
	)
	(segment
		(start 157.860641 91.927913)
		(end 157.843366 91.955406)
		(width 0.145)
		(layer "F.Cu")
		(net 36)
	)
	(segment
		(start 156.360203 94.680365)
		(end 156.334818 94.660121)
		(width 0.145)
		(layer "F.Cu")
		(net 36)
	)
	(segment
		(start 157.525 89.67)
		(end 157.525 90.125)
		(width 0.145)
		(layer "F.Cu")
		(net 36)
	)
	(segment
		(start 157.843366 90.795406)
		(end 157.820407 90.818365)
		(width 0.145)
		(layer "F.Cu")
		(net 36)
	)
	(segment
		(start 157.762266 93.166364)
		(end 157.73 93.17)
		(width 0.145)
		(layer "F.Cu")
		(net 36)
	)
	(segment
		(start 157.493365 90.215406)
		(end 157.470406 90.238365)
		(width 0.145)
		(layer "F.Cu")
		(net 36)
	)
	(segment
		(start 157.178635 92.702734)
		(end 157.175 92.735)
		(width 0.145)
		(layer "F.Cu")
		(net 36)
	)
	(segment
		(start 157.32 91.14)
		(end 157.73 91.14)
		(width 0.145)
		(layer "F.Cu")
		(net 36)
	)
	(segment
		(start 157.579594 93.201634)
		(end 157.556635 93.224593)
		(width 0.145)
		(layer "F.Cu")
		(net 36)
	)
	(segment
		(start 157.871365 90.737265)
		(end 157.860641 90.767913)
		(width 0.145)
		(layer "F.Cu")
		(net 36)
	)
	(segment
		(start 157.206634 91.085406)
		(end 157.229593 91.108365)
		(width 0.145)
		(layer "F.Cu")
		(net 36)
	)
	(segment
		(start 157.762266 92.883635)
		(end 157.792914 92.894359)
		(width 0.145)
		(layer "F.Cu")
		(net 36)
	)
	(segment
		(start 157.792914 91.154359)
		(end 157.820407 91.171634)
		(width 0.145)
		(layer "F.Cu")
		(net 36)
	)
	(segment
		(start 157.792914 90.83564)
		(end 157.762266 90.846364)
		(width 0.145)
		(layer "F.Cu")
		(net 36)
	)
	(segment
		(start 157.860641 93.087913)
		(end 157.843366 93.115406)
		(width 0.145)
		(layer "F.Cu")
		(net 36)
	)
	(segment
		(start 155.984172 94.719596)
		(end 156.129756 94.86518)
		(width 0.145)
		(layer "F.Cu")
		(net 36)
	)
	(segment
		(start 156.560122 94.480445)
		(end 156.57421 94.509699)
		(width 0.145)
		(layer "F.Cu")
		(net 36)
	)
	(segment
		(start 156.334818 94.660121)
		(end 156.189233 94.514536)
		(width 0.145)
		(layer "F.Cu")
		(net 36)
	)
	(segment
		(start 157.32 91.72)
		(end 157.73 91.72)
		(width 0.145)
		(layer "F.Cu")
		(net 36)
	)
	(segment
		(start 157.762266 90.846364)
		(end 157.73 90.85)
		(width 0.145)
		(layer "F.Cu")
		(net 36)
	)
	(segment
		(start 157.73 91.14)
		(end 157.762266 91.143635)
		(width 0.145)
		(layer "F.Cu")
		(net 36)
	)
	(segment
		(start 157.820407 92.558365)
		(end 157.792914 92.57564)
		(width 0.145)
		(layer "F.Cu")
		(net 36)
	)
	(segment
		(start 157.257086 91.70564)
		(end 157.287734 91.716364)
		(width 0.145)
		(layer "F.Cu")
		(net 36)
	)
	(segment
		(start 157.521364 90.157265)
		(end 157.51064 90.187913)
		(width 0.145)
		(layer "F.Cu")
		(net 36)
	)
	(segment
		(start 156.129758 95.070242)
		(end 156.104372 95.090486)
		(width 0.145)
		(layer "F.Cu")
		(net 36)
	)
	(segment
		(start 155.724472 94.890324)
		(end 155.692816 94.883099)
		(width 0.145)
		(layer "F.Cu")
		(net 36)
	)
	(segment
		(start 157.206634 90.324593)
		(end 157.189359 90.352086)
		(width 0.145)
		(layer "F.Cu")
		(net 36)
	)
	(segment
		(start 157.820407 91.398365)
		(end 157.792914 91.41564)
		(width 0.145)
		(layer "F.Cu")
		(net 36)
	)
	(segment
		(start 155.574051 95.129717)
		(end 155.719635 95.275301)
		(width 0.145)
		(layer "F.Cu")
		(net 36)
	)
	(segment
		(start 156.35996 94.159055)
		(end 156.352735 94.19071)
		(width 0.145)
		(layer "F.Cu")
		(net 36)
	)
	(segment
		(start 155.719635 95.275301)
		(end 155.73988 95.300687)
		(width 0.145)
		(layer "F.Cu")
		(net 36)
	)
	(segment
		(start 157.792914 92.894359)
		(end 157.820407 92.911634)
		(width 0.145)
		(layer "F.Cu")
		(net 36)
	)
	(segment
		(start 157.73 92.88)
		(end 157.762266 92.883635)
		(width 0.145)
		(layer "F.Cu")
		(net 36)
	)
	(segment
		(start 157.820407 92.331634)
		(end 157.843366 92.354593)
		(width 0.145)
		(layer "F.Cu")
		(net 36)
	)
	(segment
		(start 156.150001 94.890566)
		(end 156.164089 94.91982)
		(width 0.145)
		(layer "F.Cu")
		(net 36)
	)
	(segment
		(start 157.820407 91.751634)
		(end 157.843366 91.774593)
		(width 0.145)
		(layer "F.Cu")
		(net 36)
	)
	(segment
		(start 156.389458 94.694453)
		(end 156.360203 94.680365)
		(width 0.145)
		(layer "F.Cu")
		(net 36)
	)
	(segment
		(start 156.134593 94.480203)
		(end 156.102937 94.472978)
		(width 0.145)
		(layer "F.Cu")
		(net 36)
	)
	(segment
		(start 157.871365 92.477265)
		(end 157.860641 92.507913)
		(width 0.145)
		(layer "F.Cu")
		(net 36)
	)
	(segment
		(start 156.573968 94.08417)
		(end 156.544714 94.070082)
		(width 0.145)
		(layer "F.Cu")
		(net 36)
	)
	(segment
		(start 157.792914 92.314359)
		(end 157.820407 92.331634)
		(width 0.145)
		(layer "F.Cu")
		(net 36)
	)
	(segment
		(start 156.102937 94.472978)
		(end 156.070467 94.472978)
		(width 0.145)
		(layer "F.Cu")
		(net 36)
	)
	(segment
		(start 157.32 92.88)
		(end 157.73 92.88)
		(width 0.145)
		(layer "F.Cu")
		(net 36)
	)
	(segment
		(start 157.178635 92.767265)
		(end 157.189359 92.797913)
		(width 0.145)
		(layer "F.Cu")
		(net 36)
	)
	(segment
		(start 157.206634 92.064593)
		(end 157.189359 92.092086)
		(width 0.145)
		(layer "F.Cu")
		(net 36)
	)
	(segment
		(start 157.175 92.155)
		(end 157.178635 92.187265)
		(width 0.145)
		(layer "F.Cu")
		(net 36)
	)
	(segment
		(start 157.792914 92.57564)
		(end 157.762266 92.586364)
		(width 0.145)
		(layer "F.Cu")
		(net 36)
	)
	(segment
		(start 157.206634 91.665406)
		(end 157.229593 91.688365)
		(width 0.145)
		(layer "F.Cu")
		(net 36)
	)
	(segment
		(start 156.863704 94.291557)
		(end 156.831234 94.291557)
		(width 0.145)
		(layer "F.Cu")
		(net 36)
	)
	(segment
		(start 157.189359 92.797913)
		(end 157.206634 92.825406)
		(width 0.145)
		(layer "F.Cu")
		(net 36)
	)
	(segment
		(start 157.843366 92.934593)
		(end 157.860641 92.962086)
		(width 0.145)
		(layer "F.Cu")
		(net 36)
	)
	(segment
		(start 157.525 90.125)
		(end 157.521364 90.157265)
		(width 0.145)
		(layer "F.Cu")
		(net 36)
	)
	(segment
		(start 157.189359 92.092086)
		(end 157.178635 92.122734)
		(width 0.145)
		(layer "F.Cu")
		(net 36)
	)
	(segment
		(start 157.229593 92.848365)
		(end 157.257086 92.86564)
		(width 0.145)
		(layer "F.Cu")
		(net 36)
	)
	(segment
		(start 157.229593 92.268365)
		(end 157.257086 92.28564)
		(width 0.145)
		(layer "F.Cu")
		(net 36)
	)
	(segment
		(start 156.895359 94.284332)
		(end 156.863704 94.291557)
		(width 0.145)
		(layer "F.Cu")
		(net 36)
	)
	(segment
		(start 156.799579 94.284332)
		(end 156.770324 94.270244)
		(width 0.145)
		(layer "F.Cu")
		(net 36)
	)
	(segment
		(start 156.163847 94.494291)
		(end 156.134593 94.480203)
		(width 0.145)
		(layer "F.Cu")
		(net 36)
	)
	(segment
		(start 157.189359 91.637913)
		(end 157.206634 91.665406)
		(width 0.145)
		(layer "F.Cu")
		(net 36)
	)
	(segment
		(start 157.178635 90.962734)
		(end 157.175 90.995)
		(width 0.145)
		(layer "F.Cu")
		(net 36)
	)
	(segment
		(start 156.038812 94.480203)
		(end 156.009558 94.494291)
		(width 0.145)
		(layer "F.Cu")
		(net 36)
	)
	(segment
		(start 157.178635 90.382734)
		(end 157.175 90.415)
		(width 0.145)
		(layer "F.Cu")
		(net 36)
	)
	(segment
		(start 157.875 93.025)
		(end 157.871365 93.057265)
		(width 0.145)
		(layer "F.Cu")
		(net 36)
	)
	(segment
		(start 156.129756 94.86518)
		(end 156.150001 94.890566)
		(width 0.145)
		(layer "F.Cu")
		(net 36)
	)
	(segment
		(start 155.539718 95.075077)
		(end 155.553806 95.104332)
		(width 0.145)
		(layer "F.Cu")
		(net 36)
	)
	(segment
		(start 157.73 90.56)
		(end 157.762266 90.563635)
		(width 0.145)
		(layer "F.Cu")
		(net 36)
	)
	(segment
		(start 157.525 93.315)
		(end 157.525 93.675)
		(width 0.145)
		(layer "F.Cu")
		(net 36)
	)
	(segment
		(start 157.875 91.865)
		(end 157.871365 91.897265)
		(width 0.145)
		(layer "F.Cu")
		(net 36)
	)
	(segment
		(start 157.178635 92.122734)
		(end 157.175 92.155)
		(width 0.145)
		(layer "F.Cu")
		(net 36)
	)
	(segment
		(start 157.229593 91.461634)
		(end 157.206634 91.484593)
		(width 0.145)
		(layer "F.Cu")
		(net 36)
	)
	(segment
		(start 156.831234 94.291557)
		(end 156.799579 94.284332)
		(width 0.145)
		(layer "F.Cu")
		(net 36)
	)
	(segment
		(start 155.553806 94.950042)
		(end 155.539718 94.979297)
		(width 0.145)
		(layer "F.Cu")
		(net 36)
	)
	(segment
		(start 157.412265 90.266364)
		(end 157.38 90.27)
		(width 0.145)
		(layer "F.Cu")
		(net 36)
	)
	(segment
		(start 157.189359 91.512086)
		(end 157.178635 91.542734)
		(width 0.145)
		(layer "F.Cu")
		(net 36)
	)
	(segment
		(start 156.744939 94.25)
		(end 156.599354 94.104415)
		(width 0.145)
		(layer "F.Cu")
		(net 36)
	)
	(segment
		(start 157.843366 91.194593)
		(end 157.860641 91.222086)
		(width 0.145)
		(layer "F.Cu")
		(net 36)
	)
	(segment
		(start 156.539879 94.660121)
		(end 156.514493 94.680365)
		(width 0.145)
		(layer "F.Cu")
		(net 36)
	)
	(segment
		(start 157.175 92.735)
		(end 157.178635 92.767265)
		(width 0.145)
		(layer "F.Cu")
		(net 36)
	)
	(segment
		(start 155.950082 95.090486)
		(end 155.924697 95.070242)
		(width 0.145)
		(layer "F.Cu")
		(net 36)
	)
	(segment
		(start 157.206634 91.484593)
		(end 157.189359 91.512086)
		(width 0.145)
		(layer "F.Cu")
		(net 36)
	)
	(segment
		(start 157.257086 91.444359)
		(end 157.229593 91.461634)
		(width 0.145)
		(layer "F.Cu")
		(net 36)
	)
	(segment
		(start 157.229593 90.528365)
		(end 157.257086 90.54564)
		(width 0.145)
		(layer "F.Cu")
		(net 36)
	)
	(segment
		(start 157.860641 92.962086)
		(end 157.871365 92.992734)
		(width 0.145)
		(layer "F.Cu")
		(net 36)
	)
	(segment
		(start 156.394293 94.309475)
		(end 156.539877 94.455059)
		(width 0.145)
		(layer "F.Cu")
		(net 36)
	)
	(segment
		(start 157.206634 90.904593)
		(end 157.189359 90.932086)
		(width 0.145)
		(layer "F.Cu")
		(net 36)
	)
	(segment
		(start 157.178635 92.187265)
		(end 157.189359 92.217913)
		(width 0.145)
		(layer "F.Cu")
		(net 36)
	)
	(segment
		(start 157.229593 90.881634)
		(end 157.206634 90.904593)
		(width 0.145)
		(layer "F.Cu")
		(net 36)
	)
	(segment
		(start 157.257086 90.54564)
		(end 157.287734 90.556364)
		(width 0.145)
		(layer "F.Cu")
		(net 36)
	)
	(segment
		(start 157.792914 93.15564)
		(end 157.762266 93.166364)
		(width 0.145)
		(layer "F.Cu")
		(net 36)
	)
	(segment
		(start 157.287734 92.296364)
		(end 157.32 92.3)
		(width 0.145)
		(layer "F.Cu")
		(net 36)
	)
	(segment
		(start 157.762266 92.303635)
		(end 157.792914 92.314359)
		(width 0.145)
		(layer "F.Cu")
		(net 36)
	)
	(segment
		(start 157.73 92.59)
		(end 157.32 92.59)
		(width 0.145)
		(layer "F.Cu")
		(net 36)
	)
	(segment
		(start 157.189359 90.352086)
		(end 157.178635 90.382734)
		(width 0.145)
		(layer "F.Cu")
		(net 36)
	)
	(segment
		(start 156.770324 94.270244)
		(end 156.744939 94.25)
		(width 0.145)
		(layer "F.Cu")
		(net 36)
	)
	(segment
		(start 157.229593 91.108365)
		(end 157.257086 91.12564)
		(width 0.145)
		(layer "F.Cu")
		(net 36)
	)
	(segment
		(start 157.73 90.85)
		(end 157.32 90.85)
		(width 0.145)
		(layer "F.Cu")
		(net 36)
	)
	(segment
		(start 156.514493 94.680365)
		(end 156.485238 94.694453)
		(width 0.145)
		(layer "F.Cu")
		(net 36)
	)
	(segment
		(start 157.189359 92.217913)
		(end 157.206634 92.245406)
		(width 0.145)
		(layer "F.Cu")
		(net 36)
	)
	(segment
		(start 157.528636 93.282734)
		(end 157.525 93.315)
		(width 0.145)
		(layer "F.Cu")
		(net 36)
	)
	(segment
		(start 156.043462 95.111799)
		(end 156.010992 95.111799)
		(width 0.145)
		(layer "F.Cu")
		(net 36)
	)
	(segment
		(start 157.73 92.3)
		(end 157.762266 92.303635)
		(width 0.145)
		(layer "F.Cu")
		(net 36)
	)
	(segment
		(start 157.53936 93.252086)
		(end 157.528636 93.282734)
		(width 0.145)
		(layer "F.Cu")
		(net 36)
	)
	(segment
		(start 155.979337 95.104574)
		(end 155.950082 95.090486)
		(width 0.145)
		(layer "F.Cu")
		(net 36)
	)
	(segment
		(start 155.599437 94.904412)
		(end 155.574051 94.924657)
		(width 0.145)
		(layer "F.Cu")
		(net 36)
	)
	(segment
		(start 157.73 91.72)
		(end 157.762266 91.723635)
		(width 0.145)
		(layer "F.Cu")
		(net 36)
	)
	(segment
		(start 157.257086 91.12564)
		(end 157.287734 91.136364)
		(width 0.145)
		(layer "F.Cu")
		(net 36)
	)
	(segment
		(start 154.925 96.275)
		(end 154.925 98.7)
		(width 0.145)
		(layer "F.Cu")
		(net 36)
	)
	(segment
		(start 157.860641 91.222086)
		(end 157.871365 91.252734)
		(width 0.145)
		(layer "F.Cu")
		(net 36)
	)
	(segment
		(start 156.57421 94.60548)
		(end 156.560122 94.634734)
		(width 0.145)
		(layer "F.Cu")
		(net 36)
	)
	(segment
		(start 155.628691 94.890324)
		(end 155.599437 94.904412)
		(width 0.145)
		(layer "F.Cu")
		(net 36)
	)
	(segment
		(start 156.070467 94.472978)
		(end 156.038812 94.480203)
		(width 0.145)
		(layer "F.Cu")
		(net 36)
	)
	(segment
		(start 156.189233 94.514536)
		(end 156.163847 94.494291)
		(width 0.145)
		(layer "F.Cu")
		(net 36)
	)
	(segment
		(start 156.419679 94.08417)
		(end 156.394293 94.104415)
		(width 0.145)
		(layer "F.Cu")
		(net 36)
	)
	(segment
		(start 157.189359 91.057913)
		(end 157.206634 91.085406)
		(width 0.145)
		(layer "F.Cu")
		(net 36)
	)
	(segment
		(start 157.470406 90.238365)
		(end 157.442913 90.25564)
		(width 0.145)
		(layer "F.Cu")
		(net 36)
	)
	(segment
		(start 156.421113 94.701678)
		(end 156.389458 94.694453)
		(width 0.145)
		(layer "F.Cu")
		(net 36)
	)
	(segment
		(start 157.257086 92.604359)
		(end 157.229593 92.621634)
		(width 0.145)
		(layer "F.Cu")
		(net 36)
	)
	(segment
		(start 157.189359 90.477913)
		(end 157.206634 90.505406)
		(width 0.145)
		(layer "F.Cu")
		(net 36)
	)
	(segment
		(start 156.374048 94.28409)
		(end 156.394293 94.309475)
		(width 0.145)
		(layer "F.Cu")
		(net 36)
	)
	(segment
		(start 157.871365 90.672734)
		(end 157.875 90.705)
		(width 0.145)
		(layer "F.Cu")
		(net 36)
	)
	(segment
		(start 156.581435 94.573825)
		(end 156.57421 94.60548)
		(width 0.145)
		(layer "F.Cu")
		(net 36)
	)
	(segment
		(start 157.820407 92.911634)
		(end 157.843366 92.934593)
		(width 0.145)
		(layer "F.Cu")
		(net 36)
	)
	(segment
		(start 157.229593 91.688365)
		(end 157.257086 91.70564)
		(width 0.145)
		(layer "F.Cu")
		(net 36)
	)
	(segment
		(start 155.574051 94.924657)
		(end 155.553806 94.950042)
		(width 0.145)
		(layer "F.Cu")
		(net 36)
	)
	(segment
		(start 155.924697 95.070242)
		(end 155.779112 94.924657)
		(width 0.145)
		(layer "F.Cu")
		(net 36)
	)
	(segment
		(start 157.525 93.675)
		(end 156.95 94.25)
		(width 0.145)
		(layer "F.Cu")
		(net 36)
	)
	(segment
		(start 157.556635 93.224593)
		(end 157.53936 93.252086)
		(width 0.145)
		(layer "F.Cu")
		(net 36)
	)
	(segment
		(start 156.480588 94.062857)
		(end 156.448933 94.070082)
		(width 0.145)
		(layer "F.Cu")
		(net 36)
	)
	(segment
		(start 157.257086 90.284359)
		(end 157.229593 90.301634)
		(width 0.145)
		(layer "F.Cu")
		(net 36)
	)
	(segment
		(start 157.820407 91.978365)
		(end 157.792914 91.99564)
		(width 0.145)
		(layer "F.Cu")
		(net 36)
	)
	(segment
		(start 157.820407 90.591634)
		(end 157.843366 90.614593)
		(width 0.145)
		(layer "F.Cu")
		(net 36)
	)
	(segment
		(start 157.206634 92.825406)
		(end 157.229593 92.848365)
		(width 0.145)
		(layer "F.Cu")
		(net 36)
	)
	(segment
		(start 157.32 90.27)
		(end 157.287734 90.273635)
		(width 0.145)
		(layer "F.Cu")
		(net 36)
	)
	(segment
		(start 157.843366 93.115406)
		(end 157.820407 93.138365)
		(width 0.145)
		(layer "F.Cu")
		(net 36)
	)
	(segment
		(start 155.779112 94.924657)
		(end 155.753726 94.904412)
		(width 0.145)
		(layer "F.Cu")
		(net 36)
	)
	(segment
		(start 155.753968 95.329941)
		(end 155.761193 95.361597)
		(width 0.145)
		(layer "F.Cu")
		(net 36)
	)
	(segment
		(start 157.860641 90.767913)
		(end 157.843366 90.795406)
		(width 0.145)
		(layer "F.Cu")
		(net 36)
	)
	(segment
		(start 157.875 92.445)
		(end 157.871365 92.477265)
		(width 0.145)
		(layer "F.Cu")
		(net 36)
	)
	(segment
		(start 157.175 90.995)
		(end 157.178635 91.027265)
		(width 0.145)
		(layer "F.Cu")
		(net 36)
	)
	(segment
		(start 157.792914 90.574359)
		(end 157.820407 90.591634)
		(width 0.145)
		(layer "F.Cu")
		(net 36)
	)
	(segment
		(start 157.287734 90.556364)
		(end 157.32 90.56)
		(width 0.145)
		(layer "F.Cu")
		(net 36)
	)
	(segment
		(start 157.32 92.01)
		(end 157.287734 92.013635)
		(width 0.145)
		(layer "F.Cu")
		(net 36)
	)
	(segment
		(start 157.442913 90.25564)
		(end 157.412265 90.266364)
		(width 0.145)
		(layer "F.Cu")
		(net 36)
	)
	(segment
		(start 155.942614 94.600831)
		(end 155.942614 94.633301)
		(width 0.145)
		(layer "F.Cu")
		(net 36)
	)
	(segment
		(start 157.73 92.01)
		(end 157.32 92.01)
		(width 0.145)
		(layer "F.Cu")
		(net 36)
	)
	(segment
		(start 157.871365 93.057265)
		(end 157.860641 93.087913)
		(width 0.145)
		(layer "F.Cu")
		(net 36)
	)
	(segment
		(start 157.32 92.3)
		(end 157.73 92.3)
		(width 0.145)
		(layer "F.Cu")
		(net 36)
	)
	(segment
		(start 157.32 90.85)
		(end 157.287734 90.853635)
		(width 0.145)
		(layer "F.Cu")
		(net 36)
	)
	(segment
		(start 157.820407 93.138365)
		(end 157.792914 93.15564)
		(width 0.145)
		(layer "F.Cu")
		(net 36)
	)
	(segment
		(start 157.257086 92.86564)
		(end 157.287734 92.876364)
		(width 0.145)
		(layer "F.Cu")
		(net 36)
	)
	(segment
		(start 157.67 93.17)
		(end 157.637735 93.173635)
		(width 0.145)
		(layer "F.Cu")
		(net 36)
	)
	(segment
		(start 155.532493 95.010952)
		(end 155.532493 95.043422)
		(width 0.145)
		(layer "F.Cu")
		(net 36)
	)
	(segment
		(start 156.544714 94.070082)
		(end 156.513058 94.062857)
		(width 0.145)
		(layer "F.Cu")
		(net 36)
	)
	(segment
		(start 156.164089 95.015601)
		(end 156.150001 95.044855)
		(width 0.145)
		(layer "F.Cu")
		(net 36)
	)
	(segment
		(start 156.009558 94.494291)
		(end 155.984172 94.514536)
		(width 0.145)
		(layer "F.Cu")
		(net 36)
	)
	(segment
		(start 154.3008 86.7508)
		(end 154.425 86.875)
		(width 0.1016)
		(layer "F.Cu")
		(net 37)
	)
	(segment
		(start 154.3008 86.334949)
		(end 154.3008 86.7508)
		(width 0.1016)
		(layer "F.Cu")
		(net 37)
	)
	(via
		(at 154.3008 86.334949)
		(size 0.45)
		(drill 0.15)
		(layers "F.Cu" "B.Cu")
		(net 37)
	)
	(via
		(at 154.375 89.620991)
		(size 0.45)
		(drill 0.15)
		(layers "F.Cu" "B.Cu")
		(net 37)
	)
	(segment
		(start 146.394858 95.160968)
		(end 146.371461 95.175669)
		(width 0.1016)
		(layer "B.Cu")
		(net 37)
	)
	(segment
		(start 146.4484 95.148748)
		(end 146.42094 95.151841)
		(width 0.1016)
		(layer "B.Cu")
		(net 37)
	)
	(segment
		(start 146.294525 95.52739)
		(end 146.257863 95.585737)
		(width 0.1016)
		(layer "B.Cu")
		(net 37)
	)
	(segment
		(start 144.675 96.824999)
		(end 144.675 98.7)
		(width 0.1016)
		(layer "B.Cu")
		(net 37)
	)
	(segment
		(start 154.375 89.620991)
		(end 154.1266 89.869391)
		(width 0.1016)
		(layer "B.Cu")
		(net 37)
	)
	(segment
		(start 146.559579 95.218606)
		(end 146.544878 95.195209)
		(width 0.1016)
		(layer "B.Cu")
		(net 37)
	)
	(segment
		(start 146.544878 95.195209)
		(end 146.525338 95.175669)
		(width 0.1016)
		(layer "B.Cu")
		(net 37)
	)
	(segment
		(start 146.525338 95.175669)
		(end 146.501941 95.160968)
		(width 0.1016)
		(layer "B.Cu")
		(net 37)
	)
	(segment
		(start 146.579515 95.462347)
		(end 146.5718 95.393872)
		(width 0.1016)
		(layer "B.Cu")
		(net 37)
	)
	(segment
		(start 146.638936 95.585737)
		(end 146.602274 95.52739)
		(width 0.1016)
		(layer "B.Cu")
		(net 37)
	)
	(segment
		(start 146.475859 95.151841)
		(end 146.4484 95.148748)
		(width 0.1016)
		(layer "B.Cu")
		(net 37)
	)
	(segment
		(start 146.746009 95.671125)
		(end 146.687662 95.634463)
		(width 0.1016)
		(layer "B.Cu")
		(net 37)
	)
	(segment
		(start 146.325 95.393872)
		(end 146.317284 95.462347)
		(width 0.1016)
		(layer "B.Cu")
		(net 37)
	)
	(segment
		(start 146.085747 95.693884)
		(end 146.017272 95.7016)
		(width 0.1016)
		(layer "B.Cu")
		(net 37)
	)
	(segment
		(start 146.351921 95.195209)
		(end 146.33722 95.218606)
		(width 0.1016)
		(layer "B.Cu")
		(net 37)
	)
	(segment
		(start 146.568706 95.244688)
		(end 146.559579 95.218606)
		(width 0.1016)
		(layer "B.Cu")
		(net 37)
	)
	(segment
		(start 144.5266 96.217086)
		(end 144.5266 96.676599)
		(width 0.1016)
		(layer "B.Cu")
		(net 37)
	)
	(segment
		(start 144.5266 96.676599)
		(end 144.675 96.824999)
		(width 0.1016)
		(layer "B.Cu")
		(net 37)
	)
	(segment
		(start 146.501941 95.160968)
		(end 146.475859 95.151841)
		(width 0.1016)
		(layer "B.Cu")
		(net 37)
	)
	(segment
		(start 146.879527 95.7016)
		(end 146.811052 95.693884)
		(width 0.1016)
		(layer "B.Cu")
		(net 37)
	)
	(segment
		(start 154.1266 90.817086)
		(end 152.842086 92.1016)
		(width 0.1016)
		(layer "B.Cu")
		(net 37)
	)
	(segment
		(start 152.842086 92.1016)
		(end 151.042086 92.1016)
		(width 0.1016)
		(layer "B.Cu")
		(net 37)
	)
	(segment
		(start 154.1266 89.869391)
		(end 154.1266 90.817086)
		(width 0.1016)
		(layer "B.Cu")
		(net 37)
	)
	(segment
		(start 146.42094 95.151841)
		(end 146.394858 95.160968)
		(width 0.1016)
		(layer "B.Cu")
		(net 37)
	)
	(segment
		(start 146.15079 95.671125)
		(end 146.085747 95.693884)
		(width 0.1016)
		(layer "B.Cu")
		(net 37)
	)
	(segment
		(start 146.325 95.272148)
		(end 146.325 95.393872)
		(width 0.1016)
		(layer "B.Cu")
		(net 37)
	)
	(segment
		(start 146.257863 95.585737)
		(end 146.209137 95.634463)
		(width 0.1016)
		(layer "B.Cu")
		(net 37)
	)
	(segment
		(start 146.317284 95.462347)
		(end 146.294525 95.52739)
		(width 0.1016)
		(layer "B.Cu")
		(net 37)
	)
	(segment
		(start 146.33722 95.218606)
		(end 146.328093 95.244688)
		(width 0.1016)
		(layer "B.Cu")
		(net 37)
	)
	(segment
		(start 146.5718 95.272148)
		(end 146.568706 95.244688)
		(width 0.1016)
		(layer "B.Cu")
		(net 37)
	)
	(segment
		(start 146.602274 95.52739)
		(end 146.579515 95.462347)
		(width 0.1016)
		(layer "B.Cu")
		(net 37)
	)
	(segment
		(start 147.442086 95.7016)
		(end 146.879527 95.7016)
		(width 0.1016)
		(layer "B.Cu")
		(net 37)
	)
	(segment
		(start 146.209137 95.634463)
		(end 146.15079 95.671125)
		(width 0.1016)
		(layer "B.Cu")
		(net 37)
	)
	(segment
		(start 151.042086 92.1016)
		(end 147.442086 95.7016)
		(width 0.1016)
		(layer "B.Cu")
		(net 37)
	)
	(segment
		(start 146.371461 95.175669)
		(end 146.351921 95.195209)
		(width 0.1016)
		(layer "B.Cu")
		(net 37)
	)
	(segment
		(start 146.811052 95.693884)
		(end 146.746009 95.671125)
		(width 0.1016)
		(layer "B.Cu")
		(net 37)
	)
	(segment
		(start 145.042086 95.7016)
		(end 144.5266 96.217086)
		(width 0.1016)
		(layer "B.Cu")
		(net 37)
	)
	(segment
		(start 146.5718 95.393872)
		(end 146.5718 95.272148)
		(width 0.1016)
		(layer "B.Cu")
		(net 37)
	)
	(segment
		(start 146.687662 95.634463)
		(end 146.638936 95.585737)
		(width 0.1016)
		(layer "B.Cu")
		(net 37)
	)
	(segment
		(start 146.017272 95.7016)
		(end 145.042086 95.7016)
		(width 0.1016)
		(layer "B.Cu")
		(net 37)
	)
	(segment
		(start 146.328093 95.244688)
		(end 146.325 95.272148)
		(width 0.1016)
		(layer "B.Cu")
		(net 37)
	)
	(segment
		(start 154.2008 86.434949)
		(end 154.3008 86.334949)
		(width 0.1016)
		(layer "In2.Cu")
		(net 37)
	)
	(segment
		(start 154.2008 89.446791)
		(end 154.2008 86.434949)
		(width 0.1016)
		(layer "In2.Cu")
		(net 37)
	)
	(segment
		(start 154.2008 89.446791)
		(end 154.375 89.620991)
		(width 0.1016)
		(layer "In2.Cu")
		(net 37)
	)
	(segment
		(start 156.766718 95.251536)
		(end 156.71012 95.194938)
		(width 0.145)
		(layer "F.Cu")
		(net 38)
	)
	(segment
		(start 156.561657 95.456597)
		(end 156.587043 95.476842)
		(width 0.145)
		(layer "F.Cu")
		(net 38)
	)
	(segment
		(start 156.675787 95.140298)
		(end 156.668562 95.108642)
		(width 0.145)
		(layer "F.Cu")
		(net 38)
	)
	(segment
		(start 156.808275 95.370301)
		(end 156.808275 95.337831)
		(width 0.145)
		(layer "F.Cu")
		(net 38)
	)
	(segment
		(start 156.689875 95.169552)
		(end 156.675787 95.140298)
		(width 0.145)
		(layer "F.Cu")
		(net 38)
	)
	(segment
		(start 156.386295 95.358442)
		(end 156.418765 95.358442)
		(width 0.145)
		(layer "F.Cu")
		(net 38)
	)
	(segment
		(start 156.80105 95.401956)
		(end 156.808275 95.370301)
		(width 0.145)
		(layer "F.Cu")
		(net 38)
	)
	(segment
		(start 156.741332 95.476842)
		(end 156.766718 95.456597)
		(width 0.145)
		(layer "F.Cu")
		(net 38)
	)
	(segment
		(start 156.647953 95.498155)
		(end 156.680422 95.498155)
		(width 0.145)
		(layer "F.Cu")
		(net 38)
	)
	(segment
		(start 156.668562 95.076173)
		(end 156.675787 95.044517)
		(width 0.145)
		(layer "F.Cu")
		(net 38)
	)
	(segment
		(start 156.50506 95.4)
		(end 156.561657 95.456597)
		(width 0.145)
		(layer "F.Cu")
		(net 38)
	)
	(segment
		(start 156.479675 95.379755)
		(end 156.50506 95.4)
		(width 0.145)
		(layer "F.Cu")
		(net 38)
	)
	(segment
		(start 156.587043 95.476842)
		(end 156.616297 95.49093)
		(width 0.145)
		(layer "F.Cu")
		(net 38)
	)
	(segment
		(start 155.3 97)
		(end 155.3 96.4)
		(width 0.145)
		(layer "F.Cu")
		(net 38)
	)
	(segment
		(start 156.3 95.4)
		(end 156.325385 95.379755)
		(width 0.145)
		(layer "F.Cu")
		(net 38)
	)
	(segment
		(start 156.668562 95.108642)
		(end 156.668562 95.076173)
		(width 0.145)
		(layer "F.Cu")
		(net 38)
	)
	(segment
		(start 156.35464 95.365667)
		(end 156.386295 95.358442)
		(width 0.145)
		(layer "F.Cu")
		(net 38)
	)
	(segment
		(start 155.3 96.4)
		(end 156.3 95.4)
		(width 0.145)
		(layer "F.Cu")
		(net 38)
	)
	(segment
		(start 156.418765 95.358442)
		(end 156.45042 95.365667)
		(width 0.145)
		(layer "F.Cu")
		(net 38)
	)
	(segment
		(start 156.675787 95.044517)
		(end 156.689875 95.015263)
		(width 0.145)
		(layer "F.Cu")
		(net 38)
	)
	(segment
		(start 155.425 97.125)
		(end 155.3 97)
		(width 0.145)
		(layer "F.Cu")
		(net 38)
	)
	(segment
		(start 158.325 93.375)
		(end 158.325 84.06)
		(width 0.145)
		(layer "F.Cu")
		(net 38)
	)
	(segment
		(start 156.766718 95.456597)
		(end 156.786962 95.431211)
		(width 0.145)
		(layer "F.Cu")
		(net 38)
	)
	(segment
		(start 155.425 98.7)
		(end 155.425 97.125)
		(width 0.145)
		(layer "F.Cu")
		(net 38)
	)
	(segment
		(start 156.80105 95.306176)
		(end 156.786962 95.276921)
		(width 0.145)
		(layer "F.Cu")
		(net 38)
	)
	(segment
		(start 156.680422 95.498155)
		(end 156.712078 95.49093)
		(width 0.145)
		(layer "F.Cu")
		(net 38)
	)
	(segment
		(start 156.616297 95.49093)
		(end 156.647953 95.498155)
		(width 0.145)
		(layer "F.Cu")
		(net 38)
	)
	(segment
		(start 156.325385 95.379755)
		(end 156.35464 95.365667)
		(width 0.145)
		(layer "F.Cu")
		(net 38)
	)
	(segment
		(start 156.712078 95.49093)
		(end 156.741332 95.476842)
		(width 0.145)
		(layer "F.Cu")
		(net 38)
	)
	(segment
		(start 156.786962 95.276921)
		(end 156.766718 95.251536)
		(width 0.145)
		(layer "F.Cu")
		(net 38)
	)
	(segment
		(start 156.808275 95.337831)
		(end 156.80105 95.306176)
		(width 0.145)
		(layer "F.Cu")
		(net 38)
	)
	(segment
		(start 156.689875 95.015263)
		(end 156.710121 94.989878)
		(width 0.145)
		(layer "F.Cu")
		(net 38)
	)
	(segment
		(start 156.71012 95.194938)
		(end 156.689875 95.169552)
		(width 0.145)
		(layer "F.Cu")
		(net 38)
	)
	(segment
		(start 156.786962 95.431211)
		(end 156.80105 95.401956)
		(width 0.145)
		(layer "F.Cu")
		(net 38)
	)
	(segment
		(start 156.45042 95.365667)
		(end 156.479675 95.379755)
		(width 0.145)
		(layer "F.Cu")
		(net 38)
	)
	(segment
		(start 156.710121 94.989878)
		(end 158.325 93.375)
		(width 0.145)
		(layer "F.Cu")
		(net 38)
	)
	(segment
		(start 153.7492 86.7508)
		(end 153.625 86.875)
		(width 0.1016)
		(layer "F.Cu")
		(net 39)
	)
	(segment
		(start 153.7492 86.334949)
		(end 153.7492 86.7508)
		(width 0.1016)
		(layer "F.Cu")
		(net 39)
	)
	(via
		(at 153.7492 86.334949)
		(size 0.45)
		(drill 0.15)
		(layers "F.Cu" "B.Cu")
		(net 39)
	)
	(via
		(at 153.675 89.620991)
		(size 0.45)
		(drill 0.15)
		(layers "F.Cu" "B.Cu")
		(net 39)
	)
	(segment
		(start 146.775 95.375)
		(end 146.775 95.253275)
		(width 0.1016)
		(layer "B.Cu")
		(net 39)
	)
	(segment
		(start 146.78722 95.428541)
		(end 146.778093 95.402459)
		(width 0.1016)
		(layer "B.Cu")
		(net 39)
	)
	(segment
		(start 146.535747 94.953263)
		(end 146.467272 94.945548)
		(width 0.1016)
		(layer "B.Cu")
		(net 39)
	)
	(segment
		(start 146.075338 95.471478)
		(end 146.051941 95.486179)
		(width 0.1016)
		(layer "B.Cu")
		(net 39)
	)
	(segment
		(start 147.357914 95.4984)
		(end 146.8984 95.4984)
		(width 0.1016)
		(layer "B.Cu")
		(net 39)
	)
	(segment
		(start 145.9984 95.4984)
		(end 144.957914 95.4984)
		(width 0.1016)
		(layer "B.Cu")
		(net 39)
	)
	(segment
		(start 153.9234 90.732914)
		(end 152.757914 91.8984)
		(width 0.1016)
		(layer "B.Cu")
		(net 39)
	)
	(segment
		(start 146.467272 94.945548)
		(end 146.429527 94.945548)
		(width 0.1016)
		(layer "B.Cu")
		(net 39)
	)
	(segment
		(start 153.9234 89.869391)
		(end 153.9234 90.732914)
		(width 0.1016)
		(layer "B.Cu")
		(net 39)
	)
	(segment
		(start 146.87094 95.495306)
		(end 146.844858 95.486179)
		(width 0.1016)
		(layer "B.Cu")
		(net 39)
	)
	(segment
		(start 146.361052 94.953263)
		(end 146.296009 94.976022)
		(width 0.1016)
		(layer "B.Cu")
		(net 39)
	)
	(segment
		(start 146.237662 95.012684)
		(end 146.188936 95.06141)
		(width 0.1016)
		(layer "B.Cu")
		(net 39)
	)
	(segment
		(start 146.051941 95.486179)
		(end 146.025859 95.495306)
		(width 0.1016)
		(layer "B.Cu")
		(net 39)
	)
	(segment
		(start 146.429527 94.945548)
		(end 146.361052 94.953263)
		(width 0.1016)
		(layer "B.Cu")
		(net 39)
	)
	(segment
		(start 146.707863 95.06141)
		(end 146.659137 95.012684)
		(width 0.1016)
		(layer "B.Cu")
		(net 39)
	)
	(segment
		(start 146.1218 95.375)
		(end 146.118706 95.402459)
		(width 0.1016)
		(layer "B.Cu")
		(net 39)
	)
	(segment
		(start 146.744525 95.119757)
		(end 146.707863 95.06141)
		(width 0.1016)
		(layer "B.Cu")
		(net 39)
	)
	(segment
		(start 146.767284 95.1848)
		(end 146.744525 95.119757)
		(width 0.1016)
		(layer "B.Cu")
		(net 39)
	)
	(segment
		(start 146.109579 95.428541)
		(end 146.094878 95.451938)
		(width 0.1016)
		(layer "B.Cu")
		(net 39)
	)
	(segment
		(start 146.1218 95.253275)
		(end 146.1218 95.375)
		(width 0.1016)
		(layer "B.Cu")
		(net 39)
	)
	(segment
		(start 146.8984 95.4984)
		(end 146.87094 95.495306)
		(width 0.1016)
		(layer "B.Cu")
		(net 39)
	)
	(segment
		(start 153.675 89.620991)
		(end 153.9234 89.869391)
		(width 0.1016)
		(layer "B.Cu")
		(net 39)
	)
	(segment
		(start 146.821461 95.471478)
		(end 146.801921 95.451938)
		(width 0.1016)
		(layer "B.Cu")
		(net 39)
	)
	(segment
		(start 146.659137 95.012684)
		(end 146.60079 94.976022)
		(width 0.1016)
		(layer "B.Cu")
		(net 39)
	)
	(segment
		(start 146.129515 95.1848)
		(end 146.1218 95.253275)
		(width 0.1016)
		(layer "B.Cu")
		(net 39)
	)
	(segment
		(start 146.778093 95.402459)
		(end 146.775 95.375)
		(width 0.1016)
		(layer "B.Cu")
		(net 39)
	)
	(segment
		(start 146.296009 94.976022)
		(end 146.237662 95.012684)
		(width 0.1016)
		(layer "B.Cu")
		(net 39)
	)
	(segment
		(start 146.60079 94.976022)
		(end 146.535747 94.953263)
		(width 0.1016)
		(layer "B.Cu")
		(net 39)
	)
	(segment
		(start 146.094878 95.451938)
		(end 146.075338 95.471478)
		(width 0.1016)
		(layer "B.Cu")
		(net 39)
	)
	(segment
		(start 144.3234 96.676599)
		(end 144.175 96.824999)
		(width 0.1016)
		(layer "B.Cu")
		(net 39)
	)
	(segment
		(start 146.118706 95.402459)
		(end 146.109579 95.428541)
		(width 0.1016)
		(layer "B.Cu")
		(net 39)
	)
	(segment
		(start 152.757914 91.8984)
		(end 150.957914 91.8984)
		(width 0.1016)
		(layer "B.Cu")
		(net 39)
	)
	(segment
		(start 146.775 95.253275)
		(end 146.767284 95.1848)
		(width 0.1016)
		(layer "B.Cu")
		(net 39)
	)
	(segment
		(start 146.152274 95.119757)
		(end 146.129515 95.1848)
		(width 0.1016)
		(layer "B.Cu")
		(net 39)
	)
	(segment
		(start 146.844858 95.486179)
		(end 146.821461 95.471478)
		(width 0.1016)
		(layer "B.Cu")
		(net 39)
	)
	(segment
		(start 144.175 96.824999)
		(end 144.175 98.7)
		(width 0.1016)
		(layer "B.Cu")
		(net 39)
	)
	(segment
		(start 144.3234 96.132914)
		(end 144.3234 96.676599)
		(width 0.1016)
		(layer "B.Cu")
		(net 39)
	)
	(segment
		(start 144.957914 95.4984)
		(end 144.3234 96.132914)
		(width 0.1016)
		(layer "B.Cu")
		(net 39)
	)
	(segment
		(start 146.025859 95.495306)
		(end 145.9984 95.4984)
		(width 0.1016)
		(layer "B.Cu")
		(net 39)
	)
	(segment
		(start 146.188936 95.06141)
		(end 146.152274 95.119757)
		(width 0.1016)
		(layer "B.Cu")
		(net 39)
	)
	(segment
		(start 146.801921 95.451938)
		(end 146.78722 95.428541)
		(width 0.1016)
		(layer "B.Cu")
		(net 39)
	)
	(segment
		(start 150.957914 91.8984)
		(end 147.357914 95.4984)
		(width 0.1016)
		(layer "B.Cu")
		(net 39)
	)
	(segment
		(start 153.8492 89.446791)
		(end 153.8492 86.434949)
		(width 0.1016)
		(layer "In2.Cu")
		(net 39)
	)
	(segment
		(start 153.8492 89.446791)
		(end 153.675 89.620991)
		(width 0.1016)
		(layer "In2.Cu")
		(net 39)
	)
	(segment
		(start 153.8492 86.434949)
		(end 153.7492 86.334949)
		(width 0.1016)
		(layer "In2.Cu")
		(net 39)
	)
	(segment
		(start 145.574101 96.574101)
		(end 143.975 94.975)
		(width 0.145)
		(layer "F.Cu")
		(net 40)
	)
	(segment
		(start 148.825 82.85)
		(end 148.425 83.25)
		(width 0.145)
		(layer "F.Cu")
		(net 40)
	)
	(segment
		(start 145.425 97.09067)
		(end 145.574101 96.941569)
		(width 0.145)
		(layer "F.Cu")
		(net 40)
	)
	(segment
		(start 143.975 94.975)
		(end 143.975 92.7)
		(width 0.145)
		(layer "F.Cu")
		(net 40)
	)
	(segment
		(start 145.574101 96.941569)
		(end 145.574101 96.574101)
		(width 0.145)
		(layer "F.Cu")
		(net 40)
	)
	(segment
		(start 145.425 98.7)
		(end 145.425 97.09067)
		(width 0.145)
		(layer "F.Cu")
		(net 40)
	)
	(via
		(at 143.975 92.7)
		(size 0.45)
		(drill 0.15)
		(layers "F.Cu" "B.Cu")
		(net 40)
	)
	(via
		(at 148.425 83.25)
		(size 0.45)
		(drill 0.15)
		(layers "F.Cu" "B.Cu")
		(net 40)
	)
	(segment
		(start 143.838175 90.680135)
		(end 143.836437 90.664719)
		(width 0.1016)
		(layer "In2.Cu")
		(net 40)
	)
	(segment
		(start 143.836437 91.071119)
		(end 143.836437 91.006481)
		(width 0.1016)
		(layer "In2.Cu")
		(net 40)
	)
	(segment
		(start 143.843298 90.694778)
		(end 143.838175 90.680135)
		(width 0.1016)
		(layer "In2.Cu")
		(net 40)
	)
	(segment
		(start 143.851552 90.963285)
		(end 143.862523 90.952314)
		(width 0.1016)
		(layer "In2.Cu")
		(net 40)
	)
	(segment
		(start 143.976737 91.809583)
		(end 143.98186 91.79494)
		(width 0.1016)
		(layer "In2.Cu")
		(net 40)
	)
	(segment
		(start 144.098448 91.166485)
		(end 144.087477 91.155514)
		(width 0.1016)
		(layer "In2.Cu")
		(net 40)
	)
	(segment
		(start 143.975 91.552519)
		(end 143.975 91.5468)
		(width 0.1016)
		(layer "In2.Cu")
		(net 40)
	)
	(segment
		(start 143.959886 90.504714)
		(end 143.96814 90.491578)
		(width 0.1016)
		(layer "In2.Cu")
		(net 40)
	)
	(segment
		(start 143.905718 91.1404)
		(end 143.890302 91.138662)
		(width 0.1016)
		(layer "In2.Cu")
		(net 40)
	)
	(segment
		(start 144.028864 91.757456)
		(end 144.059698 91.753981)
		(width 0.1016)
		(layer "In2.Cu")
		(net 40)
	)
	(segment
		(start 144.106702 90.773221)
		(end 144.098448 90.760085)
		(width 0.1016)
		(layer "In2.Cu")
		(net 40)
	)
	(segment
		(start 144.059698 90.935462)
		(end 144.074341 90.930339)
		(width 0.1016)
		(layer "In2.Cu")
		(net 40)
	)
	(segment
		(start 143.836437 90.664719)
		(end 143.836437 90.600081)
		(width 0.1016)
		(layer "In2.Cu")
		(net 40)
	)
	(segment
		(start 143.862523 90.952314)
		(end 143.875659 90.94406)
		(width 0.1016)
		(layer "In2.Cu")
		(net 40)
	)
	(segment
		(start 143.890302 91.345337)
		(end 143.905718 91.3436)
		(width 0.1016)
		(layer "In2.Cu")
		(net 40)
	)
	(segment
		(start 144.106702 91.716497)
		(end 144.111825 91.701854)
		(width 0.1016)
		(layer "In2.Cu")
		(net 40)
	)
	(segment
		(start 143.836437 91.006481)
		(end 143.838175 90.991064)
		(width 0.1016)
		(layer "In2.Cu")
		(net 40)
	)
	(segment
		(start 144.106702 91.59174)
		(end 144.098448 91.578604)
		(width 0.1016)
		(layer "In2.Cu")
		(net 40)
	)
	(segment
		(start 143.862523 90.718885)
		(end 143.851552 90.707914)
		(width 0.1016)
		(layer "In2.Cu")
		(net 40)
	)
	(segment
		(start 144.059698 91.341862)
		(end 144.074341 91.336739)
		(width 0.1016)
		(layer "In2.Cu")
		(net 40)
	)
	(segment
		(start 144.044282 91.3436)
		(end 144.059698 91.341862)
		(width 0.1016)
		(layer "In2.Cu")
		(net 40)
	)
	(segment
		(start 143.921136 90.529062)
		(end 143.935779 90.523939)
		(width 0.1016)
		(layer "In2.Cu")
		(net 40)
	)
	(segment
		(start 143.838175 90.991064)
		(end 143.843298 90.976421)
		(width 0.1016)
		(layer "In2.Cu")
		(net 40)
	)
	(segment
		(start 143.836437 90.600081)
		(end 143.838175 90.584664)
		(width 0.1016)
		(layer "In2.Cu")
		(net 40)
	)
	(segment
		(start 143.96814 90.491578)
		(end 143.973263 90.476935)
		(width 0.1016)
		(layer "In2.Cu")
		(net 40)
	)
	(segment
		(start 144.087477 90.922085)
		(end 144.098448 90.911114)
		(width 0.1016)
		(layer "In2.Cu")
		(net 40)
	)
	(segment
		(start 143.862523 91.531685)
		(end 143.851552 91.520714)
		(width 0.1016)
		(layer "In2.Cu")
		(net 40)
	)
	(segment
		(start 144.074341 90.74086)
		(end 144.059698 90.735737)
		(width 0.1016)
		(layer "In2.Cu")
		(net 40)
	)
	(segment
		(start 143.890302 91.138662)
		(end 143.875659 91.133539)
		(width 0.1016)
		(layer "In2.Cu")
		(net 40)
	)
	(segment
		(start 143.836437 91.477519)
		(end 143.836437 91.412881)
		(width 0.1016)
		(layer "In2.Cu")
		(net 40)
	)
	(segment
		(start 144.106702 91.179621)
		(end 144.098448 91.166485)
		(width 0.1016)
		(layer "In2.Cu")
		(net 40)
	)
	(segment
		(start 143.838175 91.492935)
		(end 143.836437 91.477519)
		(width 0.1016)
		(layer "In2.Cu")
		(net 40)
	)
	(segment
		(start 143.905718 91.3436)
		(end 144.044282 91.3436)
		(width 0.1016)
		(layer "In2.Cu")
		(net 40)
	)
	(segment
		(start 143.875659 90.94406)
		(end 143.890302 90.938937)
		(width 0.1016)
		(layer "In2.Cu")
		(net 40)
	)
	(segment
		(start 144.087477 90.749114)
		(end 144.074341 90.74086)
		(width 0.1016)
		(layer "In2.Cu")
		(net 40)
	)
	(segment
		(start 144.106702 91.304378)
		(end 144.111825 91.289735)
		(width 0.1016)
		(layer "In2.Cu")
		(net 40)
	)
	(segment
		(start 144.111825 90.787864)
		(end 144.106702 90.773221)
		(width 0.1016)
		(layer "In2.Cu")
		(net 40)
	)
	(segment
		(start 143.975 92.7)
		(end 143.975 91.825)
		(width 0.1016)
		(layer "In2.Cu")
		(net 40)
	)
	(segment
		(start 144.059698 91.753981)
		(end 144.074341 91.748858)
		(width 0.1016)
		(layer "In2.Cu")
		(net 40)
	)
	(segment
		(start 143.973263 90.476935)
		(end 143.975 90.461519)
		(width 0.1016)
		(layer "In2.Cu")
		(net 40)
	)
	(segment
		(start 143.875659 90.727139)
		(end 143.862523 90.718885)
		(width 0.1016)
		(layer "In2.Cu")
		(net 40)
	)
	(segment
		(start 144.111825 91.289735)
		(end 144.113563 91.274319)
		(width 0.1016)
		(layer "In2.Cu")
		(net 40)
	)
	(segment
		(start 143.975 90.461519)
		(end 143.975 85.55)
		(width 0.1016)
		(layer "In2.Cu")
		(net 40)
	)
	(segment
		(start 143.875659 91.35046)
		(end 143.890302 91.345337)
		(width 0.1016)
		(layer "In2.Cu")
		(net 40)
	)
	(segment
		(start 143.838175 90.584664)
		(end 143.843298 90.570021)
		(width 0.1016)
		(layer "In2.Cu")
		(net 40)
	)
	(segment
		(start 143.843298 91.382821)
		(end 143.851552 91.369685)
		(width 0.1016)
		(layer "In2.Cu")
		(net 40)
	)
	(segment
		(start 143.862523 91.358714)
		(end 143.875659 91.35046)
		(width 0.1016)
		(layer "In2.Cu")
		(net 40)
	)
	(segment
		(start 144.074341 91.748858)
		(end 144.087477 91.740604)
		(width 0.1016)
		(layer "In2.Cu")
		(net 40)
	)
	(segment
		(start 144.38463 85.14037)
		(end 148.175 85.14037)
		(width 0.1016)
		(layer "In2.Cu")
		(net 40)
	)
	(segment
		(start 143.990114 91.781804)
		(end 144.001085 91.770833)
		(width 0.1016)
		(layer "In2.Cu")
		(net 40)
	)
	(segment
		(start 143.890302 90.732262)
		(end 143.875659 90.727139)
		(width 0.1016)
		(layer "In2.Cu")
		(net 40)
	)
	(segment
		(start 143.875659 91.133539)
		(end 143.862523 91.125285)
		(width 0.1016)
		(layer "In2.Cu")
		(net 40)
	)
	(segment
		(start 144.059698 91.554256)
		(end 144.044281 91.552519)
		(width 0.1016)
		(layer "In2.Cu")
		(net 40)
	)
	(segment
		(start 144.014221 91.762579)
		(end 144.028864 91.757456)
		(width 0.1016)
		(layer "In2.Cu")
		(net 40)
	)
	(segment
		(start 143.975 85.55)
		(end 144.38463 85.14037)
		(width 0.1016)
		(layer "In2.Cu")
		(net 40)
	)
	(segment
		(start 143.851552 90.556885)
		(end 143.862523 90.545914)
		(width 0.1016)
		(layer "In2.Cu")
		(net 40)
	)
	(segment
		(start 144.111825 91.606383)
		(end 144.106702 91.59174)
		(width 0.1016)
		(layer "In2.Cu")
		(net 40)
	)
	(segment
		(start 143.975 91.5468)
		(end 143.905718 91.5468)
		(width 0.1016)
		(layer "In2.Cu")
		(net 40)
	)
	(segment
		(start 143.851552 91.369685)
		(end 143.862523 91.358714)
		(width 0.1016)
		(layer "In2.Cu")
		(net 40)
	)
	(segment
		(start 143.890302 91.545062)
		(end 143.875659 91.539939)
		(width 0.1016)
		(layer "In2.Cu")
		(net 40)
	)
	(segment
		(start 143.862523 90.545914)
		(end 143.875659 90.53766)
		(width 0.1016)
		(layer "In2.Cu")
		(net 40)
	)
	(segment
		(start 143.905718 90.9372)
		(end 144.044282 90.9372)
		(width 0.1016)
		(layer "In2.Cu")
		(net 40)
	)
	(segment
		(start 143.905718 91.5468)
		(end 143.890302 91.545062)
		(width 0.1016)
		(layer "In2.Cu")
		(net 40)
	)
	(segment
		(start 144.044281 91.552519)
		(end 143.975 91.552519)
		(width 0.1016)
		(layer "In2.Cu")
		(net 40)
	)
	(segment
		(start 144.106702 90.897978)
		(end 144.111825 90.883335)
		(width 0.1016)
		(layer "In2.Cu")
		(net 40)
	)
	(segment
		(start 144.044282 90.9372)
		(end 144.059698 90.935462)
		(width 0.1016)
		(layer "In2.Cu")
		(net 40)
	)
	(segment
		(start 143.851552 91.114314)
		(end 143.843298 91.101178)
		(width 0.1016)
		(layer "In2.Cu")
		(net 40)
	)
	(segment
		(start 144.044282 91.1404)
		(end 143.905718 91.1404)
		(width 0.1016)
		(layer "In2.Cu")
		(net 40)
	)
	(segment
		(start 144.074341 91.559379)
		(end 144.059698 91.554256)
		(width 0.1016)
		(layer "In2.Cu")
		(net 40)
	)
	(segment
		(start 143.890302 90.938937)
		(end 143.905718 90.9372)
		(width 0.1016)
		(layer "In2.Cu")
		(net 40)
	)
	(segment
		(start 143.843298 90.570021)
		(end 143.851552 90.556885)
		(width 0.1016)
		(layer "In2.Cu")
		(net 40)
	)
	(segment
		(start 143.838175 91.086535)
		(end 143.836437 91.071119)
		(width 0.1016)
		(layer "In2.Cu")
		(net 40)
	)
	(segment
		(start 143.843298 90.976421)
		(end 143.851552 90.963285)
		(width 0.1016)
		(layer "In2.Cu")
		(net 40)
	)
	(segment
		(start 148.175 85.14037)
		(end 148.425 84.89037)
		(width 0.1016)
		(layer "In2.Cu")
		(net 40)
	)
	(segment
		(start 144.074341 90.930339)
		(end 144.087477 90.922085)
		(width 0.1016)
		(layer "In2.Cu")
		(net 40)
	)
	(segment
		(start 143.862523 91.125285)
		(end 143.851552 91.114314)
		(width 0.1016)
		(layer "In2.Cu")
		(net 40)
	)
	(segment
		(start 144.098448 91.578604)
		(end 144.087477 91.567633)
		(width 0.1016)
		(layer "In2.Cu")
		(net 40)
	)
	(segment
		(start 148.425 84.89037)
		(end 148.425 83.25)
		(width 0.1016)
		(layer "In2.Cu")
		(net 40)
	)
	(segment
		(start 144.113563 91.6218)
		(end 144.111825 91.606383)
		(width 0.1016)
		(layer "In2.Cu")
		(net 40)
	)
	(segment
		(start 144.111825 91.701854)
		(end 144.113563 91.686438)
		(width 0.1016)
		(layer "In2.Cu")
		(net 40)
	)
	(segment
		(start 144.113563 91.686438)
		(end 144.113563 91.6218)
		(width 0.1016)
		(layer "In2.Cu")
		(net 40)
	)
	(segment
		(start 144.074341 91.14726)
		(end 144.059698 91.142137)
		(width 0.1016)
		(layer "In2.Cu")
		(net 40)
	)
	(segment
		(start 143.843298 91.507578)
		(end 143.838175 91.492935)
		(width 0.1016)
		(layer "In2.Cu")
		(net 40)
	)
	(segment
		(start 144.001085 91.770833)
		(end 144.014221 91.762579)
		(width 0.1016)
		(layer "In2.Cu")
		(net 40)
	)
	(segment
		(start 144.074341 91.336739)
		(end 144.087477 91.328485)
		(width 0.1016)
		(layer "In2.Cu")
		(net 40)
	)
	(segment
		(start 144.113563 90.867919)
		(end 144.113563 90.803281)
		(width 0.1016)
		(layer "In2.Cu")
		(net 40)
	)
	(segment
		(start 143.843298 91.101178)
		(end 143.838175 91.086535)
		(width 0.1016)
		(layer "In2.Cu")
		(net 40)
	)
	(segment
		(start 143.851552 91.520714)
		(end 143.843298 91.507578)
		(width 0.1016)
		(layer "In2.Cu")
		(net 40)
	)
	(segment
		(start 143.890302 90.532537)
		(end 143.921136 90.529062)
		(width 0.1016)
		(layer "In2.Cu")
		(net 40)
	)
	(segment
		(start 143.875659 90.53766)
		(end 143.890302 90.532537)
		(width 0.1016)
		(layer "In2.Cu")
		(net 40)
	)
	(segment
		(start 144.111825 90.883335)
		(end 144.113563 90.867919)
		(width 0.1016)
		(layer "In2.Cu")
		(net 40)
	)
	(segment
		(start 144.087477 91.740604)
		(end 144.098448 91.729633)
		(width 0.1016)
		(layer "In2.Cu")
		(net 40)
	)
	(segment
		(start 143.905718 90.734)
		(end 143.890302 90.732262)
		(width 0.1016)
		(layer "In2.Cu")
		(net 40)
	)
	(segment
		(start 143.836437 91.412881)
		(end 143.838175 91.397464)
		(width 0.1016)
		(layer "In2.Cu")
		(net 40)
	)
	(segment
		(start 143.975 91.825)
		(end 143.976737 91.809583)
		(width 0.1016)
		(layer "In2.Cu")
		(net 40)
	)
	(segment
		(start 144.044282 90.734)
		(end 143.905718 90.734)
		(width 0.1016)
		(layer "In2.Cu")
		(net 40)
	)
	(segment
		(start 144.113563 91.209681)
		(end 144.111825 91.194264)
		(width 0.1016)
		(layer "In2.Cu")
		(net 40)
	)
	(segment
		(start 143.935779 90.523939)
		(end 143.948915 90.515685)
		(width 0.1016)
		(layer "In2.Cu")
		(net 40)
	)
	(segment
		(start 144.098448 91.729633)
		(end 144.106702 91.716497)
		(width 0.1016)
		(layer "In2.Cu")
		(net 40)
	)
	(segment
		(start 144.113563 91.274319)
		(end 144.113563 91.209681)
		(width 0.1016)
		(layer "In2.Cu")
		(net 40)
	)
	(segment
		(start 144.098448 90.911114)
		(end 144.106702 90.897978)
		(width 0.1016)
		(layer "In2.Cu")
		(net 40)
	)
	(segment
		(start 144.087477 91.155514)
		(end 144.074341 91.14726)
		(width 0.1016)
		(layer "In2.Cu")
		(net 40)
	)
	(segment
		(start 144.113563 90.803281)
		(end 144.111825 90.787864)
		(width 0.1016)
		(layer "In2.Cu")
		(net 40)
	)
	(segment
		(start 143.851552 90.707914)
		(end 143.843298 90.694778)
		(width 0.1016)
		(layer "In2.Cu")
		(net 40)
	)
	(segment
		(start 143.838175 91.397464)
		(end 143.843298 91.382821)
		(width 0.1016)
		(layer "In2.Cu")
		(net 40)
	)
	(segment
		(start 144.059698 91.142137)
		(end 144.044282 91.1404)
		(width 0.1016)
		(layer "In2.Cu")
		(net 40)
	)
	(segment
		(start 144.098448 91.317514)
		(end 144.106702 91.304378)
		(width 0.1016)
		(layer "In2.Cu")
		(net 40)
	)
	(segment
		(start 144.098448 90.760085)
		(end 144.087477 90.749114)
		(width 0.1016)
		(layer "In2.Cu")
		(net 40)
	)
	(segment
		(start 143.98186 91.79494)
		(end 143.990114 91.781804)
		(width 0.1016)
		(layer "In2.Cu")
		(net 40)
	)
	(segment
		(start 144.059698 90.735737)
		(end 144.044282 90.734)
		(width 0.1016)
		(layer "In2.Cu")
		(net 40)
	)
	(segment
		(start 144.087477 91.328485)
		(end 144.098448 91.317514)
		(width 0.1016)
		(layer "In2.Cu")
		(net 40)
	)
	(segment
		(start 143.875659 91.539939)
		(end 143.862523 91.531685)
		(width 0.1016)
		(layer "In2.Cu")
		(net 40)
	)
	(segment
		(start 144.111825 91.194264)
		(end 144.106702 91.179621)
		(width 0.1016)
		(layer "In2.Cu")
		(net 40)
	)
	(segment
		(start 144.087477 91.567633)
		(end 144.074341 91.559379)
		(width 0.1016)
		(layer "In2.Cu")
		(net 40)
	)
	(segment
		(start 143.948915 90.515685)
		(end 143.959886 90.504714)
		(width 0.1016)
		(layer "In2.Cu")
		(net 40)
	)
	(segment
		(start 148.825 87.65)
		(end 148.425 87.25)
		(width 0.145)
		(layer "F.Cu")
		(net 41)
	)
	(segment
		(start 150.425 95.825)
		(end 148.8 94.2)
		(width 0.145)
		(layer "F.Cu")
		(net 41)
	)
	(segment
		(start 148.8 94.2)
		(end 147.4 94.2)
		(width 0.145)
		(layer "F.Cu")
		(net 41)
	)
	(segment
		(start 146.775 92.3)
		(end 146.775 93.575)
		(width 0.145)
		(layer "F.Cu")
		(net 41)
	)
	(segment
		(start 150.425 98.7)
		(end 150.425 95.825)
		(width 0.145)
		(layer "F.Cu")
		(net 41)
	)
	(segment
		(start 147.4 94.2)
		(end 146.775 93.575)
		(width 0.145)
		(layer "F.Cu")
		(net 41)
	)
	(via
		(at 148.425 87.25)
		(size 0.45)
		(drill 0.15)
		(layers "F.Cu" "B.Cu")
		(net 41)
	)
	(via
		(at 146.775 92.3)
		(size 0.45)
		(drill 0.15)
		(layers "F.Cu" "B.Cu")
		(net 41)
	)
	(segment
		(start 147.380931 90.100414)
		(end 147.401428 90.110286)
		(width 0.1016)
		(layer "In2.Cu")
		(net 41)
	)
	(segment
		(start 148.137633 89.262368)
		(end 148.155421 89.248184)
		(width 0.1016)
		(layer "In2.Cu")
		(net 41)
	)
	(segment
		(start 148.516689 87.88588)
		(end 148.5 87.884)
		(width 0.1016)
		(layer "In2.Cu")
		(net 41)
	)
	(segment
		(start 147.556113 90.548732)
		(end 147.275533 90.268152)
		(width 0.1016)
		(layer "In2.Cu")
		(net 41)
	)
	(segment
		(start 148.333311 88.08908)
		(end 148.35 88.0872)
		(width 0.1016)
		(layer "In2.Cu")
		(net 41)
	)
	(segment
		(start 148.276881 88.55191)
		(end 148.282428 88.536058)
		(width 0.1016)
		(layer "In2.Cu")
		(net 41)
	)
	(segment
		(start 148.155421 89.248184)
		(end 148.175919 89.238312)
		(width 0.1016)
		(layer "In2.Cu")
		(net 41)
	)
	(segment
		(start 147.867536 90.299652)
		(end 147.857666 90.279153)
		(width 0.1016)
		(layer "In2.Cu")
		(net 41)
	)
	(segment
		(start 148.447333 89.747099)
		(end 148.44227 89.724918)
		(width 0.1016)
		(layer "In2.Cu")
		(net 41)
	)
	(segment
		(start 148.593279 89.31831)
		(end 148.588216 89.29613)
		(width 0.1016)
		(layer "In2.Cu")
		(net 41)
	)
	(segment
		(start 148.275 87.809)
		(end 148.275 87.7558)
		(width 0.1016)
		(layer "In2.Cu")
		(net 41)
	)
	(segment
		(start 148.108515 89.345584)
		(end 148.108514 89.322834)
		(width 0.1016)
		(layer "In2.Cu")
		(net 41)
	)
	(segment
		(start 147.760263 90.43417)
		(end 147.783013 90.434171)
		(width 0.1016)
		(layer "In2.Cu")
		(net 41)
	)
	(segment
		(start 148.532541 88.297827)
		(end 148.516689 88.29228)
		(width 0.1016)
		(layer "In2.Cu")
		(net 41)
	)
	(segment
		(start 148.558637 87.505838)
		(end 148.546761 87.493962)
		(width 0.1016)
		(layer "In2.Cu")
		(net 41)
	)
	(segment
		(start 147.538843 89.875387)
		(end 147.548715 89.854888)
		(width 0.1016)
		(layer "In2.Cu")
		(net 41)
	)
	(segment
		(start 147.450715 90.716474)
		(end 147.472896 90.721537)
		(width 0.1016)
		(layer "In2.Cu")
		(net 41)
	)
	(segment
		(start 148.546372 89.415714)
		(end 148.56416 89.401527)
		(width 0.1016)
		(layer "In2.Cu")
		(net 41)
	)
	(segment
		(start 147.251477 90.229866)
		(end 147.246414 90.207685)
		(width 0.1016)
		(layer "In2.Cu")
		(net 41)
	)
	(segment
		(start 148.154904 90.079397)
		(end 148.159967 90.057216)
		(width 0.1016)
		(layer "In2.Cu")
		(net 41)
	)
	(segment
		(start 148.333311 87.68268)
		(end 148.35 87.6808)
		(width 0.1016)
		(layer "In2.Cu")
		(net 41)
	)
	(segment
		(start 147.987162 90.117684)
		(end 148.00495 90.13187)
		(width 0.1016)
		(layer "In2.Cu")
		(net 41)
	)
	(segment
		(start 148.558637 88.465361)
		(end 148.567572 88.451141)
		(width 0.1016)
		(layer "In2.Cu")
		(net 41)
	)
	(segment
		(start 148.441362 88.928238)
		(end 148.453238 88.916362)
		(width 0.1016)
		(layer "In2.Cu")
		(net 41)
	)
	(segment
		(start 148.275 88.6218)
		(end 148.275 88.5686)
		(width 0.1016)
		(layer "In2.Cu")
		(net 41)
	)
	(segment
		(start 148.425 87.4026)
		(end 148.425 87.25)
		(width 0.1016)
		(layer "In2.Cu")
		(net 41)
	)
	(segment
		(start 148.546761 87.493962)
		(end 148.532541 87.485027)
		(width 0.1016)
		(layer "In2.Cu")
		(net 41)
	)
	(segment
		(start 147.335998 90.095352)
		(end 147.35875 90.095351)
		(width 0.1016)
		(layer "In2.Cu")
		(net 41)
	)
	(segment
		(start 148.525875 89.425584)
		(end 148.546372 89.415714)
		(width 0.1016)
		(layer "In2.Cu")
		(net 41)
	)
	(segment
		(start 148.11306 90.131869)
		(end 148.130846 90.117684)
		(width 0.1016)
		(layer "In2.Cu")
		(net 41)
	)
	(segment
		(start 148.317459 88.094627)
		(end 148.333311 88.08908)
		(width 0.1016)
		(layer "In2.Cu")
		(net 41)
	)
	(segment
		(start 148.567572 88.044741)
		(end 148.573119 88.028889)
		(width 0.1016)
		(layer "In2.Cu")
		(net 41)
	)
	(segment
		(start 148.44227 89.724918)
		(end 148.4324 89.704419)
		(width 0.1016)
		(layer "In2.Cu")
		(net 41)
	)
	(segment
		(start 147.29332 90.110285)
		(end 147.313817 90.100415)
		(width 0.1016)
		(layer "In2.Cu")
		(net 41)
	)
	(segment
		(start 148.282428 88.536058)
		(end 148.291363 88.521838)
		(width 0.1016)
		(layer "In2.Cu")
		(net 41)
	)
	(segment
		(start 148.575 87.5526)
		(end 148.573119 87.53591)
		(width 0.1016)
		(layer "In2.Cu")
		(net 41)
	)
	(segment
		(start 147.836081 89.675631)
		(end 147.826211 89.655132)
		(width 0.1016)
		(layer "In2.Cu")
		(net 41)
	)
	(segment
		(start 147.570298 90.67463)
		(end 147.58017 90.654131)
		(width 0.1016)
		(layer "In2.Cu")
		(net 41)
	)
	(segment
		(start 148.546761 88.306762)
		(end 148.532541 88.297827)
		(width 0.1016)
		(layer "In2.Cu")
		(net 41)
	)
	(segment
		(start 148.516689 88.085319)
		(end 148.532541 88.079772)
		(width 0.1016)
		(layer "In2.Cu")
		(net 41)
	)
	(segment
		(start 148.400944 89.013286)
		(end 148.410816 88.992787)
		(width 0.1016)
		(layer "In2.Cu")
		(net 41)
	)
	(segment
		(start 147.706583 89.837105)
		(end 147.987162 90.117684)
		(width 0.1016)
		(layer "In2.Cu")
		(net 41)
	)
	(segment
		(start 148.567572 87.926458)
		(end 148.558637 87.912238)
		(width 0.1016)
		(layer "In2.Cu")
		(net 41)
	)
	(segment
		(start 148.317459 87.688227)
		(end 148.333311 87.68268)
		(width 0.1016)
		(layer "In2.Cu")
		(net 41)
	)
	(segment
		(start 147.246413 90.184935)
		(end 147.251476 90.162754)
		(width 0.1016)
		(layer "In2.Cu")
		(net 41)
	)
	(segment
		(start 147.8726 90.344583)
		(end 147.872599 90.321833)
		(width 0.1016)
		(layer "In2.Cu")
		(net 41)
	)
	(segment
		(start 148.303239 88.274037)
		(end 148.291363 88.262161)
		(width 0.1016)
		(layer "In2.Cu")
		(net 41)
	)
	(segment
		(start 148.532541 88.704227)
		(end 148.516689 88.69868)
		(width 0.1016)
		(layer "In2.Cu")
		(net 41)
	)
	(segment
		(start 146.8766 91.5234)
		(end 147.100687 91.5234)
		(width 0.1016)
		(layer "In2.Cu")
		(net 41)
	)
	(segment
		(start 147.868054 89.535551)
		(end 147.888551 89.525681)
		(width 0.1016)
		(layer "In2.Cu")
		(net 41)
	)
	(segment
		(start 148.575 87.6058)
		(end 148.575 87.5526)
		(width 0.1016)
		(layer "In2.Cu")
		(net 41)
	)
	(segment
		(start 147.412428 90.692418)
		(end 147.430216 90.706604)
		(width 0.1016)
		(layer "In2.Cu")
		(net 41)
	)
	(segment
		(start 147.548714 89.962998)
		(end 147.538844 89.942499)
		(width 0.1016)
		(layer "In2.Cu")
		(net 41)
	)
	(segment
		(start 148.575 88.0122)
		(end 148.575 87.959)
		(width 0.1016)
		(layer "In2.Cu")
		(net 41)
	)
	(segment
		(start 148.558637 87.652561)
		(end 148.567572 87.638341)
		(width 0.1016)
		(layer "In2.Cu")
		(net 41)
	)
	(segment
		(start 148.573119 88.841689)
		(end 148.575 88.825)
		(width 0.1016)
		(layer "In2.Cu")
		(net 41)
	)
	(segment
		(start 147.401428 90.110286)
		(end 147.419216 90.124472)
		(width 0.1016)
		(layer "In2.Cu")
		(net 41)
	)
	(segment
		(start 147.430216 90.706604)
		(end 147.450715 90.716474)
		(width 0.1016)
		(layer "In2.Cu")
		(net 41)
	)
	(segment
		(start 147.131849 90.411839)
		(end 147.412428 90.692418)
		(width 0.1016)
		(layer "In2.Cu")
		(net 41)
	)
	(segment
		(start 148.4324 89.704419)
		(end 148.418214 89.686631)
		(width 0.1016)
		(layer "In2.Cu")
		(net 41)
	)
	(segment
		(start 148.442271 89.79203)
		(end 148.447334 89.769849)
		(width 0.1016)
		(layer "In2.Cu")
		(net 41)
	)
	(segment
		(start 148.395882 89.058217)
		(end 148.395881 89.035467)
		(width 0.1016)
		(layer "In2.Cu")
		(net 41)
	)
	(segment
		(start 148.588217 89.363242)
		(end 148.593278 89.341062)
		(width 0.1016)
		(layer "In2.Cu")
		(net 41)
	)
	(segment
		(start 148.467458 88.907427)
		(end 148.48331 88.90188)
		(width 0.1016)
		(layer "In2.Cu")
		(net 41)
	)
	(segment
		(start 148.588216 89.29613)
		(end 148.578344 89.275632)
		(width 0.1016)
		(layer "In2.Cu")
		(net 41)
	)
	(segment
		(start 148.516689 88.29228)
		(end 148.5 88.2904)
		(width 0.1016)
		(layer "In2.Cu")
		(net 41)
	)
	(segment
		(start 148.593278 89.341062)
		(end 148.593279 89.31831)
		(width 0.1016)
		(layer "In2.Cu")
		(net 41)
	)
	(segment
		(start 148.35 87.884)
		(end 148.333311 87.882119)
		(width 0.1016)
		(layer "In2.Cu")
		(net 41)
	)
	(segment
		(start 148.578344 89.275632)
		(end 148.56416 89.257843)
		(width 0.1016)
		(layer "In2.Cu")
		(net 41)
	)
	(segment
		(start 148.575 87.959)
		(end 148.573119 87.94231)
		(width 0.1016)
		(layer "In2.Cu")
		(net 41)
	)
	(segment
		(start 148.573119 88.75511)
		(end 148.567572 88.739258)
		(width 0.1016)
		(layer "In2.Cu")
		(net 41)
	)
	(segment
		(start 147.688795 89.822919)
		(end 147.706583 89.837105)
		(width 0.1016)
		(layer "In2.Cu")
		(net 41)
	)
	(segment
		(start 148.07038 90.146804)
		(end 148.092561 90.141741)
		(width 0.1016)
		(layer "In2.Cu")
		(net 41)
	)
	(segment
		(start 147.495646 90.721538)
		(end 147.517827 90.716475)
		(width 0.1016)
		(layer "In2.Cu")
		(net 41)
	)
	(segment
		(start 148.395881 89.035467)
		(end 148.400944 89.013286)
		(width 0.1016)
		(layer "In2.Cu")
		(net 41)
	)
	(segment
		(start 147.313817 90.100415)
		(end 147.335998 90.095352)
		(width 0.1016)
		(layer "In2.Cu")
		(net 41)
	)
	(segment
		(start 148.573119 88.435289)
		(end 148.575 88.4186)
		(width 0.1016)
		(layer "In2.Cu")
		(net 41)
	)
	(segment
		(start 148.567572 88.857541)
		(end 148.573119 88.841689)
		(width 0.1016)
		(layer "In2.Cu")
		(net 41)
	)
	(segment
		(start 147.164033 91.501234)
		(end 147.180121 91.485146)
		(width 0.1016)
		(layer "In2.Cu")
		(net 41)
	)
	(segment
		(start 147.646117 89.807984)
		(end 147.668298 89.813047)
		(width 0.1016)
		(layer "In2.Cu")
		(net 41)
	)
	(segment
		(start 148.113578 89.367765)
		(end 148.108515 89.345584)
		(width 0.1016)
		(layer "In2.Cu")
		(net 41)
	)
	(segment
		(start 147.821148 89.632951)
		(end 147.821147 89.610201)
		(width 0.1016)
		(layer "In2.Cu")
		(net 41)
	)
	(segment
		(start 148.558637 88.058961)
		(end 148.567572 88.044741)
		(width 0.1016)
		(layer "In2.Cu")
		(net 41)
	)
	(segment
		(start 146.775 91.2186)
		(end 146.775 90.625)
		(width 0.1016)
		(layer "In2.Cu")
		(net 41)
	)
	(segment
		(start 147.699795 90.405051)
		(end 147.717583 90.419237)
		(width 0.1016)
		(layer "In2.Cu")
		(net 41)
	)
	(segment
		(start 148.092561 90.141741)
		(end 148.11306 90.131869)
		(width 0.1016)
		(layer "In2.Cu")
		(net 41)
	)
	(segment
		(start 148.425001 89.118684)
		(end 148.410815 89.100897)
		(width 0.1016)
		(layer "In2.Cu")
		(net 41)
	)
	(segment
		(start 148.130847 89.973998)
		(end 147.850267 89.693418)
		(width 0.1016)
		(layer "In2.Cu")
		(net 41)
	)
	(segment
		(start 147.84348 90.261365)
		(end 147.5629 89.980785)
		(width 0.1016)
		(layer "In2.Cu")
		(net 41)
	)
	(segment
		(start 148.532541 88.892572)
		(end 148.546761 88.883637)
		(width 0.1016)
		(layer "In2.Cu")
		(net 41)
	)
	(segment
		(start 148.159966 90.034466)
		(end 148.154903 90.012285)
		(width 0.1016)
		(layer "In2.Cu")
		(net 41)
	)
	(segment
		(start 146.775 91.625)
		(end 146.777547 91.602391)
		(width 0.1016)
		(layer "In2.Cu")
		(net 41)
	)
	(segment
		(start 147.580169 90.587019)
		(end 147.570299 90.56652)
		(width 0.1016)
		(layer "In2.Cu")
		(net 41)
	)
	(segment
		(start 147.738082 90.429107)
		(end 147.760263 90.43417)
		(width 0.1016)
		(layer "In2.Cu")
		(net 41)
	)
	(segment
		(start 148.291363 87.855761)
		(end 148.282428 87.841541)
		(width 0.1016)
		(layer "In2.Cu")
		(net 41)
	)
	(segment
		(start 147.872599 90.321833)
		(end 147.867536 90.299652)
		(width 0.1016)
		(layer "In2.Cu")
		(net 41)
	)
	(segment
		(start 148.418214 89.686631)
		(end 148.137634 89.406051)
		(width 0.1016)
		(layer "In2.Cu")
		(net 41)
	)
	(segment
		(start 147.82621 89.58802)
		(end 147.836082 89.567521)
		(width 0.1016)
		(layer "In2.Cu")
		(net 41)
	)
	(segment
		(start 147.246414 90.207685)
		(end 147.246413 90.184935)
		(width 0.1016)
		(layer "In2.Cu")
		(net 41)
	)
	(segment
		(start 148.453238 88.916362)
		(end 148.467458 88.907427)
		(width 0.1016)
		(layer "In2.Cu")
		(net 41)
	)
	(segment
		(start 148.432427 88.942458)
		(end 148.441362 88.928238)
		(width 0.1016)
		(layer "In2.Cu")
		(net 41)
	)
	(segment
		(start 147.548715 89.854888)
		(end 147.562899 89.837102)
		(width 0.1016)
		(layer "In2.Cu")
		(net 41)
	)
	(segment
		(start 148.573119 88.34871)
		(end 148.567572 88.332858)
		(width 0.1016)
		(layer "In2.Cu")
		(net 41)
	)
	(segment
		(start 147.867537 90.366764)
		(end 147.8726 90.344583)
		(width 0.1016)
		(layer "In2.Cu")
		(net 41)
	)
	(segment
		(start 148.379928 89.854374)
		(end 148.400427 89.844502)
		(width 0.1016)
		(layer "In2.Cu")
		(net 41)
	)
	(segment
		(start 146.832517 91.533461)
		(end 146.853991 91.525947)
		(width 0.1016)
		(layer "In2.Cu")
		(net 41)
	)
	(segment
		(start 147.850267 89.693418)
		(end 147.836081 89.675631)
		(width 0.1016)
		(layer "In2.Cu")
		(net 41)
	)
	(segment
		(start 147.58017 90.654131)
		(end 147.585233 90.63195)
		(width 0.1016)
		(layer "In2.Cu")
		(net 41)
	)
	(segment
		(start 148.275 88.5686)
		(end 148.276881 88.55191)
		(width 0.1016)
		(layer "In2.Cu")
		(net 41)
	)
	(segment
		(start 148.48331 87.475719)
		(end 148.467458 87.470172)
		(width 0.1016)
		(layer "In2.Cu")
		(net 41)
	)
	(segment
		(start 146.853991 91.317652)
		(end 146.832517 91.310138)
		(width 0.1016)
		(layer "In2.Cu")
		(net 41)
	)
	(segment
		(start 148.35 87.6808)
		(end 148.5 87.6808)
		(width 0.1016)
		(layer "In2.Cu")
		(net 41)
	)
	(segment
		(start 148.35 88.2904)
		(end 148.333311 88.288519)
		(width 0.1016)
		(layer "In2.Cu")
		(net 41)
	)
	(segment
		(start 146.785061 91.262682)
		(end 146.777547 91.241208)
		(width 0.1016)
		(layer "In2.Cu")
		(net 41)
	)
	(segment
		(start 148.291363 87.709038)
		(end 148.303239 87.697162)
		(width 0.1016)
		(layer "In2.Cu")
		(net 41)
	)
	(segment
		(start 147.821147 89.610201)
		(end 147.82621 89.58802)
		(width 0.1016)
		(layer "In2.Cu")
		(net 41)
	)
	(segment
		(start 148.546761 88.477237)
		(end 148.558637 88.465361)
		(width 0.1016)
		(layer "In2.Cu")
		(net 41)
	)
	(segment
		(start 148.333311 88.288519)
		(end 148.317459 88.282972)
		(width 0.1016)
		(layer "In2.Cu")
		(net 41)
	)
	(segment
		(start 148.458761 89.425585)
		(end 148.480942 89.430648)
		(width 0.1016)
		(layer "In2.Cu")
		(net 41)
	)
	(segment
		(start 147.275533 90.268152)
		(end 147.261347 90.250365)
		(width 0.1016)
		(layer "In2.Cu")
		(net 41)
	)
	(segment
		(start 148.263529 89.248185)
		(end 148.281318 89.262369)
		(width 0.1016)
		(layer "In2.Cu")
		(net 41)
	)
	(segment
		(start 148.438264 89.415713)
		(end 148.458761 89.425585)
		(width 0.1016)
		(layer "In2.Cu")
		(net 41)
	)
	(segment
		(start 148.546761 87.664437)
		(end 148.558637 87.652561)
		(width 0.1016)
		(layer "In2.Cu")
		(net 41)
	)
	(segment
		(start 148.292317 89.844503)
		(end 148.312816 89.854373)
		(width 0.1016)
		(layer "In2.Cu")
		(net 41)
	)
	(segment
		(start 148.123449 89.280154)
		(end 148.137633 89.262368)
		(width 0.1016)
		(layer "In2.Cu")
		(net 41)
	)
	(segment
		(start 148.575 88.825)
		(end 148.575 88.7718)
		(width 0.1016)
		(layer "In2.Cu")
		(net 41)
	)
	(segment
		(start 148.303239 88.680437)
		(end 148.291363 88.668561)
		(width 0.1016)
		(layer "In2.Cu")
		(net 41)
	)
	(segment
		(start 147.419216 90.124472)
		(end 147.699795 90.405051)
		(width 0.1016)
		(layer "In2.Cu")
		(net 41)
	)
	(segment
		(start 147.825693 90.419236)
		(end 147.843479 90.405051)
		(width 0.1016)
		(layer "In2.Cu")
		(net 41)
	)
	(segment
		(start 148.282428 87.841541)
		(end 148.276881 87.825689)
		(width 0.1016)
		(layer "In2.Cu")
		(net 41)
	)
	(segment
		(start 148.516689 88.491719)
		(end 148.532541 88.486172)
		(width 0.1016)
		(layer "In2.Cu")
		(net 41)
	)
	(segment
		(start 148.573119 87.53591)
		(end 148.567572 87.520058)
		(width 0.1016)
		(layer "In2.Cu")
		(net 41)
	)
	(segment
		(start 147.850266 89.549735)
		(end 147.868054 89.535551)
		(width 0.1016)
		(layer "In2.Cu")
		(net 41)
	)
	(segment
		(start 146.813253 91.298034)
		(end 146.797165 91.281946)
		(width 0.1016)
		(layer "In2.Cu")
		(net 41)
	)
	(segment
		(start 148.276881 88.14551)
		(end 148.282428 88.129658)
		(width 0.1016)
		(layer "In2.Cu")
		(net 41)
	)
	(segment
		(start 148.303239 88.509962)
		(end 148.317459 88.501027)
		(width 0.1016)
		(layer "In2.Cu")
		(net 41)
	)
	(segment
		(start 148.276881 87.73911)
		(end 148.282428 87.723258)
		(width 0.1016)
		(layer "In2.Cu")
		(net 41)
	)
	(segment
		(start 148.480942 89.430648)
		(end 148.503694 89.430647)
		(width 0.1016)
		(layer "In2.Cu")
		(net 41)
	)
	(segment
		(start 148.567572 88.332858)
		(end 148.558637 88.318638)
		(width 0.1016)
		(layer "In2.Cu")
		(net 41)
	)
	(segment
		(start 147.144769 91.513338)
		(end 147.164033 91.501234)
		(width 0.1016)
		(layer "In2.Cu")
		(net 41)
	)
	(segment
		(start 148.447334 89.769849)
		(end 148.447333 89.747099)
		(width 0.1016)
		(layer "In2.Cu")
		(net 41)
	)
	(segment
		(start 147.517827 90.716475)
		(end 147.538326 90.706603)
		(width 0.1016)
		(layer "In2.Cu")
		(net 41)
	)
	(segment
		(start 146.832517 91.310138)
		(end 146.813253 91.298034)
		(width 0.1016)
		(layer "In2.Cu")
		(net 41)
	)
	(segment
		(start 147.533781 89.920318)
		(end 147.53378 89.897568)
		(width 0.1016)
		(layer "In2.Cu")
		(net 41)
	)
	(segment
		(start 148.303239 87.697162)
		(end 148.317459 87.688227)
		(width 0.1016)
		(layer "In2.Cu")
		(net 41)
	)
	(segment
		(start 146.988165 90.411836)
		(end 147.005953 90.397652)
		(width 0.1016)
		(layer "In2.Cu")
		(net 41)
	)
	(segment
		(start 148.025449 90.14174)
		(end 148.04763 90.146803)
		(width 0.1016)
		(layer "In2.Cu")
		(net 41)
	)
	(segment
		(start 146.8766 91.3202)
		(end 146.853991 91.317652)
		(width 0.1016)
		(layer "In2.Cu")
		(net 41)
	)
	(segment
		(start 147.53378 89.897568)
		(end 147.538843 89.875387)
		(width 0.1016)
		(layer "In2.Cu")
		(net 41)
	)
	(segment
		(start 148.312816 89.854373)
		(end 148.334997 89.859436)
		(width 0.1016)
		(layer "In2.Cu")
		(net 41)
	)
	(segment
		(start 148.175919 89.238312)
		(end 148.198099 89.233251)
		(width 0.1016)
		(layer "In2.Cu")
		(net 41)
	)
	(segment
		(start 148.516689 88.898119)
		(end 148.532541 88.892572)
		(width 0.1016)
		(layer "In2.Cu")
		(net 41)
	)
	(segment
		(start 148.558637 88.725038)
		(end 148.546761 88.713162)
		(width 0.1016)
		(layer "In2.Cu")
		(net 41)
	)
	(segment
		(start 148.275 87.7558)
		(end 148.276881 87.73911)
		(width 0.1016)
		(layer "In2.Cu")
		(net 41)
	)
	(segment
		(start 148.159967 90.057216)
		(end 148.159966 90.034466)
		(width 0.1016)
		(layer "In2.Cu")
		(net 41)
	)
	(segment
		(start 148.274529 89.830317)
		(end 148.292317 89.844503)
		(width 0.1016)
		(layer "In2.Cu")
		(net 41)
	)
	(segment
		(start 148.546761 88.883637)
		(end 148.558637 88.871761)
		(width 0.1016)
		(layer "In2.Cu")
		(net 41)
	)
	(segment
		(start 148.291363 88.668561)
		(end 148.282428 88.654341)
		(width 0.1016)
		(layer "In2.Cu")
		(net 41)
	)
	(segment
		(start 147.601184 89.813048)
		(end 147.623365 89.807985)
		(width 0.1016)
		(layer "In2.Cu")
		(net 41)
	)
	(segment
		(start 148.04763 90.146803)
		(end 148.07038 90.146804)
		(width 0.1016)
		(layer "In2.Cu")
		(net 41)
	)
	(segment
		(start 148.282428 87.723258)
		(end 148.291363 87.709038)
		(width 0.1016)
		(layer "In2.Cu")
		(net 41)
	)
	(segment
		(start 147.192225 91.465882)
		(end 147.199739 91.444408)
		(width 0.1016)
		(layer "In2.Cu")
		(net 41)
	)
	(segment
		(start 148.56416 89.401527)
		(end 148.578345 89.38374)
		(width 0.1016)
		(layer "In2.Cu")
		(net 41)
	)
	(segment
		(start 148.573119 87.94231)
		(end 148.567572 87.926458)
		(width 0.1016)
		(layer "In2.Cu")
		(net 41)
	)
	(segment
		(start 147.093564 90.387781)
		(end 147.114061 90.397653)
		(width 0.1016)
		(layer "In2.Cu")
		(net 41)
	)
	(segment
		(start 146.797165 91.281946)
		(end 146.785061 91.262682)
		(width 0.1016)
		(layer "In2.Cu")
		(net 41)
	)
	(segment
		(start 148.5 88.0872)
		(end 148.516689 88.085319)
		(width 0.1016)
		(layer "In2.Cu")
		(net 41)
	)
	(segment
		(start 147.100687 91.3202)
		(end 146.8766 91.3202)
		(width 0.1016)
		(layer "In2.Cu")
		(net 41)
	)
	(segment
		(start 147.538326 90.706603)
		(end 147.556112 90.692418)
		(width 0.1016)
		(layer "In2.Cu")
		(net 41)
	)
	(segment
		(start 147.071383 90.382718)
		(end 147.093564 90.387781)
		(width 0.1016)
		(layer "In2.Cu")
		(net 41)
	)
	(segment
		(start 147.02645 90.387782)
		(end 147.048631 90.382719)
		(width 0.1016)
		(layer "In2.Cu")
		(net 41)
	)
	(segment
		(start 148.317459 88.282972)
		(end 148.303239 88.274037)
		(width 0.1016)
		(layer "In2.Cu")
		(net 41)
	)
	(segment
		(start 148.220851 89.23325)
		(end 148.243031 89.238313)
		(width 0.1016)
		(layer "In2.Cu")
		(net 41)
	)
	(segment
		(start 147.202287 91.4218)
		(end 147.199739 91.399191)
		(width 0.1016)
		(layer "In2.Cu")
		(net 41)
	)
	(segment
		(start 147.100687 91.5234)
		(end 147.123295 91.520852)
		(width 0.1016)
		(layer "In2.Cu")
		(net 41)
	)
	(segment
		(start 147.783013 90.434171)
		(end 147.805194 90.429108)
		(width 0.1016)
		(layer "In2.Cu")
		(net 41)
	)
	(segment
		(start 147.005953 90.397652)
		(end 147.02645 90.387782)
		(width 0.1016)
		(layer "In2.Cu")
		(net 41)
	)
	(segment
		(start 146.775 90.625)
		(end 146.988165 90.411836)
		(width 0.1016)
		(layer "In2.Cu")
		(net 41)
	)
	(segment
		(start 148.516689 87.47948)
		(end 148.48331 87.475719)
		(width 0.1016)
		(layer "In2.Cu")
		(net 41)
	)
	(segment
		(start 147.843479 90.405051)
		(end 147.857665 90.387263)
		(width 0.1016)
		(layer "In2.Cu")
		(net 41)
	)
	(segment
		(start 147.933484 89.520617)
		(end 147.955665 89.52568)
		(width 0.1016)
		(layer "In2.Cu")
		(net 41)
	)
	(segment
		(start 148.275 88.2154)
		(end 148.275 88.1622)
		(width 0.1016)
		(layer "In2.Cu")
		(net 41)
	)
	(segment
		(start 148.42688 87.419289)
		(end 148.425 87.4026)
		(width 0.1016)
		(layer "In2.Cu")
		(net 41)
	)
	(segment
		(start 148.357747 89.859437)
		(end 148.379928 89.854374)
		(width 0.1016)
		(layer "In2.Cu")
		(net 41)
	)
	(segment
		(start 148.281318 89.262369)
		(end 148.420476 89.401527)
		(width 0.1016)
		(layer "In2.Cu")
		(net 41)
	)
	(segment
		(start 147.5629 89.980785)
		(end 147.548714 89.962998)
		(width 0.1016)
		(layer "In2.Cu")
		(net 41)
	)
	(segment
		(start 147.570299 90.56652)
		(end 147.556113 90.548732)
		(width 0.1016)
		(layer "In2.Cu")
		(net 41)
	)
	(segment
		(start 148.317459 87.876572)
		(end 148.303239 87.867637)
		(width 0.1016)
		(layer "In2.Cu")
		(net 41)
	)
	(segment
		(start 146.775 92.3)
		(end 146.775 91.625)
		(width 0.1016)
		(layer "In2.Cu")
		(net 41)
	)
	(segment
		(start 148.516689 88.69868)
		(end 148.5 88.6968)
		(width 0.1016)
		(layer "In2.Cu")
		(net 41)
	)
	(segment
		(start 148.276881 88.232089)
		(end 148.275 88.2154)
		(width 0.1016)
		(layer "In2.Cu")
		(net 41)
	)
	(segment
		(start 147.144769 91.330261)
		(end 147.123295 91.322747)
		(width 0.1016)
		(layer "In2.Cu")
		(net 41)
	)
	(segment
		(start 146.797165 91.561653)
		(end 146.813253 91.545565)
		(width 0.1016)
		(layer "In2.Cu")
		(net 41)
	)
	(segment
		(start 147.556112 90.692418)
		(end 147.570298 90.67463)
		(width 0.1016)
		(layer "In2.Cu")
		(net 41)
	)
	(segment
		(start 148.113577 89.300653)
		(end 148.123449 89.280154)
		(width 0.1016)
		(layer "In2.Cu")
		(net 41)
	)
	(segment
		(start 147.261348 90.142255)
		(end 147.275532 90.124469)
		(width 0.1016)
		(layer "In2.Cu")
		(net 41)
	)
	(segment
		(start 147.857665 90.387263)
		(end 147.867537 90.366764)
		(width 0.1016)
		(layer "In2.Cu")
		(net 41)
	)
	(segment
		(start 148.467458 87.470172)
		(end 148.453238 87.461237)
		(width 0.1016)
		(layer "In2.Cu")
		(net 41)
	)
	(segment
		(start 148.5 87.6808)
		(end 148.516689 87.678919)
		(width 0.1016)
		(layer "In2.Cu")
		(net 41)
	)
	(segment
		(start 148.137634 89.406051)
		(end 148.123448 89.388264)
		(width 0.1016)
		(layer "In2.Cu")
		(net 41)
	)
	(segment
		(start 148.48331 88.90188)
		(end 148.516689 88.898119)
		(width 0.1016)
		(layer "In2.Cu")
		(net 41)
	)
	(segment
		(start 148.5 88.6968)
		(end 148.35 88.6968)
		(width 0.1016)
		(layer "In2.Cu")
		(net 41)
	)
	(segment
		(start 147.048631 90.382719)
		(end 147.071383 90.382718)
		(width 0.1016)
		(layer "In2.Cu")
		(net 41)
	)
	(segment
		(start 148.333311 88.49548)
		(end 148.35 88.4936)
		(width 0.1016)
		(layer "In2.Cu")
		(net 41)
	)
	(segment
		(start 146.777547 91.241208)
		(end 146.775 91.2186)
		(width 0.1016)
		(layer "In2.Cu")
		(net 41)
	)
	(segment
		(start 147.836082 89.567521)
		(end 147.850266 89.549735)
		(width 0.1016)
		(layer "In2.Cu")
		(net 41)
	)
	(segment
		(start 148.432399 89.812529)
		(end 148.442271 89.79203)
		(width 0.1016)
		(layer "In2.Cu")
		(net 41)
	)
	(segment
		(start 148.333311 87.882119)
		(end 148.317459 87.876572)
		(width 0.1016)
		(layer "In2.Cu")
		(net 41)
	)
	(segment
		(start 148.334997 89.859436)
		(end 148.357747 89.859437)
		(width 0.1016)
		(layer "In2.Cu")
		(net 41)
	)
	(segment
		(start 148.546761 88.713162)
		(end 148.532541 88.704227)
		(width 0.1016)
		(layer "In2.Cu")
		(net 41)
	)
	(segment
		(start 148.453238 87.461237)
		(end 148.441362 87.449361)
		(width 0.1016)
		(layer "In2.Cu")
		(net 41)
	)
	(segment
		(start 148.425 88.975)
		(end 148.42688 88.95831)
		(width 0.1016)
		(layer "In2.Cu")
		(net 41)
	)
	(segment
		(start 148.154903 90.012285)
		(end 148.145033 89.991786)
		(width 0.1016)
		(layer "In2.Cu")
		(net 41)
	)
	(segment
		(start 148.567572 87.638341)
		(end 148.573119 87.622489)
		(width 0.1016)
		(layer "In2.Cu")
		(net 41)
	)
	(segment
		(start 148.198099 89.233251)
		(end 148.220851 89.23325)
		(width 0.1016)
		(layer "In2.Cu")
		(net 41)
	)
	(segment
		(start 148.35 88.4936)
		(end 148.5 88.4936)
		(width 0.1016)
		(layer "In2.Cu")
		(net 41)
	)
	(segment
		(start 147.585232 90.6092)
		(end 147.580169 90.587019)
		(width 0.1016)
		(layer "In2.Cu")
		(net 41)
	)
	(segment
		(start 147.623365 89.807985)
		(end 147.646117 89.807984)
		(width 0.1016)
		(layer "In2.Cu")
		(net 41)
	)
	(segment
		(start 147.888551 89.525681)
		(end 147.910732 89.520618)
		(width 0.1016)
		(layer "In2.Cu")
		(net 41)
	)
	(segment
		(start 147.717583 90.419237)
		(end 147.738082 90.429107)
		(width 0.1016)
		(layer "In2.Cu")
		(net 41)
	)
	(segment
		(start 148.432427 87.435141)
		(end 148.42688 87.419289)
		(width 0.1016)
		(layer "In2.Cu")
		(net 41)
	)
	(segment
		(start 147.180121 91.485146)
		(end 147.192225 91.465882)
		(width 0.1016)
		(layer "In2.Cu")
		(net 41)
	)
	(segment
		(start 148.567572 88.739258)
		(end 148.558637 88.725038)
		(width 0.1016)
		(layer "In2.Cu")
		(net 41)
	)
	(segment
		(start 148.532541 87.891427)
		(end 148.516689 87.88588)
		(width 0.1016)
		(layer "In2.Cu")
		(net 41)
	)
	(segment
		(start 147.261347 90.250365)
		(end 147.251477 90.229866)
		(width 0.1016)
		(layer "In2.Cu")
		(net 41)
	)
	(segment
		(start 147.180121 91.358453)
		(end 147.164033 91.342365)
		(width 0.1016)
		(layer "In2.Cu")
		(net 41)
	)
	(segment
		(start 147.955665 89.52568)
		(end 147.976162 89.535552)
		(width 0.1016)
		(layer "In2.Cu")
		(net 41)
	)
	(segment
		(start 148.291363 88.115438)
		(end 148.303239 88.103562)
		(width 0.1016)
		(layer "In2.Cu")
		(net 41)
	)
	(segment
		(start 148.5 88.2904)
		(end 148.35 88.2904)
		(width 0.1016)
		(layer "In2.Cu")
		(net 41)
	)
	(segment
		(start 148.420476 89.401527)
		(end 148.438264 89.415713)
		(width 0.1016)
		(layer "In2.Cu")
		(net 41)
	)
	(segment
		(start 147.805194 90.429108)
		(end 147.825693 90.419236)
		(width 0.1016)
		(layer "In2.Cu")
		(net 41)
	)
	(segment
		(start 148.400945 89.080398)
		(end 148.395882 89.058217)
		(width 0.1016)
		(layer "In2.Cu")
		(net 41)
	)
	(segment
		(start 146.853991 91.525947)
		(end 146.8766 91.5234)
		(width 0.1016)
		(layer "In2.Cu")
		(net 41)
	)
	(segment
		(start 148.558637 87.912238)
		(end 148.546761 87.900362)
		(width 0.1016)
		(layer "In2.Cu")
		(net 41)
	)
	(segment
		(start 148.575 88.7718)
		(end 148.573119 88.75511)
		(width 0.1016)
		(layer "In2.Cu")
		(net 41)
	)
	(segment
		(start 146.777547 91.602391)
		(end 146.785061 91.580917)
		(width 0.1016)
		(layer "In2.Cu")
		(net 41)
	)
	(segment
		(start 148.276881 87.825689)
		(end 148.275 87.809)
		(width 0.1016)
		(layer "In2.Cu")
		(net 41)
	)
	(segment
		(start 148.575 88.4186)
		(end 148.575 88.3654)
		(width 0.1016)
		(layer "In2.Cu")
		(net 41)
	)
	(segment
		(start 148.578345 89.38374)
		(end 148.588217 89.363242)
		(width 0.1016)
		(layer "In2.Cu")
		(net 41)
	)
	(segment
		(start 148.5 88.4936)
		(end 148.516689 88.491719)
		(width 0.1016)
		(layer "In2.Cu")
		(net 41)
	)
	(segment
		(start 147.275532 90.124469)
		(end 147.29332 90.110285)
		(width 0.1016)
		(layer "In2.Cu")
		(net 41)
	)
	(segment
		(start 148.532541 87.673372)
		(end 148.546761 87.664437)
		(width 0.1016)
		(layer "In2.Cu")
		(net 41)
	)
	(segment
		(start 148.410816 88.992787)
		(end 148.425 88.975)
		(width 0.1016)
		(layer "In2.Cu")
		(net 41)
	)
	(segment
		(start 148.532541 88.486172)
		(end 148.546761 88.477237)
		(width 0.1016)
		(layer "In2.Cu")
		(net 41)
	)
	(segment
		(start 147.123295 91.322747)
		(end 147.100687 91.3202)
		(width 0.1016)
		(layer "In2.Cu")
		(net 41)
	)
	(segment
		(start 148.123448 89.388264)
		(end 148.113578 89.367765)
		(width 0.1016)
		(layer "In2.Cu")
		(net 41)
	)
	(segment
		(start 148.441362 87.449361)
		(end 148.432427 87.435141)
		(width 0.1016)
		(layer "In2.Cu")
		(net 41)
	)
	(segment
		(start 148.35 88.0872)
		(end 148.5 88.0872)
		(width 0.1016)
		(layer "In2.Cu")
		(net 41)
	)
	(segment
		(start 148.575 88.3654)
		(end 148.573119 88.34871)
		(width 0.1016)
		(layer "In2.Cu")
		(net 41)
	)
	(segment
		(start 148.282428 88.654341)
		(end 148.276881 88.638489)
		(width 0.1016)
		(layer "In2.Cu")
		(net 41)
	)
	(segment
		(start 147.857666 90.279153)
		(end 147.84348 90.261365)
		(width 0.1016)
		(layer "In2.Cu")
		(net 41)
	)
	(segment
		(start 148.56416 89.257843)
		(end 148.425001 89.118684)
		(width 0.1016)
		(layer "In2.Cu")
		(net 41)
	)
	(segment
		(start 148.243031 89.238313)
		(end 148.263529 89.248185)
		(width 0.1016)
		(layer "In2.Cu")
		(net 41)
	)
	(segment
		(start 148.558637 88.871761)
		(end 148.567572 88.857541)
		(width 0.1016)
		(layer "In2.Cu")
		(net 41)
	)
	(segment
		(start 146.785061 91.580917)
		(end 146.797165 91.561653)
		(width 0.1016)
		(layer "In2.Cu")
		(net 41)
	)
	(segment
		(start 147.123295 91.520852)
		(end 147.144769 91.513338)
		(width 0.1016)
		(layer "In2.Cu")
		(net 41)
	)
	(segment
		(start 148.291363 88.521838)
		(end 148.303239 88.509962)
		(width 0.1016)
		(layer "In2.Cu")
		(net 41)
	)
	(segment
		(start 148.276881 88.638489)
		(end 148.275 88.6218)
		(width 0.1016)
		(layer "In2.Cu")
		(net 41)
	)
	(segment
		(start 148.410815 89.100897)
		(end 148.400945 89.080398)
		(width 0.1016)
		(layer "In2.Cu")
		(net 41)
	)
	(segment
		(start 147.538844 89.942499)
		(end 147.533781 89.920318)
		(width 0.1016)
		(layer "In2.Cu")
		(net 41)
	)
	(segment
		(start 147.199739 91.444408)
		(end 147.202287 91.4218)
		(width 0.1016)
		(layer "In2.Cu")
		(net 41)
	)
	(segment
		(start 147.580687 89.822918)
		(end 147.601184 89.813048)
		(width 0.1016)
		(layer "In2.Cu")
		(net 41)
	)
	(segment
		(start 148.5 87.884)
		(end 148.35 87.884)
		(width 0.1016)
		(layer "In2.Cu")
		(net 41)
	)
	(segment
		(start 148.282428 88.129658)
		(end 148.291363 88.115438)
		(width 0.1016)
		(layer "In2.Cu")
		(net 41)
	)
	(segment
		(start 148.558637 88.318638)
		(end 148.546761 88.306762)
		(width 0.1016)
		(layer "In2.Cu")
		(net 41)
	)
	(segment
		(start 148.145032 90.099896)
		(end 148.154904 90.079397)
		(width 0.1016)
		(layer "In2.Cu")
		(net 41)
	)
	(segment
		(start 147.164033 91.342365)
		(end 147.144769 91.330261)
		(width 0.1016)
		(layer "In2.Cu")
		(net 41)
	)
	(segment
		(start 148.516689 87.678919)
		(end 148.532541 87.673372)
		(width 0.1016)
		(layer "In2.Cu")
		(net 41)
	)
	(segment
		(start 147.199739 91.399191)
		(end 147.192225 91.377717)
		(width 0.1016)
		(layer "In2.Cu")
		(net 41)
	)
	(segment
		(start 147.562899 89.837102)
		(end 147.580687 89.822918)
		(width 0.1016)
		(layer "In2.Cu")
		(net 41)
	)
	(segment
		(start 147.910732 89.520618)
		(end 147.933484 89.520617)
		(width 0.1016)
		(layer "In2.Cu")
		(net 41)
	)
	(segment
		(start 148.130846 90.117684)
		(end 148.145032 90.099896)
		(width 0.1016)
		(layer "In2.Cu")
		(net 41)
	)
	(segment
		(start 147.472896 90.721537)
		(end 147.495646 90.721538)
		(width 0.1016)
		(layer "In2.Cu")
		(net 41)
	)
	(segment
		(start 148.567572 88.451141)
		(end 148.573119 88.435289)
		(width 0.1016)
		(layer "In2.Cu")
		(net 41)
	)
	(segment
		(start 147.585233 90.63195)
		(end 147.585232 90.6092)
		(width 0.1016)
		(layer "In2.Cu")
		(net 41)
	)
	(segment
		(start 148.317459 88.689372)
		(end 148.303239 88.680437)
		(width 0.1016)
		(layer "In2.Cu")
		(net 41)
	)
	(segment
		(start 147.114061 90.397653)
		(end 147.131849 90.411839)
		(width 0.1016)
		(layer "In2.Cu")
		(net 41)
	)
	(segment
		(start 147.192225 91.377717)
		(end 147.180121 91.358453)
		(width 0.1016)
		(layer "In2.Cu")
		(net 41)
	)
	(segment
		(start 148.303239 88.103562)
		(end 148.317459 88.094627)
		(width 0.1016)
		(layer "In2.Cu")
		(net 41)
	)
	(segment
		(start 148.00495 90.13187)
		(end 148.025449 90.14174)
		(width 0.1016)
		(layer "In2.Cu")
		(net 41)
	)
	(segment
		(start 148.317459 88.501027)
		(end 148.333311 88.49548)
		(width 0.1016)
		(layer "In2.Cu")
		(net 41)
	)
	(segment
		(start 147.668298 89.813047)
		(end 147.688795 89.822919)
		(width 0.1016)
		(layer "In2.Cu")
		(net 41)
	)
	(segment
		(start 148.573119 87.622489)
		(end 148.575 87.6058)
		(width 0.1016)
		(layer "In2.Cu")
		(net 41)
	)
	(segment
		(start 148.567572 87.520058)
		(end 148.558637 87.505838)
		(width 0.1016)
		(layer "In2.Cu")
		(net 41)
	)
	(segment
		(start 148.291363 88.262161)
		(end 148.282428 88.247941)
		(width 0.1016)
		(layer "In2.Cu")
		(net 41)
	)
	(segment
		(start 147.826211 89.655132)
		(end 147.821148 89.632951)
		(width 0.1016)
		(layer "In2.Cu")
		(net 41)
	)
	(segment
		(start 148.333311 88.694919)
		(end 148.317459 88.689372)
		(width 0.1016)
		(layer "In2.Cu")
		(net 41)
	)
	(segment
		(start 148.503694 89.430647)
		(end 148.525875 89.425584)
		(width 0.1016)
		(layer "In2.Cu")
		(net 41)
	)
	(segment
		(start 148.573119 88.028889)
		(end 148.575 88.0122)
		(width 0.1016)
		(layer "In2.Cu")
		(net 41)
	)
	(segment
		(start 148.418213 89.830317)
		(end 148.432399 89.812529)
		(width 0.1016)
		(layer "In2.Cu")
		(net 41)
	)
	(segment
		(start 148.275 88.1622)
		(end 148.276881 88.14551)
		(width 0.1016)
		(layer "In2.Cu")
		(net 41)
	)
	(segment
		(start 148.546761 87.900362)
		(end 148.532541 87.891427)
		(width 0.1016)
		(layer "In2.Cu")
		(net 41)
	)
	(segment
		(start 148.108514 89.322834)
		(end 148.113577 89.300653)
		(width 0.1016)
		(layer "In2.Cu")
		(net 41)
	)
	(segment
		(start 147.99395 89.549738)
		(end 148.274529 89.830317)
		(width 0.1016)
		(layer "In2.Cu")
		(net 41)
	)
	(segment
		(start 148.282428 88.247941)
		(end 148.276881 88.232089)
		(width 0.1016)
		(layer "In2.Cu")
		(net 41)
	)
	(segment
		(start 148.546761 88.070837)
		(end 148.558637 88.058961)
		(width 0.1016)
		(layer "In2.Cu")
		(net 41)
	)
	(segment
		(start 148.145033 89.991786)
		(end 148.130847 89.973998)
		(width 0.1016)
		(layer "In2.Cu")
		(net 41)
	)
	(segment
		(start 148.42688 88.95831)
		(end 148.432427 88.942458)
		(width 0.1016)
		(layer "In2.Cu")
		(net 41)
	)
	(segment
		(start 148.303239 87.867637)
		(end 148.291363 87.855761)
		(width 0.1016)
		(layer "In2.Cu")
		(net 41)
	)
	(segment
		(start 148.532541 88.079772)
		(end 148.546761 88.070837)
		(width 0.1016)
		(layer "In2.Cu")
		(net 41)
	)
	(segment
		(start 148.400427 89.844502)
		(end 148.418213 89.830317)
		(width 0.1016)
		(layer "In2.Cu")
		(net 41)
	)
	(segment
		(start 147.976162 89.535552)
		(end 147.99395 89.549738)
		(width 0.1016)
		(layer "In2.Cu")
		(net 41)
	)
	(segment
		(start 147.251476 90.162754)
		(end 147.261348 90.142255)
		(width 0.1016)
		(layer "In2.Cu")
		(net 41)
	)
	(segment
		(start 146.813253 91.545565)
		(end 146.832517 91.533461)
		(width 0.1016)
		(layer "In2.Cu")
		(net 41)
	)
	(segment
		(start 148.35 88.6968)
		(end 148.333311 88.694919)
		(width 0.1016)
		(layer "In2.Cu")
		(net 41)
	)
	(segment
		(start 148.532541 87.485027)
		(end 148.516689 87.47948)
		(width 0.1016)
		(layer "In2.Cu")
		(net 41)
	)
	(segment
		(start 147.35875 90.095351)
		(end 147.380931 90.100414)
		(width 0.1016)
		(layer "In2.Cu")
		(net 41)
	)
	(segment
		(start 151.1008 86.7258)
		(end 151.225 86.85)
		(width 0.1016)
		(layer "F.Cu")
		(net 42)
	)
	(segment
		(start 146.925 97.085749)
		(end 146.9508 97.059949)
		(width 0.1016)
		(layer "F.Cu")
		(net 42)
	)
	(segment
		(start 151.1008 86.309949)
		(end 151.1008 86.7258)
		(width 0.1016)
		(layer "F.Cu")
		(net 42)
	)
	(segment
		(start 146.925 98.7)
		(end 146.925 97.085749)
		(width 0.1016)
		(layer "F.Cu")
		(net 42)
	)
	(via
		(at 151.1008 86.309949)
		(size 0.45)
		(drill 0.15)
		(layers "F.Cu" "B.Cu")
		(net 42)
	)
	(via
		(at 146.9508 97.059949)
		(size 0.45)
		(drill 0.15)
		(layers "F.Cu" "B.Cu")
		(net 42)
	)
	(segment
		(start 146.977213 93.841074)
		(end 147.002272 93.829006)
		(width 0.1016)
		(layer "In2.Cu")
		(net 42)
	)
	(segment
		(start 148.927834 95.516813)
		(end 149.028223 95.516813)
		(width 0.1016)
		(layer "In2.Cu")
		(net 42)
	)
	(segment
		(start 148.547973 95.642458)
		(end 148.485381 95.56397)
		(width 0.1016)
		(layer "In2.Cu")
		(net 42)
	)
	(segment
		(start 147.057197 93.822818)
		(end 147.084312 93.829007)
		(width 0.1016)
		(layer "In2.Cu")
		(net 42)
	)
	(segment
		(start 148.485381 95.56397)
		(end 146.955468 94.034059)
		(width 0.1016)
		(layer "In2.Cu")
		(net 42)
	)
	(segment
		(start 149.33391 95.349445)
		(end 149.396502 95.270958)
		(width 0.1016)
		(layer "In2.Cu")
		(net 42)
	)
	(segment
		(start 147.002272 93.829006)
		(end 147.029385 93.822818)
		(width 0.1016)
		(layer "In2.Cu")
		(net 42)
	)
	(segment
		(start 147.109371 93.841073)
		(end 147.131115 93.858413)
		(width 0.1016)
		(layer "In2.Cu")
		(net 42)
	)
	(segment
		(start 146.9508 97.059949)
		(end 146.8508 96.959949)
		(width 0.1016)
		(layer "In2.Cu")
		(net 42)
	)
	(segment
		(start 147.22821 95.656968)
		(end 147.249954 95.674309)
		(width 0.1016)
		(layer "In2.Cu")
		(net 42)
	)
	(segment
		(start 147.203152 95.644901)
		(end 147.22821 95.656968)
		(width 0.1016)
		(layer "In2.Cu")
		(net 42)
	)
	(segment
		(start 151.0008 91.74782)
		(end 151.0008 86.409949)
		(width 0.1016)
		(layer "In2.Cu")
		(net 42)
	)
	(segment
		(start 148.368013 96.299445)
		(end 148.4465 96.236854)
		(width 0.1016)
		(layer "In2.Cu")
		(net 42)
	)
	(segment
		(start 147.121111 95.644901)
		(end 147.148226 95.638712)
		(width 0.1016)
		(layer "In2.Cu")
		(net 42)
	)
	(segment
		(start 146.919872 93.932331)
		(end 146.926061 93.905216)
		(width 0.1016)
		(layer "In2.Cu")
		(net 42)
	)
	(segment
		(start 149.440059 95.18051)
		(end 149.462397 95.082639)
		(width 0.1016)
		(layer "In2.Cu")
		(net 42)
	)
	(segment
		(start 148.4465 96.236854)
		(end 148.485381 96.197972)
		(width 0.1016)
		(layer "In2.Cu")
		(net 42)
	)
	(segment
		(start 149.028223 95.516813)
		(end 149.126095 95.494475)
		(width 0.1016)
		(layer "In2.Cu")
		(net 42)
	)
	(segment
		(start 147.981433 96.343002)
		(end 148.079305 96.365341)
		(width 0.1016)
		(layer "In2.Cu")
		(net 42)
	)
	(segment
		(start 147.890986 96.299445)
		(end 147.981433 96.343002)
		(width 0.1016)
		(layer "In2.Cu")
		(net 42)
	)
	(segment
		(start 146.955469 93.858413)
		(end 146.977213 93.841074)
		(width 0.1016)
		(layer "In2.Cu")
		(net 42)
	)
	(segment
		(start 149.33391 94.715443)
		(end 148.771365 94.152898)
		(width 0.1016)
		(layer "In2.Cu")
		(net 42)
	)
	(segment
		(start 149.126095 95.494475)
		(end 149.216542 95.450918)
		(width 0.1016)
		(layer "In2.Cu")
		(net 42)
	)
	(segment
		(start 149.462397 95.082639)
		(end 149.462397 94.98225)
		(width 0.1016)
		(layer "In2.Cu")
		(net 42)
	)
	(segment
		(start 146.919872 93.960143)
		(end 146.919872 93.932331)
		(width 0.1016)
		(layer "In2.Cu")
		(net 42)
	)
	(segment
		(start 146.955468 94.034059)
		(end 146.938128 94.012315)
		(width 0.1016)
		(layer "In2.Cu")
		(net 42)
	)
	(segment
		(start 148.179694 96.365341)
		(end 148.277566 96.343002)
		(width 0.1016)
		(layer "In2.Cu")
		(net 42)
	)
	(segment
		(start 148.754024 93.998997)
		(end 148.771365 93.977252)
		(width 0.1016)
		(layer "In2.Cu")
		(net 42)
	)
	(segment
		(start 148.661028 95.388326)
		(end 148.739515 95.450918)
		(width 0.1016)
		(layer "In2.Cu")
		(net 42)
	)
	(segment
		(start 148.59153 95.732905)
		(end 148.547973 95.642458)
		(width 0.1016)
		(layer "In2.Cu")
		(net 42)
	)
	(segment
		(start 147.131115 93.858413)
		(end 148.661028 95.388326)
		(width 0.1016)
		(layer "In2.Cu")
		(net 42)
	)
	(segment
		(start 147.148226 95.638712)
		(end 147.176038 95.638712)
		(width 0.1016)
		(layer "In2.Cu")
		(net 42)
	)
	(segment
		(start 148.771365 94.152898)
		(end 148.754024 94.131154)
		(width 0.1016)
		(layer "In2.Cu")
		(net 42)
	)
	(segment
		(start 148.59153 96.029037)
		(end 148.613868 95.931166)
		(width 0.1016)
		(layer "In2.Cu")
		(net 42)
	)
	(segment
		(start 148.741957 94.106096)
		(end 148.735768 94.078981)
		(width 0.1016)
		(layer "In2.Cu")
		(net 42)
	)
	(segment
		(start 148.829962 95.494475)
		(end 148.927834 95.516813)
		(width 0.1016)
		(layer "In2.Cu")
		(net 42)
	)
	(segment
		(start 148.735768 94.078981)
		(end 148.735768 94.051169)
		(width 0.1016)
		(layer "In2.Cu")
		(net 42)
	)
	(segment
		(start 146.938129 93.880157)
		(end 146.955469 93.858413)
		(width 0.1016)
		(layer "In2.Cu")
		(net 42)
	)
	(segment
		(start 148.485381 96.197972)
		(end 148.547973 96.119485)
		(width 0.1016)
		(layer "In2.Cu")
		(net 42)
	)
	(segment
		(start 147.084312 93.829007)
		(end 147.109371 93.841073)
		(width 0.1016)
		(layer "In2.Cu")
		(net 42)
	)
	(segment
		(start 148.741957 94.024055)
		(end 148.754024 93.998997)
		(width 0.1016)
		(layer "In2.Cu")
		(net 42)
	)
	(segment
		(start 149.295029 95.388326)
		(end 149.33391 95.349445)
		(width 0.1016)
		(layer "In2.Cu")
		(net 42)
	)
	(segment
		(start 147.029385 93.822818)
		(end 147.057197 93.822818)
		(width 0.1016)
		(layer "In2.Cu")
		(net 42)
	)
	(segment
		(start 149.216542 95.450918)
		(end 149.295029 95.388326)
		(width 0.1016)
		(layer "In2.Cu")
		(net 42)
	)
	(segment
		(start 149.462397 94.98225)
		(end 149.440059 94.884378)
		(width 0.1016)
		(layer "In2.Cu")
		(net 42)
	)
	(segment
		(start 146.8508 96.959949)
		(end 146.8508 95.89782)
		(width 0.1016)
		(layer "In2.Cu")
		(net 42)
	)
	(segment
		(start 146.8508 95.89782)
		(end 147.074309 95.674309)
		(width 0.1016)
		(layer "In2.Cu")
		(net 42)
	)
	(segment
		(start 147.096053 95.656968)
		(end 147.121111 95.644901)
		(width 0.1016)
		(layer "In2.Cu")
		(net 42)
	)
	(segment
		(start 148.277566 96.343002)
		(end 148.368013 96.299445)
		(width 0.1016)
		(layer "In2.Cu")
		(net 42)
	)
	(segment
		(start 148.735768 94.051169)
		(end 148.741957 94.024055)
		(width 0.1016)
		(layer "In2.Cu")
		(net 42)
	)
	(segment
		(start 148.613868 95.830777)
		(end 148.59153 95.732905)
		(width 0.1016)
		(layer "In2.Cu")
		(net 42)
	)
	(segment
		(start 148.739515 95.450918)
		(end 148.829962 95.494475)
		(width 0.1016)
		(layer "In2.Cu")
		(net 42)
	)
	(segment
		(start 148.754024 94.131154)
		(end 148.741957 94.106096)
		(width 0.1016)
		(layer "In2.Cu")
		(net 42)
	)
	(segment
		(start 147.812499 96.236854)
		(end 147.890986 96.299445)
		(width 0.1016)
		(layer "In2.Cu")
		(net 42)
	)
	(segment
		(start 148.613868 95.931166)
		(end 148.613868 95.830777)
		(width 0.1016)
		(layer "In2.Cu")
		(net 42)
	)
	(segment
		(start 146.926062 93.987256)
		(end 146.919872 93.960143)
		(width 0.1016)
		(layer "In2.Cu")
		(net 42)
	)
	(segment
		(start 149.396502 95.270958)
		(end 149.440059 95.18051)
		(width 0.1016)
		(layer "In2.Cu")
		(net 42)
	)
	(segment
		(start 146.938128 94.012315)
		(end 146.926062 93.987256)
		(width 0.1016)
		(layer "In2.Cu")
		(net 42)
	)
	(segment
		(start 147.249954 95.674309)
		(end 147.812499 96.236854)
		(width 0.1016)
		(layer "In2.Cu")
		(net 42)
	)
	(segment
		(start 146.926061 93.905216)
		(end 146.938129 93.880157)
		(width 0.1016)
		(layer "In2.Cu")
		(net 42)
	)
	(segment
		(start 148.547973 96.119485)
		(end 148.59153 96.029037)
		(width 0.1016)
		(layer "In2.Cu")
		(net 42)
	)
	(segment
		(start 148.079305 96.365341)
		(end 148.179694 96.365341)
		(width 0.1016)
		(layer "In2.Cu")
		(net 42)
	)
	(segment
		(start 149.440059 94.884378)
		(end 149.396502 94.793931)
		(width 0.1016)
		(layer "In2.Cu")
		(net 42)
	)
	(segment
		(start 149.396502 94.793931)
		(end 149.33391 94.715443)
		(width 0.1016)
		(layer "In2.Cu")
		(net 42)
	)
	(segment
		(start 147.176038 95.638712)
		(end 147.203152 95.644901)
		(width 0.1016)
		(layer "In2.Cu")
		(net 42)
	)
	(segment
		(start 151.0008 86.409949)
		(end 151.1008 86.309949)
		(width 0.1016)
		(layer "In2.Cu")
		(net 42)
	)
	(segment
		(start 148.771365 93.977252)
		(end 151.0008 91.74782)
		(width 0.1016)
		(layer "In2.Cu")
		(net 42)
	)
	(segment
		(start 147.074309 95.674309)
		(end 147.096053 95.656968)
		(width 0.1016)
		(layer "In2.Cu")
		(net 42)
	)
	(segment
		(start 143.575 95.225)
		(end 143.575 92.3)
		(width 0.145)
		(layer "F.Cu")
		(net 43)
	)
	(segment
		(start 144.775899 96.941569)
		(end 144.775899 96.425899)
		(width 0.145)
		(layer "F.Cu")
		(net 43)
	)
	(segment
		(start 144.775899 96.425899)
		(end 143.575 95.225)
		(width 0.145)
		(layer "F.Cu")
		(net 43)
	)
	(segment
		(start 144.925 98.7)
		(end 144.925 97.09067)
		(width 0.145)
		(layer "F.Cu")
		(net 43)
	)
	(segment
		(start 148.025 83.65)
		(end 148.025 84.21)
		(width 0.145)
		(layer "F.Cu")
		(net 43)
	)
	(segment
		(start 144.925 97.09067)
		(end 144.775899 96.941569)
		(width 0.145)
		(layer "F.Cu")
		(net 43)
	)
	(via
		(at 143.575 92.3)
		(size 0.45)
		(drill 0.15)
		(layers "F.Cu" "B.Cu")
		(net 43)
	)
	(via
		(at 148.025 84.21)
		(size 0.45)
		(drill 0.15)
		(layers "F.Cu" "B.Cu")
		(net 43)
	)
	(segment
		(start 143.661679 86.211377)
		(end 143.645902 86.2096)
		(width 0.1016)
		(layer "In2.Cu")
		(net 43)
	)
	(segment
		(start 143.448665 85.772406)
		(end 143.440218 85.758962)
		(width 0.1016)
		(layer "In2.Cu")
		(net 43)
	)
	(segment
		(start 143.434974 87.687124)
		(end 143.440218 87.672138)
		(width 0.1016)
		(layer "In2.Cu")
		(net 43)
	)
	(segment
		(start 143.716803 86.341899)
		(end 143.716803 86.280501)
		(width 0.1016)
		(layer "In2.Cu")
		(net 43)
	)
	(segment
		(start 143.534861 85.588879)
		(end 143.548305 85.580432)
		(width 0.1016)
		(layer "In2.Cu")
		(net 43)
	)
	(segment
		(start 143.690109 86.803731)
		(end 143.701335 86.792505)
		(width 0.1016)
		(layer "In2.Cu")
		(net 43)
	)
	(segment
		(start 143.573222 85.540776)
		(end 143.575 85.525)
		(width 0.1016)
		(layer "In2.Cu")
		(net 43)
	)
	(segment
		(start 143.448665 87.658694)
		(end 143.459891 87.647468)
		(width 0.1016)
		(layer "In2.Cu")
		(net 43)
	)
	(segment
		(start 143.504098 86.616)
		(end 143.488321 86.614222)
		(width 0.1016)
		(layer "In2.Cu")
		(net 43)
	)
	(segment
		(start 143.434974 86.874324)
		(end 143.440218 86.859338)
		(width 0.1016)
		(layer "In2.Cu")
		(net 43)
	)
	(segment
		(start 143.701335 87.049094)
		(end 143.690109 87.037868)
		(width 0.1016)
		(layer "In2.Cu")
		(net 43)
	)
	(segment
		(start 143.488321 86.207822)
		(end 143.473335 86.202578)
		(width 0.1016)
		(layer "In2.Cu")
		(net 43)
	)
	(segment
		(start 143.575 85.525)
		(end 143.575 85.35)
		(width 0.1016)
		(layer "In2.Cu")
		(net 43)
	)
	(segment
		(start 143.440218 87.388661)
		(end 143.434974 87.373675)
		(width 0.1016)
		(layer "In2.Cu")
		(net 43)
	)
	(segment
		(start 143.440218 86.452938)
		(end 143.448665 86.439494)
		(width 0.1016)
		(layer "In2.Cu")
		(net 43)
	)
	(segment
		(start 143.488321 85.597678)
		(end 143.519875 85.594123)
		(width 0.1016)
		(layer "In2.Cu")
		(net 43)
	)
	(segment
		(start 143.459891 85.783632)
		(end 143.448665 85.772406)
		(width 0.1016)
		(layer "In2.Cu")
		(net 43)
	)
	(segment
		(start 143.715026 87.483924)
		(end 143.709782 87.468938)
		(width 0.1016)
		(layer "In2.Cu")
		(net 43)
	)
	(segment
		(start 143.459891 87.241068)
		(end 143.473335 87.232621)
		(width 0.1016)
		(layer "In2.Cu")
		(net 43)
	)
	(segment
		(start 143.716803 86.686901)
		(end 143.715026 86.671124)
		(width 0.1016)
		(layer "In2.Cu")
		(net 43)
	)
	(segment
		(start 143.434974 87.280724)
		(end 143.440218 87.265738)
		(width 0.1016)
		(layer "In2.Cu")
		(net 43)
	)
	(segment
		(start 143.559531 87.861894)
		(end 143.548305 87.850668)
		(width 0.1016)
		(layer "In2.Cu")
		(net 43)
	)
	(segment
		(start 143.701335 85.979705)
		(end 143.709782 85.966261)
		(width 0.1016)
		(layer "In2.Cu")
		(net 43)
	)
	(segment
		(start 143.448665 86.995705)
		(end 143.440218 86.982261)
		(width 0.1016)
		(layer "In2.Cu")
		(net 43)
	)
	(segment
		(start 143.645902 87.0224)
		(end 143.504098 87.0224)
		(width 0.1016)
		(layer "In2.Cu")
		(net 43)
	)
	(segment
		(start 143.488321 86.820977)
		(end 143.504098 86.8192)
		(width 0.1016)
		(layer "In2.Cu")
		(net 43)
	)
	(segment
		(start 143.504098 87.4288)
		(end 143.488321 87.427022)
		(width 0.1016)
		(layer "In2.Cu")
		(net 43)
	)
	(segment
		(start 143.676665 86.216621)
		(end 143.661679 86.211377)
		(width 0.1016)
		(layer "In2.Cu")
		(net 43)
	)
	(segment
		(start 143.661679 85.804977)
		(end 143.645902 85.8032)
		(width 0.1016)
		(layer "In2.Cu")
		(net 43)
	)
	(segment
		(start 143.645902 87.2256)
		(end 143.661679 87.223822)
		(width 0.1016)
		(layer "In2.Cu")
		(net 43)
	)
	(segment
		(start 143.433197 87.296501)
		(end 143.434974 87.280724)
		(width 0.1016)
		(layer "In2.Cu")
		(net 43)
	)
	(segment
		(start 143.701335 86.792505)
		(end 143.709782 86.779061)
		(width 0.1016)
		(layer "In2.Cu")
		(net 43)
	)
	(segment
		(start 143.473335 87.639021)
		(end 143.488321 87.633777)
		(width 0.1016)
		(layer "In2.Cu")
		(net 43)
	)
	(segment
		(start 143.459891 87.413331)
		(end 143.448665 87.402105)
		(width 0.1016)
		(layer "In2.Cu")
		(net 43)
	)
	(segment
		(start 143.676665 85.999378)
		(end 143.690109 85.990931)
		(width 0.1016)
		(layer "In2.Cu")
		(net 43)
	)
	(segment
		(start 143.504098 86.2096)
		(end 143.488321 86.207822)
		(width 0.1016)
		(layer "In2.Cu")
		(net 43)
	)
	(segment
		(start 143.448665 86.182905)
		(end 143.440218 86.169461)
		(width 0.1016)
		(layer "In2.Cu")
		(net 43)
	)
	(segment
		(start 143.690109 85.818668)
		(end 143.676665 85.810221)
		(width 0.1016)
		(layer "In2.Cu")
		(net 43)
	)
	(segment
		(start 143.575 85.799101)
		(end 143.504099 85.799101)
		(width 0.1016)
		(layer "In2.Cu")
		(net 43)
	)
	(segment
		(start 143.473335 86.202578)
		(end 143.459891 86.194131)
		(width 0.1016)
		(layer "In2.Cu")
		(net 43)
	)
	(segment
		(start 143.433197 86.951499)
		(end 143.433197 86.890101)
		(width 0.1016)
		(layer "In2.Cu")
		(net 43)
	)
	(segment
		(start 143.488321 85.797323)
		(end 143.473335 85.792079)
		(width 0.1016)
		(layer "In2.Cu")
		(net 43)
	)
	(segment
		(start 143.434974 86.467924)
		(end 143.440218 86.452938)
		(width 0.1016)
		(layer "In2.Cu")
		(net 43)
	)
	(segment
		(start 143.645902 85.8032)
		(end 143.575 85.8032)
		(width 0.1016)
		(layer "In2.Cu")
		(net 43)
	)
	(segment
		(start 143.440218 86.575861)
		(end 143.434974 86.560875)
		(width 0.1016)
		(layer "In2.Cu")
		(net 43)
	)
	(segment
		(start 143.559531 85.569206)
		(end 143.567978 85.555762)
		(width 0.1016)
		(layer "In2.Cu")
		(net 43)
	)
	(segment
		(start 143.709782 86.656138)
		(end 143.701335 86.642694)
		(width 0.1016)
		(layer "In2.Cu")
		(net 43)
	)
	(segment
		(start 143.488321 86.414577)
		(end 143.504098 86.4128)
		(width 0.1016)
		(layer "In2.Cu")
		(net 43)
	)
	(segment
		(start 143.548305 87.850668)
		(end 143.534861 87.842221)
		(width 0.1016)
		(layer "In2.Cu")
		(net 43)
	)
	(segment
		(start 143.709782 86.249738)
		(end 143.701335 86.236294)
		(width 0.1016)
		(layer "In2.Cu")
		(net 43)
	)
	(segment
		(start 148.025 84.68716)
		(end 148.025 84.21)
		(width 0.1016)
		(layer "In2.Cu")
		(net 43)
	)
	(segment
		(start 143.701335 85.829894)
		(end 143.690109 85.818668)
		(width 0.1016)
		(layer "In2.Cu")
		(net 43)
	)
	(segment
		(start 143.488321 87.227377)
		(end 143.504098 87.2256)
		(width 0.1016)
		(layer "In2.Cu")
		(net 43)
	)
	(segment
		(start 143.440218 86.982261)
		(end 143.434974 86.967275)
		(width 0.1016)
		(layer "In2.Cu")
		(net 43)
	)
	(segment
		(start 143.504098 87.632)
		(end 143.645902 87.632)
		(width 0.1016)
		(layer "In2.Cu")
		(net 43)
	)
	(segment
		(start 143.715026 86.264724)
		(end 143.709782 86.249738)
		(width 0.1016)
		(layer "In2.Cu")
		(net 43)
	)
	(segment
		(start 143.690109 87.616531)
		(end 143.701335 87.605305)
		(width 0.1016)
		(layer "In2.Cu")
		(net 43)
	)
	(segment
		(start 143.575 85.8032)
		(end 143.575 85.799101)
		(width 0.1016)
		(layer "In2.Cu")
		(net 43)
	)
	(segment
		(start 143.488321 86.008177)
		(end 143.504098 86.0064)
		(width 0.1016)
		(layer "In2.Cu")
		(net 43)
	)
	(segment
		(start 143.473335 86.826221)
		(end 143.488321 86.820977)
		(width 0.1016)
		(layer "In2.Cu")
		(net 43)
	)
	(segment
		(start 143.534861 87.842221)
		(end 143.519875 87.836977)
		(width 0.1016)
		(layer "In2.Cu")
		(net 43)
	)
	(segment
		(start 143.433197 85.666802)
		(end 143.434974 85.651025)
		(width 0.1016)
		(layer "In2.Cu")
		(net 43)
	)
	(segment
		(start 143.488321 86.614222)
		(end 143.473335 86.608978)
		(width 0.1016)
		(layer "In2.Cu")
		(net 43)
	)
	(segment
		(start 143.709782 85.843338)
		(end 143.701335 85.829894)
		(width 0.1016)
		(layer "In2.Cu")
		(net 43)
	)
	(segment
		(start 143.433197 86.077301)
		(end 143.434974 86.061524)
		(width 0.1016)
		(layer "In2.Cu")
		(net 43)
	)
	(segment
		(start 143.567978 87.875338)
		(end 143.559531 87.861894)
		(width 0.1016)
		(layer "In2.Cu")
		(net 43)
	)
	(segment
		(start 143.440218 85.758962)
		(end 143.434974 85.743976)
		(width 0.1016)
		(layer "In2.Cu")
		(net 43)
	)
	(segment
		(start 143.459891 87.647468)
		(end 143.473335 87.639021)
		(width 0.1016)
		(layer "In2.Cu")
		(net 43)
	)
	(segment
		(start 143.473335 86.013421)
		(end 143.488321 86.008177)
		(width 0.1016)
		(layer "In2.Cu")
		(net 43)
	)
	(segment
		(start 143.690109 87.210131)
		(end 143.701335 87.198905)
		(width 0.1016)
		(layer "In2.Cu")
		(net 43)
	)
	(segment
		(start 143.459891 87.006931)
		(end 143.448665 86.995705)
		(width 0.1016)
		(layer "In2.Cu")
		(net 43)
	)
	(segment
		(start 143.716803 87.499701)
		(end 143.715026 87.483924)
		(width 0.1016)
		(layer "In2.Cu")
		(net 43)
	)
	(segment
		(start 143.567978 85.555762)
		(end 143.573222 85.540776)
		(width 0.1016)
		(layer "In2.Cu")
		(net 43)
	)
	(segment
		(start 143.434974 86.154475)
		(end 143.433197 86.138699)
		(width 0.1016)
		(layer "In2.Cu")
		(net 43)
	)
	(segment
		(start 143.440218 87.265738)
		(end 143.448665 87.252294)
		(width 0.1016)
		(layer "In2.Cu")
		(net 43)
	)
	(segment
		(start 143.709782 87.468938)
		(end 143.701335 87.455494)
		(width 0.1016)
		(layer "In2.Cu")
		(net 43)
	)
	(segment
		(start 143.676665 87.218578)
		(end 143.690109 87.210131)
		(width 0.1016)
		(layer "In2.Cu")
		(net 43)
	)
	(segment
		(start 143.645902 86.0064)
		(end 143.661679 86.004622)
		(width 0.1016)
		(layer "In2.Cu")
		(net 43)
	)
	(segment
		(start 143.440218 85.636039)
		(end 143.448665 85.622595)
		(width 0.1016)
		(layer "In2.Cu")
		(net 43)
	)
	(segment
		(start 143.701335 86.236294)
		(end 143.690109 86.225068)
		(width 0.1016)
		(layer "In2.Cu")
		(net 43)
	)
	(segment
		(start 143.433197 86.483701)
		(end 143.434974 86.467924)
		(width 0.1016)
		(layer "In2.Cu")
		(net 43)
	)
	(segment
		(start 143.645902 86.616)
		(end 143.504098 86.616)
		(width 0.1016)
		(layer "In2.Cu")
		(net 43)
	)
	(segment
		(start 143.434974 86.061524)
		(end 143.440218 86.046538)
		(width 0.1016)
		(layer "In2.Cu")
		(net 43)
	)
	(segment
		(start 143.433197 87.357899)
		(end 143.433197 87.296501)
		(width 0.1016)
		(layer "In2.Cu")
		(net 43)
	)
	(segment
		(start 143.98784 84.93716)
		(end 147.775 84.93716)
		(width 0.1016)
		(layer "In2.Cu")
		(net 43)
	)
	(segment
		(start 143.433197 87.702901)
		(end 143.434974 87.687124)
		(width 0.1016)
		(layer "In2.Cu")
		(net 43)
	)
	(segment
		(start 143.448665 86.439494)
		(end 143.459891 86.428268)
		(width 0.1016)
		(layer "In2.Cu")
		(net 43)
	)
	(segment
		(start 143.715026 87.170475)
		(end 143.716803 87.154699)
		(width 0.1016)
		(layer "In2.Cu")
		(net 43)
	)
	(segment
		(start 143.716803 85.874101)
		(end 143.715026 85.858324)
		(width 0.1016)
		(layer "In2.Cu")
		(net 43)
	)
	(segment
		(start 143.661679 86.617777)
		(end 143.645902 86.616)
		(width 0.1016)
		(layer "In2.Cu")
		(net 43)
	)
	(segment
		(start 143.716803 86.748299)
		(end 143.716803 86.686901)
		(width 0.1016)
		(layer "In2.Cu")
		(net 43)
	)
	(segment
		(start 143.701335 87.605305)
		(end 143.709782 87.591861)
		(width 0.1016)
		(layer "In2.Cu")
		(net 43)
	)
	(segment
		(start 143.434974 85.651025)
		(end 143.440218 85.636039)
		(width 0.1016)
		(layer "In2.Cu")
		(net 43)
	)
	(segment
		(start 143.575 85.35)
		(end 143.98784 84.93716)
		(width 0.1016)
		(layer "In2.Cu")
		(net 43)
	)
	(segment
		(start 143.701335 87.455494)
		(end 143.690109 87.444268)
		(width 0.1016)
		(layer "In2.Cu")
		(net 43)
	)
	(segment
		(start 143.440218 87.672138)
		(end 143.448665 87.658694)
		(width 0.1016)
		(layer "In2.Cu")
		(net 43)
	)
	(segment
		(start 143.488321 87.633777)
		(end 143.504098 87.632)
		(width 0.1016)
		(layer "In2.Cu")
		(net 43)
	)
	(segment
		(start 143.575 92.3)
		(end 143.575 87.906101)
		(width 0.1016)
		(layer "In2.Cu")
		(net 43)
	)
	(segment
		(start 143.575 87.906101)
		(end 143.573222 87.890324)
		(width 0.1016)
		(layer "In2.Cu")
		(net 43)
	)
	(segment
		(start 143.433197 86.545099)
		(end 143.433197 86.483701)
		(width 0.1016)
		(layer "In2.Cu")
		(net 43)
	)
	(segment
		(start 143.440218 86.169461)
		(end 143.434974 86.154475)
		(width 0.1016)
		(layer "In2.Cu")
		(net 43)
	)
	(segment
		(start 143.709782 87.062538)
		(end 143.701335 87.049094)
		(width 0.1016)
		(layer "In2.Cu")
		(net 43)
	)
	(segment
		(start 143.434974 87.780075)
		(end 143.433197 87.764299)
		(width 0.1016)
		(layer "In2.Cu")
		(net 43)
	)
	(segment
		(start 143.709782 87.591861)
		(end 143.715026 87.576875)
		(width 0.1016)
		(layer "In2.Cu")
		(net 43)
	)
	(segment
		(start 143.690109 86.397331)
		(end 143.701335 86.386105)
		(width 0.1016)
		(layer "In2.Cu")
		(net 43)
	)
	(segment
		(start 143.661679 87.024177)
		(end 143.645902 87.0224)
		(width 0.1016)
		(layer "In2.Cu")
		(net 43)
	)
	(segment
		(start 143.548305 85.580432)
		(end 143.559531 85.569206)
		(width 0.1016)
		(layer "In2.Cu")
		(net 43)
	)
	(segment
		(start 143.709782 86.779061)
		(end 143.715026 86.764075)
		(width 0.1016)
		(layer "In2.Cu")
		(net 43)
	)
	(segment
		(start 143.715026 85.858324)
		(end 143.709782 85.843338)
		(width 0.1016)
		(layer "In2.Cu")
		(net 43)
	)
	(segment
		(start 143.715026 86.764075)
		(end 143.716803 86.748299)
		(width 0.1016)
		(layer "In2.Cu")
		(net 43)
	)
	(segment
		(start 143.473335 87.828178)
		(end 143.459891 87.819731)
		(width 0.1016)
		(layer "In2.Cu")
		(net 43)
	)
	(segment
		(start 143.433197 87.764299)
		(end 143.433197 87.702901)
		(width 0.1016)
		(layer "In2.Cu")
		(net 43)
	)
	(segment
		(start 143.690109 86.225068)
		(end 143.676665 86.216621)
		(width 0.1016)
		(layer "In2.Cu")
		(net 43)
	)
	(segment
		(start 143.459891 86.021868)
		(end 143.473335 86.013421)
		(width 0.1016)
		(layer "In2.Cu")
		(net 43)
	)
	(segment
		(start 143.473335 87.015378)
		(end 143.459891 87.006931)
		(width 0.1016)
		(layer "In2.Cu")
		(net 43)
	)
	(segment
		(start 143.488321 87.833422)
		(end 143.473335 87.828178)
		(width 0.1016)
		(layer "In2.Cu")
		(net 43)
	)
	(segment
		(start 143.459891 85.611369)
		(end 143.473335 85.602922)
		(width 0.1016)
		(layer "In2.Cu")
		(net 43)
	)
	(segment
		(start 143.709782 85.966261)
		(end 143.715026 85.951275)
		(width 0.1016)
		(layer "In2.Cu")
		(net 43)
	)
	(segment
		(start 143.473335 87.232621)
		(end 143.488321 87.227377)
		(width 0.1016)
		(layer "In2.Cu")
		(net 43)
	)
	(segment
		(start 143.473335 86.608978)
		(end 143.459891 86.600531)
		(width 0.1016)
		(layer "In2.Cu")
		(net 43)
	)
	(segment
		(start 143.519875 87.836977)
		(end 143.488321 87.833422)
		(width 0.1016)
		(layer "In2.Cu")
		(net 43)
	)
	(segment
		(start 143.440218 86.859338)
		(end 143.448665 86.845894)
		(width 0.1016)
		(layer "In2.Cu")
		(net 43)
	)
	(segment
		(start 143.459891 87.819731)
		(end 143.448665 87.808505)
		(width 0.1016)
		(layer "In2.Cu")
		(net 43)
	)
	(segment
		(start 143.433197 86.138699)
		(end 143.433197 86.077301)
		(width 0.1016)
		(layer "In2.Cu")
		(net 43)
	)
	(segment
		(start 143.434974 85.743976)
		(end 143.433197 85.7282)
		(width 0.1016)
		(layer "In2.Cu")
		(net 43)
	)
	(segment
		(start 143.690109 85.990931)
		(end 143.701335 85.979705)
		(width 0.1016)
		(layer "In2.Cu")
		(net 43)
	)
	(segment
		(start 143.504098 86.8192)
		(end 143.645902 86.8192)
		(width 0.1016)
		(layer "In2.Cu")
		(net 43)
	)
	(segment
		(start 143.661679 87.630222)
		(end 143.676665 87.624978)
		(width 0.1016)
		(layer "In2.Cu")
		(net 43)
	)
	(segment
		(start 143.661679 87.223822)
		(end 143.676665 87.218578)
		(width 0.1016)
		(layer "In2.Cu")
		(net 43)
	)
	(segment
		(start 143.448665 86.589305)
		(end 143.440218 86.575861)
		(width 0.1016)
		(layer "In2.Cu")
		(net 43)
	)
	(segment
		(start 143.676665 87.029421)
		(end 143.661679 87.024177)
		(width 0.1016)
		(layer "In2.Cu")
		(net 43)
	)
	(segment
		(start 143.459891 86.428268)
		(end 143.473335 86.419821)
		(width 0.1016)
		(layer "In2.Cu")
		(net 43)
	)
	(segment
		(start 143.433197 86.890101)
		(end 143.434974 86.874324)
		(width 0.1016)
		(layer "In2.Cu")
		(net 43)
	)
	(segment
		(start 143.661679 86.817422)
		(end 143.676665 86.812178)
		(width 0.1016)
		(layer "In2.Cu")
		(net 43)
	)
	(segment
		(start 143.676665 86.405778)
		(end 143.690109 86.397331)
		(width 0.1016)
		(layer "In2.Cu")
		(net 43)
	)
	(segment
		(start 143.676665 86.812178)
		(end 143.690109 86.803731)
		(width 0.1016)
		(layer "In2.Cu")
		(net 43)
	)
	(segment
		(start 143.504098 87.2256)
		(end 143.645902 87.2256)
		(width 0.1016)
		(layer "In2.Cu")
		(net 43)
	)
	(segment
		(start 143.504098 87.0224)
		(end 143.488321 87.020622)
		(width 0.1016)
		(layer "In2.Cu")
		(net 43)
	)
	(segment
		(start 143.448665 86.845894)
		(end 143.459891 86.834668)
		(width 0.1016)
		(layer "In2.Cu")
		(net 43)
	)
	(segment
		(start 143.434974 86.967275)
		(end 143.433197 86.951499)
		(width 0.1016)
		(layer "In2.Cu")
		(net 43)
	)
	(segment
		(start 143.473335 87.421778)
		(end 143.459891 87.413331)
		(width 0.1016)
		(layer "In2.Cu")
		(net 43)
	)
	(segment
		(start 143.519875 85.594123)
		(end 143.534861 85.588879)
		(width 0.1016)
		(layer "In2.Cu")
		(net 43)
	)
	(segment
		(start 143.434974 87.373675)
		(end 143.433197 87.357899)
		(width 0.1016)
		(layer "In2.Cu")
		(net 43)
	)
	(segment
		(start 143.459891 86.600531)
		(end 143.448665 86.589305)
		(width 0.1016)
		(layer "In2.Cu")
		(net 43)
	)
	(segment
		(start 143.573222 87.890324)
		(end 143.567978 87.875338)
		(width 0.1016)
		(layer "In2.Cu")
		(net 43)
	)
	(segment
		(start 143.715026 85.951275)
		(end 143.716803 85.935499)
		(width 0.1016)
		(layer "In2.Cu")
		(net 43)
	)
	(segment
		(start 143.645902 86.4128)
		(end 143.661679 86.411022)
		(width 0.1016)
		(layer "In2.Cu")
		(net 43)
	)
	(segment
		(start 143.448665 87.402105)
		(end 143.440218 87.388661)
		(width 0.1016)
		(layer "In2.Cu")
		(net 43)
	)
	(segment
		(start 143.645902 87.4288)
		(end 143.504098 87.4288)
		(width 0.1016)
		(layer "In2.Cu")
		(net 43)
	)
	(segment
		(start 143.645902 86.2096)
		(end 143.504098 86.2096)
		(width 0.1016)
		(layer "In2.Cu")
		(net 43)
	)
	(segment
		(start 143.504098 86.4128)
		(end 143.645902 86.4128)
		(width 0.1016)
		(layer "In2.Cu")
		(net 43)
	)
	(segment
		(start 143.676665 87.435821)
		(end 143.661679 87.430577)
		(width 0.1016)
		(layer "In2.Cu")
		(net 43)
	)
	(segment
		(start 143.488321 87.020622)
		(end 143.473335 87.015378)
		(width 0.1016)
		(layer "In2.Cu")
		(net 43)
	)
	(segment
		(start 143.488321 87.427022)
		(end 143.473335 87.421778)
		(width 0.1016)
		(layer "In2.Cu")
		(net 43)
	)
	(segment
		(start 143.701335 86.386105)
		(end 143.709782 86.372661)
		(width 0.1016)
		(layer "In2.Cu")
		(net 43)
	)
	(segment
		(start 143.716803 87.561099)
		(end 143.716803 87.499701)
		(width 0.1016)
		(layer "In2.Cu")
		(net 43)
	)
	(segment
		(start 143.504098 86.0064)
		(end 143.645902 86.0064)
		(width 0.1016)
		(layer "In2.Cu")
		(net 43)
	)
	(segment
		(start 143.716803 86.280501)
		(end 143.715026 86.264724)
		(width 0.1016)
		(layer "In2.Cu")
		(net 43)
	)
	(segment
		(start 143.701335 87.198905)
		(end 143.709782 87.185461)
		(width 0.1016)
		(layer "In2.Cu")
		(net 43)
	)
	(segment
		(start 143.645902 86.8192)
		(end 143.661679 86.817422)
		(width 0.1016)
		(layer "In2.Cu")
		(net 43)
	)
	(segment
		(start 143.448665 86.033094)
		(end 143.459891 86.021868)
		(width 0.1016)
		(layer "In2.Cu")
		(net 43)
	)
	(segment
		(start 143.709782 86.372661)
		(end 143.715026 86.357675)
		(width 0.1016)
		(layer "In2.Cu")
		(net 43)
	)
	(segment
		(start 143.690109 87.444268)
		(end 143.676665 87.435821)
		(width 0.1016)
		(layer "In2.Cu")
		(net 43)
	)
	(segment
		(start 143.504099 85.799101)
		(end 143.488321 85.797323)
		(width 0.1016)
		(layer "In2.Cu")
		(net 43)
	)
	(segment
		(start 143.661679 87.430577)
		(end 143.645902 87.4288)
		(width 0.1016)
		(layer "In2.Cu")
		(net 43)
	)
	(segment
		(start 143.661679 86.004622)
		(end 143.676665 85.999378)
		(width 0.1016)
		(layer "In2.Cu")
		(net 43)
	)
	(segment
		(start 143.715026 87.077524)
		(end 143.709782 87.062538)
		(width 0.1016)
		(layer "In2.Cu")
		(net 43)
	)
	(segment
		(start 143.716803 87.154699)
		(end 143.716803 87.093301)
		(width 0.1016)
		(layer "In2.Cu")
		(net 43)
	)
	(segment
		(start 143.433197 85.7282)
		(end 143.433197 85.666802)
		(width 0.1016)
		(layer "In2.Cu")
		(net 43)
	)
	(segment
		(start 143.715026 86.671124)
		(end 143.709782 86.656138)
		(width 0.1016)
		(layer "In2.Cu")
		(net 43)
	)
	(segment
		(start 143.459891 86.194131)
		(end 143.448665 86.182905)
		(width 0.1016)
		(layer "In2.Cu")
		(net 43)
	)
	(segment
		(start 143.473335 85.792079)
		(end 143.459891 85.783632)
		(width 0.1016)
		(layer "In2.Cu")
		(net 43)
	)
	(segment
		(start 143.676665 85.810221)
		(end 143.661679 85.804977)
		(width 0.1016)
		(layer "In2.Cu")
		(net 43)
	)
	(segment
		(start 143.459891 86.834668)
		(end 143.473335 86.826221)
		(width 0.1016)
		(layer "In2.Cu")
		(net 43)
	)
	(segment
		(start 143.448665 87.252294)
		(end 143.459891 87.241068)
		(width 0.1016)
		(layer "In2.Cu")
		(net 43)
	)
	(segment
		(start 143.645902 87.632)
		(end 143.661679 87.630222)
		(width 0.1016)
		(layer "In2.Cu")
		(net 43)
	)
	(segment
		(start 143.434974 86.560875)
		(end 143.433197 86.545099)
		(width 0.1016)
		(layer "In2.Cu")
		(net 43)
	)
	(segment
		(start 147.775 84.93716)
		(end 148.025 84.68716)
		(width 0.1016)
		(layer "In2.Cu")
		(net 43)
	)
	(segment
		(start 143.701335 86.642694)
		(end 143.690109 86.631468)
		(width 0.1016)
		(layer "In2.Cu")
		(net 43)
	)
	(segment
		(start 143.715026 87.576875)
		(end 143.716803 87.561099)
		(width 0.1016)
		(layer "In2.Cu")
		(net 43)
	)
	(segment
		(start 143.440218 86.046538)
		(end 143.448665 86.033094)
		(width 0.1016)
		(layer "In2.Cu")
		(net 43)
	)
	(segment
		(start 143.473335 86.419821)
		(end 143.488321 86.414577)
		(width 0.1016)
		(layer "In2.Cu")
		(net 43)
	)
	(segment
		(start 143.661679 86.411022)
		(end 143.676665 86.405778)
		(width 0.1016)
		(layer "In2.Cu")
		(net 43)
	)
	(segment
		(start 143.440218 87.795061)
		(end 143.434974 87.780075)
		(width 0.1016)
		(layer "In2.Cu")
		(net 43)
	)
	(segment
		(start 143.690109 87.037868)
		(end 143.676665 87.029421)
		(width 0.1016)
		(layer "In2.Cu")
		(net 43)
	)
	(segment
		(start 143.715026 86.357675)
		(end 143.716803 86.341899)
		(width 0.1016)
		(layer "In2.Cu")
		(net 43)
	)
	(segment
		(start 143.709782 87.185461)
		(end 143.715026 87.170475)
		(width 0.1016)
		(layer "In2.Cu")
		(net 43)
	)
	(segment
		(start 143.473335 85.602922)
		(end 143.488321 85.597678)
		(width 0.1016)
		(layer "In2.Cu")
		(net 43)
	)
	(segment
		(start 143.690109 86.631468)
		(end 143.676665 86.623021)
		(width 0.1016)
		(layer "In2.Cu")
		(net 43)
	)
	(segment
		(start 143.448665 85.622595)
		(end 143.459891 85.611369)
		(width 0.1016)
		(layer "In2.Cu")
		(net 43)
	)
	(segment
		(start 143.676665 87.624978)
		(end 143.690109 87.616531)
		(width 0.1016)
		(layer "In2.Cu")
		(net 43)
	)
	(segment
		(start 143.448665 87.808505)
		(end 143.440218 87.795061)
		(width 0.1016)
		(layer "In2.Cu")
		(net 43)
	)
	(segment
		(start 143.676665 86.623021)
		(end 143.661679 86.617777)
		(width 0.1016)
		(layer "In2.Cu")
		(net 43)
	)
	(segment
		(start 143.716803 87.093301)
		(end 143.715026 87.077524)
		(width 0.1016)
		(layer "In2.Cu")
		(net 43)
	)
	(segment
		(start 143.716803 85.935499)
		(end 143.716803 85.874101)
		(width 0.1016)
		(layer "In2.Cu")
		(net 43)
	)
	(segment
		(start 146.425 98.7)
		(end 146.425 97.085749)
		(width 0.1016)
		(layer "F.Cu")
		(net 44)
	)
	(segment
		(start 146.425 97.085749)
		(end 146.3992 97.059949)
		(width 0.1016)
		(layer "F.Cu")
		(net 44)
	)
	(segment
		(start 150.5492 86.309949)
		(end 150.5492 86.7258)
		(width 0.1016)
		(layer "F.Cu")
		(net 44)
	)
	(segment
		(start 150.5492 86.7258)
		(end 150.425 86.85)
		(width 0.1016)
		(layer "F.Cu")
		(net 44)
	)
	(via
		(at 150.5492 86.309949)
		(size 0.45)
		(drill 0.15)
		(layers "F.Cu" "B.Cu")
		(net 44)
	)
	(via
		(at 146.3992 97.059949)
		(size 0.45)
		(drill 0.15)
		(layers "F.Cu" "B.Cu")
		(net 44)
	)
	(segment
		(start 148.440714 93.826561)
		(end 148.503305 93.748074)
		(width 0.1016)
		(layer "In2.Cu")
		(net 44)
	)
	(segment
		(start 148.374818 94.01488)
		(end 148.397157 93.917008)
		(width 0.1016)
		(layer "In2.Cu")
		(net 44)
	)
	(segment
		(start 148.374818 94.115269)
		(end 148.374818 94.01488)
		(width 0.1016)
		(layer "In2.Cu")
		(net 44)
	)
	(segment
		(start 146.581261 93.798169)
		(end 146.624818 93.707722)
		(width 0.1016)
		(layer "In2.Cu")
		(net 44)
	)
	(segment
		(start 149.083191 95.098522)
		(end 149.095258 95.073464)
		(width 0.1016)
		(layer "In2.Cu")
		(net 44)
	)
	(segment
		(start 146.4992 95.75218)
		(end 146.845131 95.406249)
		(width 0.1016)
		(layer "In2.Cu")
		(net 44)
	)
	(segment
		(start 148.217323 95.968794)
		(end 148.234663 95.947049)
		(width 0.1016)
		(layer "In2.Cu")
		(net 44)
	)
	(segment
		(start 146.3992 97.059949)
		(end 146.4992 96.959949)
		(width 0.1016)
		(layer "In2.Cu")
		(net 44)
	)
	(segment
		(start 148.991934 95.155863)
		(end 149.019049 95.149674)
		(width 0.1016)
		(layer "In2.Cu")
		(net 44)
	)
	(segment
		(start 146.558924 93.996429)
		(end 146.558923 93.896041)
		(width 0.1016)
		(layer "In2.Cu")
		(net 44)
	)
	(segment
		(start 148.24673 95.83995)
		(end 148.234663 95.814892)
		(width 0.1016)
		(layer "In2.Cu")
		(net 44)
	)
	(segment
		(start 148.503305 93.748074)
		(end 150.6492 91.60218)
		(width 0.1016)
		(layer "In2.Cu")
		(net 44)
	)
	(segment
		(start 146.923618 95.343658)
		(end 147.014065 95.300101)
		(width 0.1016)
		(layer "In2.Cu")
		(net 44)
	)
	(segment
		(start 148.890206 95.120267)
		(end 148.91195 95.137607)
		(width 0.1016)
		(layer "In2.Cu")
		(net 44)
	)
	(segment
		(start 148.503305 94.382075)
		(end 148.440714 94.303588)
		(width 0.1016)
		(layer "In2.Cu")
		(net 44)
	)
	(segment
		(start 149.095258 95.073464)
		(end 149.101447 95.04635)
		(width 0.1016)
		(layer "In2.Cu")
		(net 44)
	)
	(segment
		(start 148.937008 95.149674)
		(end 148.964122 95.155863)
		(width 0.1016)
		(layer "In2.Cu")
		(net 44)
	)
	(segment
		(start 148.115594 96.004391)
		(end 148.143406 96.004391)
		(width 0.1016)
		(layer "In2.Cu")
		(net 44)
	)
	(segment
		(start 146.558923 93.896041)
		(end 146.581261 93.798169)
		(width 0.1016)
		(layer "In2.Cu")
		(net 44)
	)
	(segment
		(start 146.687409 93.629236)
		(end 146.72629 93.590355)
		(width 0.1016)
		(layer "In2.Cu")
		(net 44)
	)
	(segment
		(start 146.804778 93.527762)
		(end 146.895225 93.484206)
		(width 0.1016)
		(layer "In2.Cu")
		(net 44)
	)
	(segment
		(start 149.095258 94.991423)
		(end 149.083191 94.966365)
		(width 0.1016)
		(layer "In2.Cu")
		(net 44)
	)
	(segment
		(start 148.041677 95.968794)
		(end 148.063421 95.986135)
		(width 0.1016)
		(layer "In2.Cu")
		(net 44)
	)
	(segment
		(start 148.195578 95.986135)
		(end 148.217323 95.968794)
		(width 0.1016)
		(layer "In2.Cu")
		(net 44)
	)
	(segment
		(start 146.993097 93.461867)
		(end 147.093485 93.461868)
		(width 0.1016)
		(layer "In2.Cu")
		(net 44)
	)
	(segment
		(start 148.234663 95.947049)
		(end 148.24673 95.921991)
		(width 0.1016)
		(layer "In2.Cu")
		(net 44)
	)
	(segment
		(start 147.212326 95.277762)
		(end 147.310198 95.300101)
		(width 0.1016)
		(layer "In2.Cu")
		(net 44)
	)
	(segment
		(start 146.72629 93.590355)
		(end 146.804778 93.527762)
		(width 0.1016)
		(layer "In2.Cu")
		(net 44)
	)
	(segment
		(start 149.065851 95.120267)
		(end 149.083191 95.098522)
		(width 0.1016)
		(layer "In2.Cu")
		(net 44)
	)
	(segment
		(start 148.063421 95.986135)
		(end 148.088479 95.998202)
		(width 0.1016)
		(layer "In2.Cu")
		(net 44)
	)
	(segment
		(start 148.91195 95.137607)
		(end 148.937008 95.149674)
		(width 0.1016)
		(layer "In2.Cu")
		(net 44)
	)
	(segment
		(start 148.397157 94.213141)
		(end 148.374818 94.115269)
		(width 0.1016)
		(layer "In2.Cu")
		(net 44)
	)
	(segment
		(start 148.217323 95.793148)
		(end 146.68741 94.263236)
		(width 0.1016)
		(layer "In2.Cu")
		(net 44)
	)
	(segment
		(start 149.083191 94.966365)
		(end 149.065851 94.944621)
		(width 0.1016)
		(layer "In2.Cu")
		(net 44)
	)
	(segment
		(start 147.400645 95.343658)
		(end 147.479132 95.406249)
		(width 0.1016)
		(layer "In2.Cu")
		(net 44)
	)
	(segment
		(start 147.281804 93.527763)
		(end 147.360292 93.590355)
		(width 0.1016)
		(layer "In2.Cu")
		(net 44)
	)
	(segment
		(start 148.252919 95.867065)
		(end 148.24673 95.83995)
		(width 0.1016)
		(layer "In2.Cu")
		(net 44)
	)
	(segment
		(start 148.143406 96.004391)
		(end 148.17052 95.998202)
		(width 0.1016)
		(layer "In2.Cu")
		(net 44)
	)
	(segment
		(start 148.397157 93.917008)
		(end 148.440714 93.826561)
		(width 0.1016)
		(layer "In2.Cu")
		(net 44)
	)
	(segment
		(start 149.065851 94.944621)
		(end 148.503305 94.382075)
		(width 0.1016)
		(layer "In2.Cu")
		(net 44)
	)
	(segment
		(start 148.440714 94.303588)
		(end 148.397157 94.213141)
		(width 0.1016)
		(layer "In2.Cu")
		(net 44)
	)
	(segment
		(start 148.252919 95.894877)
		(end 148.252919 95.867065)
		(width 0.1016)
		(layer "In2.Cu")
		(net 44)
	)
	(segment
		(start 150.6492 86.409949)
		(end 150.5492 86.309949)
		(width 0.1016)
		(layer "In2.Cu")
		(net 44)
	)
	(segment
		(start 149.019049 95.149674)
		(end 149.044107 95.137607)
		(width 0.1016)
		(layer "In2.Cu")
		(net 44)
	)
	(segment
		(start 147.111937 95.277762)
		(end 147.212326 95.277762)
		(width 0.1016)
		(layer "In2.Cu")
		(net 44)
	)
	(segment
		(start 147.479132 95.406249)
		(end 148.041677 95.968794)
		(width 0.1016)
		(layer "In2.Cu")
		(net 44)
	)
	(segment
		(start 148.234663 95.814892)
		(end 148.217323 95.793148)
		(width 0.1016)
		(layer "In2.Cu")
		(net 44)
	)
	(segment
		(start 148.964122 95.155863)
		(end 148.991934 95.155863)
		(width 0.1016)
		(layer "In2.Cu")
		(net 44)
	)
	(segment
		(start 146.624818 93.707722)
		(end 146.687409 93.629236)
		(width 0.1016)
		(layer "In2.Cu")
		(net 44)
	)
	(segment
		(start 148.088479 95.998202)
		(end 148.115594 96.004391)
		(width 0.1016)
		(layer "In2.Cu")
		(net 44)
	)
	(segment
		(start 146.4992 96.959949)
		(end 146.4992 95.75218)
		(width 0.1016)
		(layer "In2.Cu")
		(net 44)
	)
	(segment
		(start 149.101447 95.04635)
		(end 149.101447 95.018538)
		(width 0.1016)
		(layer "In2.Cu")
		(net 44)
	)
	(segment
		(start 149.044107 95.137607)
		(end 149.065851 95.120267)
		(width 0.1016)
		(layer "In2.Cu")
		(net 44)
	)
	(segment
		(start 146.895225 93.484206)
		(end 146.993097 93.461867)
		(width 0.1016)
		(layer "In2.Cu")
		(net 44)
	)
	(segment
		(start 147.360292 93.590355)
		(end 148.890206 95.120267)
		(width 0.1016)
		(layer "In2.Cu")
		(net 44)
	)
	(segment
		(start 149.101447 95.018538)
		(end 149.095258 94.991423)
		(width 0.1016)
		(layer "In2.Cu")
		(net 44)
	)
	(segment
		(start 146.581262 94.094301)
		(end 146.558924 93.996429)
		(width 0.1016)
		(layer "In2.Cu")
		(net 44)
	)
	(segment
		(start 146.68741 94.263236)
		(end 146.624819 94.184748)
		(width 0.1016)
		(layer "In2.Cu")
		(net 44)
	)
	(segment
		(start 150.6492 91.60218)
		(end 150.6492 86.409949)
		(width 0.1016)
		(layer "In2.Cu")
		(net 44)
	)
	(segment
		(start 147.014065 95.300101)
		(end 147.111937 95.277762)
		(width 0.1016)
		(layer "In2.Cu")
		(net 44)
	)
	(segment
		(start 148.17052 95.998202)
		(end 148.195578 95.986135)
		(width 0.1016)
		(layer "In2.Cu")
		(net 44)
	)
	(segment
		(start 146.845131 95.406249)
		(end 146.923618 95.343658)
		(width 0.1016)
		(layer "In2.Cu")
		(net 44)
	)
	(segment
		(start 147.093485 93.461868)
		(end 147.191357 93.484206)
		(width 0.1016)
		(layer "In2.Cu")
		(net 44)
	)
	(segment
		(start 146.624819 94.184748)
		(end 146.581262 94.094301)
		(width 0.1016)
		(layer "In2.Cu")
		(net 44)
	)
	(segment
		(start 147.310198 95.300101)
		(end 147.400645 95.343658)
		(width 0.1016)
		(layer "In2.Cu")
		(net 44)
	)
	(segment
		(start 147.191357 93.484206)
		(end 147.281804 93.527763)
		(width 0.1016)
		(layer "In2.Cu")
		(net 44)
	)
	(segment
		(start 148.24673 95.921991)
		(end 148.252919 95.894877)
		(width 0.1016)
		(layer "In2.Cu")
		(net 44)
	)
	(segment
		(start 148.025 86.85)
		(end 148.025 86.29)
		(width 0.145)
		(layer "F.Cu")
		(net 45)
	)
	(segment
		(start 146.375 93.775)
		(end 147.2 94.6)
		(width 0.145)
		(layer "F.Cu")
		(net 45)
	)
	(segment
		(start 149.925 95.925)
		(end 149.925 96.475)
		(width 0.145)
		(layer "F.Cu")
		(net 45)
	)
	(segment
		(start 147.2 94.6)
		(end 148.6 94.6)
		(width 0.145)
		(layer "F.Cu")
		(net 45)
	)
	(segment
		(start 148.6 94.6)
		(end 149.925 95.925)
		(width 0.145)
		(layer "F.Cu")
		(net 45)
	)
	(segment
		(start 146.375 92.7)
		(end 146.375 93.775)
		(width 0.145)
		(layer "F.Cu")
		(net 45)
	)
	(segment
		(start 149.925 96.475)
		(end 149.925 98.7)
		(width 0.145)
		(layer "F.Cu")
		(net 45)
	)
	(via
		(at 148.025 86.29)
		(size 0.45)
		(drill 0.15)
		(layers "F.Cu" "B.Cu")
		(net 45)
	)
	(via
		(at 146.375 92.7)
		(size 0.45)
		(drill 0.15)
		(layers "F.Cu" "B.Cu")
		(net 45)
	)
	(segment
		(start 148.002835 88.711653)
		(end 148.014939 88.730917)
		(width 0.1016)
		(layer "In2.Cu")
		(net 45)
	)
	(segment
		(start 147.285834 89.138253)
		(end 147.269746 89.122165)
		(width 0.1016)
		(layer "In2.Cu")
		(net 45)
	)
	(segment
		(start 146.226881 90.88911)
		(end 146.225 90.9058)
		(width 0.1016)
		(layer "In2.Cu")
		(net 45)
	)
	(segment
		(start 146.508637 90.396161)
		(end 146.496761 90.408037)
		(width 0.1016)
		(layer "In2.Cu")
		(net 45)
	)
	(segment
		(start 147.497166 88.508453)
		(end 147.485062 88.527717)
		(width 0.1016)
		(layer "In2.Cu")
		(net 45)
	)
	(segment
		(start 146.496761 92.033637)
		(end 146.482541 92.042572)
		(width 0.1016)
		(layer "In2.Cu")
		(net 45)
	)
	(segment
		(start 146.482541 89.822227)
		(end 146.496761 89.831162)
		(width 0.1016)
		(layer "In2.Cu")
		(net 45)
	)
	(segment
		(start 146.8 89.1)
		(end 146.6 89.1)
		(width 0.1016)
		(layer "In2.Cu")
		(net 45)
	)
	(segment
		(start 147.553992 88.670852)
		(end 147.5766 88.6734)
		(width 0.1016)
		(layer "In2.Cu")
		(net 45)
	)
	(segment
		(start 146.283311 91.032119)
		(end 146.3 91.034)
		(width 0.1016)
		(layer "In2.Cu")
		(net 45)
	)
	(segment
		(start 146.525 89.943)
		(end 146.523119 89.959689)
		(width 0.1016)
		(layer "In2.Cu")
		(net 45)
	)
	(segment
		(start 146.283311 90.83268)
		(end 146.267459 90.838227)
		(width 0.1016)
		(layer "In2.Cu")
		(net 45)
	)
	(segment
		(start 146.3 89.8148)
		(end 146.45 89.8148)
		(width 0.1016)
		(layer "In2.Cu")
		(net 45)
	)
	(segment
		(start 146.496761 89.831162)
		(end 146.508637 89.843038)
		(width 0.1016)
		(layer "In2.Cu")
		(net 45)
	)
	(segment
		(start 146.508637 91.208961)
		(end 146.496761 91.220837)
		(width 0.1016)
		(layer "In2.Cu")
		(net 45)
	)
	(segment
		(start 147.513747 89.178991)
		(end 147.5112 89.2016)
		(width 0.1016)
		(layer "In2.Cu")
		(net 45)
	)
	(segment
		(start 146.225 91.7186)
		(end 146.225 91.7718)
		(width 0.1016)
		(layer "In2.Cu")
		(net 45)
	)
	(segment
		(start 146.226881 89.66991)
		(end 146.225 89.6866)
		(width 0.1016)
		(layer "In2.Cu")
		(net 45)
	)
	(segment
		(start 146.517572 91.194741)
		(end 146.508637 91.208961)
		(width 0.1016)
		(layer "In2.Cu")
		(net 45)
	)
	(segment
		(start 146.226881 90.07631)
		(end 146.225 90.093)
		(width 0.1016)
		(layer "In2.Cu")
		(net 45)
	)
	(segment
		(start 146.466689 91.641719)
		(end 146.45 91.6436)
		(width 0.1016)
		(layer "In2.Cu")
		(net 45)
	)
	(segment
		(start 146.482541 91.041427)
		(end 146.496761 91.050362)
		(width 0.1016)
		(layer "In2.Cu")
		(net 45)
	)
	(segment
		(start 146.225 89.7398)
		(end 146.226881 89.756489)
		(width 0.1016)
		(layer "In2.Cu")
		(net 45)
	)
	(segment
		(start 146.267459 90.838227)
		(end 146.253239 90.847162)
		(width 0.1016)
		(layer "In2.Cu")
		(net 45)
	)
	(segment
		(start 146.523119 91.585289)
		(end 146.517572 91.601141)
		(width 0.1016)
		(layer "In2.Cu")
		(net 45)
	)
	(segment
		(start 147.568717 89.110061)
		(end 147.549453 89.122165)
		(width 0.1016)
		(layer "In2.Cu")
		(net 45)
	)
	(segment
		(start 146.225 90.959)
		(end 146.226881 90.975689)
		(width 0.1016)
		(layer "In2.Cu")
		(net 45)
	)
	(segment
		(start 146.879434 89.138253)
		(end 146.863346 89.122165)
		(width 0.1016)
		(layer "In2.Cu")
		(net 45)
	)
	(segment
		(start 146.525 90.7558)
		(end 146.523119 90.772489)
		(width 0.1016)
		(layer "In2.Cu")
		(net 45)
	)
	(segment
		(start 146.267459 90.620172)
		(end 146.283311 90.625719)
		(width 0.1016)
		(layer "In2.Cu")
		(net 45)
	)
	(segment
		(start 146.466689 91.03588)
		(end 146.482541 91.041427)
		(width 0.1016)
		(layer "In2.Cu")
		(net 45)
	)
	(segment
		(start 146.45 90.8308)
		(end 146.3 90.8308)
		(width 0.1016)
		(layer "In2.Cu")
		(net 45)
	)
	(segment
		(start 146.267459 91.432972)
		(end 146.283311 91.438519)
		(width 0.1016)
		(layer "In2.Cu")
		(net 45)
	)
	(segment
		(start 146.496761 91.456762)
		(end 146.508637 91.468638)
		(width 0.1016)
		(layer "In2.Cu")
		(net 45)
	)
	(segment
		(start 147.5112 89.492712)
		(end 147.508652 89.51532)
		(width 0.1016)
		(layer "In2.Cu")
		(net 45)
	)
	(segment
		(start 146.225 91.3122)
		(end 146.225 91.3654)
		(width 0.1016)
		(layer "In2.Cu")
		(net 45)
	)
	(segment
		(start 147.521261 89.157517)
		(end 147.513747 89.178991)
		(width 0.1016)
		(layer "In2.Cu")
		(net 45)
	)
	(segment
		(start 146.482541 90.416972)
		(end 146.466689 90.422519)
		(width 0.1016)
		(layer "In2.Cu")
		(net 45)
	)
	(segment
		(start 148.014939 88.730917)
		(end 148.022453 88.752391)
		(width 0.1016)
		(layer "In2.Cu")
		(net 45)
	)
	(segment
		(start 146.482541 91.854227)
		(end 146.496761 91.863162)
		(width 0.1016)
		(layer "In2.Cu")
		(net 45)
	)
	(segment
		(start 146.523119 91.991689)
		(end 146.517572 92.007541)
		(width 0.1016)
		(layer "In2.Cu")
		(net 45)
	)
	(segment
		(start 146.45 90.018)
		(end 146.3 90.018)
		(width 0.1016)
		(layer "In2.Cu")
		(net 45)
	)
	(segment
		(start 146.482541 91.636172)
		(end 146.466689 91.641719)
		(width 0.1016)
		(layer "In2.Cu")
		(net 45)
	)
	(segment
		(start 146.241363 90.599361)
		(end 146.253239 90.611237)
		(width 0.1016)
		(layer "In2.Cu")
		(net 45)
	)
	(segment
		(start 146.525 91.9218)
		(end 146.525 91.975)
		(width 0.1016)
		(layer "In2.Cu")
		(net 45)
	)
	(segment
		(start 146.241363 91.412161)
		(end 146.253239 91.424037)
		(width 0.1016)
		(layer "In2.Cu")
		(net 45)
	)
	(segment
		(start 146.517572 89.975541)
		(end 146.508637 89.989761)
		(width 0.1016)
		(layer "In2.Cu")
		(net 45)
	)
	(segment
		(start 146.466689 90.22308)
		(end 146.482541 90.228627)
		(width 0.1016)
		(layer "In2.Cu")
		(net 45)
	)
	(segment
		(start 146.496761 91.627237)
		(end 146.482541 91.636172)
		(width 0.1016)
		(layer "In2.Cu")
		(net 45)
	)
	(segment
		(start 146.482541 90.228627)
		(end 146.496761 90.237562)
		(width 0.1016)
		(layer "In2.Cu")
		(net 45)
	)
	(segment
		(start 146.232428 90.466858)
		(end 146.226881 90.48271)
		(width 0.1016)
		(layer "In2.Cu")
		(net 45)
	)
	(segment
		(start 146.283311 91.64548)
		(end 146.267459 91.651027)
		(width 0.1016)
		(layer "In2.Cu")
		(net 45)
	)
	(segment
		(start 147.310547 89.51532)
		(end 147.308 89.492712)
		(width 0.1016)
		(layer "In2.Cu")
		(net 45)
	)
	(segment
		(start 147.453682 89.58425)
		(end 147.432208 89.591764)
		(width 0.1016)
		(layer "In2.Cu")
		(net 45)
	)
	(segment
		(start 146.226881 90.975689)
		(end 146.232428 90.991541)
		(width 0.1016)
		(layer "In2.Cu")
		(net 45)
	)
	(segment
		(start 146.517572 91.601141)
		(end 146.508637 91.615361)
		(width 0.1016)
		(layer "In2.Cu")
		(net 45)
	)
	(segment
		(start 146.523119 89.959689)
		(end 146.517572 89.975541)
		(width 0.1016)
		(layer "In2.Cu")
		(net 45)
	)
	(segment
		(start 147.047282 89.58425)
		(end 147.025808 89.591764)
		(width 0.1016)
		(layer "In2.Cu")
		(net 45)
	)
	(segment
		(start 147.305452 89.178991)
		(end 147.297938 89.157517)
		(width 0.1016)
		(layer "In2.Cu")
		(net 45)
	)
	(segment
		(start 147.5112 89.2016)
		(end 147.5112 89.492712)
		(width 0.1016)
		(layer "In2.Cu")
		(net 45)
	)
	(segment
		(start 147.318061 89.536794)
		(end 147.310547 89.51532)
		(width 0.1016)
		(layer "In2.Cu")
		(net 45)
	)
	(segment
		(start 147.229008 89.102547)
		(end 147.2064 89.1)
		(width 0.1016)
		(layer "In2.Cu")
		(net 45)
	)
	(segment
		(start 146.253239 91.017637)
		(end 146.267459 91.026572)
		(width 0.1016)
		(layer "In2.Cu")
		(net 45)
	)
	(segment
		(start 146.375 92.125)
		(end 146.375 92.7)
		(width 0.1016)
		(layer "In2.Cu")
		(net 45)
	)
	(segment
		(start 147.183791 89.102547)
		(end 147.162317 89.110061)
		(width 0.1016)
		(layer "In2.Cu")
		(net 45)
	)
	(segment
		(start 146.253239 91.253562)
		(end 146.241363 91.265438)
		(width 0.1016)
		(layer "In2.Cu")
		(net 45)
	)
	(segment
		(start 146.496761 90.001637)
		(end 146.482541 90.010572)
		(width 0.1016)
		(layer "In2.Cu")
		(net 45)
	)
	(segment
		(start 146.3 91.2372)
		(end 146.283311 91.23908)
		(width 0.1016)
		(layer "In2.Cu")
		(net 45)
	)
	(segment
		(start 146.496761 90.643962)
		(end 146.508637 90.655838)
		(width 0.1016)
		(layer "In2.Cu")
		(net 45)
	)
	(segment
		(start 147.114861 89.157517)
		(end 147.107347 89.178991)
		(width 0.1016)
		(layer "In2.Cu")
		(net 45)
	)
	(segment
		(start 146.417458 92.057427)
		(end 146.403238 92.066362)
		(width 0.1016)
		(layer "In2.Cu")
		(net 45)
	)
	(segment
		(start 146.482541 91.447827)
		(end 146.496761 91.456762)
		(width 0.1016)
		(layer "In2.Cu")
		(net 45)
	)
	(segment
		(start 146.508637 90.655838)
		(end 146.517572 90.670058)
		(width 0.1016)
		(layer "In2.Cu")
		(net 45)
	)
	(segment
		(start 146.496761 91.220837)
		(end 146.482541 91.229772)
		(width 0.1016)
		(layer "In2.Cu")
		(net 45)
	)
	(segment
		(start 146.267459 91.026572)
		(end 146.283311 91.032119)
		(width 0.1016)
		(layer "In2.Cu")
		(net 45)
	)
	(segment
		(start 147.269746 89.122165)
		(end 147.250482 89.110061)
		(width 0.1016)
		(layer "In2.Cu")
		(net 45)
	)
	(segment
		(start 146.226881 91.70191)
		(end 146.225 91.7186)
		(width 0.1016)
		(layer "In2.Cu")
		(net 45)
	)
	(segment
		(start 146.232428 90.585141)
		(end 146.241363 90.599361)
		(width 0.1016)
		(layer "In2.Cu")
		(net 45)
	)
	(segment
		(start 146.283311 90.01988)
		(end 146.267459 90.025427)
		(width 0.1016)
		(layer "In2.Cu")
		(net 45)
	)
	(segment
		(start 146.496761 91.050362)
		(end 146.508637 91.062238)
		(width 0.1016)
		(layer "In2.Cu")
		(net 45)
	)
	(segment
		(start 146.523119 91.49871)
		(end 146.525 91.5154)
		(width 0.1016)
		(layer "In2.Cu")
		(net 45)
	)
	(segment
		(start 146.358638 89.583361)
		(end 146.346762 89.595237)
		(width 0.1016)
		(layer "In2.Cu")
		(net 45)
	)
	(segment
		(start 146.226881 89.756489)
		(end 146.232428 89.772341)
		(width 0.1016)
		(layer "In2.Cu")
		(net 45)
	)
	(segment
		(start 147.330165 89.556058)
		(end 147.318061 89.536794)
		(width 0.1016)
		(layer "In2.Cu")
		(net 45)
	)
	(segment
		(start 146.45 91.4404)
		(end 146.466689 91.44228)
		(width 0.1016)
		(layer "In2.Cu")
		(net 45)
	)
	(segment
		(start 146.225 89.6866)
		(end 146.225 89.7398)
		(width 0.1016)
		(layer "In2.Cu")
		(net 45)
	)
	(segment
		(start 147.025808 89.591764)
		(end 147.0032 89.594312)
		(width 0.1016)
		(layer "In2.Cu")
		(net 45)
	)
	(segment
		(start 146.45 91.034)
		(end 146.466689 91.03588)
		(width 0.1016)
		(layer "In2.Cu")
		(net 45)
	)
	(segment
		(start 146.844082 89.110061)
		(end 146.822608 89.102547)
		(width 0.1016)
		(layer "In2.Cu")
		(net 45)
	)
	(segment
		(start 146.525 91.975)
		(end 146.523119 91.991689)
		(width 0.1016)
		(layer "In2.Cu")
		(net 45)
	)
	(segment
		(start 146.517572 91.482858)
		(end 146.523119 91.49871)
		(width 0.1016)
		(layer "In2.Cu")
		(net 45)
	)
	(segment
		(start 147.094738 89.536794)
		(end 147.082634 89.556058)
		(width 0.1016)
		(layer "In2.Cu")
		(net 45)
	)
	(segment
		(start 146.232428 90.991541)
		(end 146.241363 91.005761)
		(width 0.1016)
		(layer "In2.Cu")
		(net 45)
	)
	(segment
		(start 146.37688 92.10831)
		(end 146.375 92.125)
		(width 0.1016)
		(layer "In2.Cu")
		(net 45)
	)
	(segment
		(start 146.523119 90.68591)
		(end 146.525 90.7026)
		(width 0.1016)
		(layer "In2.Cu")
		(net 45)
	)
	(segment
		(start 146.3 90.8308)
		(end 146.283311 90.83268)
		(width 0.1016)
		(layer "In2.Cu")
		(net 45)
	)
	(segment
		(start 146.891538 89.157517)
		(end 146.879434 89.138253)
		(width 0.1016)
		(layer "In2.Cu")
		(net 45)
	)
	(segment
		(start 148.025 86.29)
		(end 148.025 88.3686)
		(width 0.1016)
		(layer "In2.Cu")
		(net 45)
	)
	(segment
		(start 146.45 90.4244)
		(end 146.3 90.4244)
		(width 0.1016)
		(layer "In2.Cu")
		(net 45)
	)
	(segment
		(start 147.386991 89.591764)
		(end 147.365517 89.58425)
		(width 0.1016)
		(layer "In2.Cu")
		(net 45)
	)
	(segment
		(start 146.375 89.325)
		(end 146.375 89.5366)
		(width 0.1016)
		(layer "In2.Cu")
		(net 45)
	)
	(segment
		(start 147.946009 88.467652)
		(end 147.9234 88.4702)
		(width 0.1016)
		(layer "In2.Cu")
		(net 45)
	)
	(segment
		(start 148.025 88.3686)
		(end 148.022453 88.391208)
		(width 0.1016)
		(layer "In2.Cu")
		(net 45)
	)
	(segment
		(start 146.482541 92.042572)
		(end 146.466689 92.048119)
		(width 0.1016)
		(layer "In2.Cu")
		(net 45)
	)
	(segment
		(start 146.508637 91.468638)
		(end 146.517572 91.482858)
		(width 0.1016)
		(layer "In2.Cu")
		(net 45)
	)
	(segment
		(start 146.253239 90.204837)
		(end 146.267459 90.213772)
		(width 0.1016)
		(layer "In2.Cu")
		(net 45)
	)
	(segment
		(start 146.226881 91.788489)
		(end 146.232428 91.804341)
		(width 0.1016)
		(layer "In2.Cu")
		(net 45)
	)
	(segment
		(start 146.253239 91.424037)
		(end 146.267459 91.432972)
		(width 0.1016)
		(layer "In2.Cu")
		(net 45)
	)
	(segment
		(start 146.225 90.9058)
		(end 146.225 90.959)
		(width 0.1016)
		(layer "In2.Cu")
		(net 45)
	)
	(segment
		(start 146.3 91.6436)
		(end 146.283311 91.64548)
		(width 0.1016)
		(layer "In2.Cu")
		(net 45)
	)
	(segment
		(start 146.232428 89.772341)
		(end 146.241363 89.786561)
		(width 0.1016)
		(layer "In2.Cu")
		(net 45)
	)
	(segment
		(start 146.382427 92.092458)
		(end 146.37688 92.10831)
		(width 0.1016)
		(layer "In2.Cu")
		(net 45)
	)
	(segment
		(start 147.508652 89.51532)
		(end 147.501138 89.536794)
		(width 0.1016)
		(layer "In2.Cu")
		(net 45)
	)
	(segment
		(start 147.477548 88.549191)
		(end 147.475 88.5718)
		(width 0.1016)
		(layer "In2.Cu")
		(net 45)
	)
	(segment
		(start 146.283311 89.61348)
		(end 146.267459 89.619027)
		(width 0.1016)
		(layer "In2.Cu")
		(net 45)
	)
	(segment
		(start 146.9016 89.2016)
		(end 146.899052 89.178991)
		(width 0.1016)
		(layer "In2.Cu")
		(net 45)
	)
	(segment
		(start 146.232428 90.060458)
		(end 146.226881 90.07631)
		(width 0.1016)
		(layer "In2.Cu")
		(net 45)
	)
	(segment
		(start 147.6128 89.1)
		(end 147.590191 89.102547)
		(width 0.1016)
		(layer "In2.Cu")
		(net 45)
	)
	(segment
		(start 146.241363 89.786561)
		(end 146.253239 89.798437)
		(width 0.1016)
		(layer "In2.Cu")
		(net 45)
	)
	(segment
		(start 146.508637 92.021761)
		(end 146.496761 92.033637)
		(width 0.1016)
		(layer "In2.Cu")
		(net 45)
	)
	(segment
		(start 147.472946 89.572146)
		(end 147.453682 89.58425)
		(width 0.1016)
		(layer "In2.Cu")
		(net 45)
	)
	(segment
		(start 146.517572 91.889258)
		(end 146.523119 91.90511)
		(width 0.1016)
		(layer "In2.Cu")
		(net 45)
	)
	(segment
		(start 146.3 90.4244)
		(end 146.283311 90.42628)
		(width 0.1016)
		(layer "In2.Cu")
		(net 45)
	)
	(segment
		(start 146.523119 90.366089)
		(end 146.517572 90.381941)
		(width 0.1016)
		(layer "In2.Cu")
		(net 45)
	)
	(segment
		(start 146.283311 91.438519)
		(end 146.3 91.4404)
		(width 0.1016)
		(layer "In2.Cu")
		(net 45)
	)
	(segment
		(start 146.232428 91.804341)
		(end 146.241363 91.818561)
		(width 0.1016)
		(layer "In2.Cu")
		(net 45)
	)
	(segment
		(start 146.232428 90.178741)
		(end 146.241363 90.192961)
		(width 0.1016)
		(layer "In2.Cu")
		(net 45)
	)
	(segment
		(start 146.980591 89.591764)
		(end 146.959117 89.58425)
		(width 0.1016)
		(layer "In2.Cu")
		(net 45)
	)
	(segment
		(start 146.508637 91.615361)
		(end 146.496761 91.627237)
		(width 0.1016)
		(layer "In2.Cu")
		(net 45)
	)
	(segment
		(start 146.241363 91.265438)
		(end 146.232428 91.279658)
		(width 0.1016)
		(layer "In2.Cu")
		(net 45)
	)
	(segment
		(start 146.508637 91.875038)
		(end 146.517572 91.889258)
		(width 0.1016)
		(layer "In2.Cu")
		(net 45)
	)
	(segment
		(start 146.508637 90.802561)
		(end 146.496761 90.814437)
		(width 0.1016)
		(layer "In2.Cu")
		(net 45)
	)
	(segment
		(start 146.267459 89.807372)
		(end 146.283311 89.812919)
		(width 0.1016)
		(layer "In2.Cu")
		(net 45)
	)
	(segment
		(start 146.466689 91.235319)
		(end 146.45 91.2372)
		(width 0.1016)
		(layer "In2.Cu")
		(net 45)
	)
	(segment
		(start 146.267459 91.244627)
		(end 146.253239 91.253562)
		(width 0.1016)
		(layer "In2.Cu")
		(net 45)
	)
	(segment
		(start 146.466689 90.422519)
		(end 146.45 90.4244)
		(width 0.1016)
		(layer "In2.Cu")
		(net 45)
	)
	(segment
		(start 146.367573 89.569141)
		(end 146.358638 89.583361)
		(width 0.1016)
		(layer "In2.Cu")
		(net 45)
	)
	(segment
		(start 146.523119 90.772489)
		(end 146.517572 90.788341)
		(width 0.1016)
		(layer "In2.Cu")
		(net 45)
	)
	(segment
		(start 147.1048 89.2016)
		(end 147.1048 89.492712)
		(width 0.1016)
		(layer "In2.Cu")
		(net 45)
	)
	(segment
		(start 147.986747 88.695565)
		(end 148.002835 88.711653)
		(width 0.1016)
		(layer "In2.Cu")
		(net 45)
	)
	(segment
		(start 146.517572 90.788341)
		(end 146.508637 90.802561)
		(width 0.1016)
		(layer "In2.Cu")
		(net 45)
	)
	(segment
		(start 146.517572 90.381941)
		(end 146.508637 90.396161)
		(width 0.1016)
		(layer "In2.Cu")
		(net 45)
	)
	(segment
		(start 147.2064 89.1)
		(end 147.183791 89.102547)
		(width 0.1016)
		(layer "In2.Cu")
		(net 45)
	)
	(segment
		(start 147.501138 89.536794)
		(end 147.489034 89.556058)
		(width 0.1016)
		(layer "In2.Cu")
		(net 45)
	)
	(segment
		(start 147.475 88.5718)
		(end 147.477548 88.594408)
		(width 0.1016)
		(layer "In2.Cu")
		(net 45)
	)
	(segment
		(start 147.4096 89.594312)
		(end 147.386991 89.591764)
		(width 0.1016)
		(layer "In2.Cu")
		(net 45)
	)
	(segment
		(start 146.283311 90.625719)
		(end 146.3 90.6276)
		(width 0.1016)
		(layer "In2.Cu")
		(net 45)
	)
	(segment
		(start 147.9234 88.4702)
		(end 147.5766 88.4702)
		(width 0.1016)
		(layer "In2.Cu")
		(net 45)
	)
	(segment
		(start 146.241363 90.859038)
		(end 146.232428 90.873258)
		(width 0.1016)
		(layer "In2.Cu")
		(net 45)
	)
	(segment
		(start 146.523119 91.90511)
		(end 146.525 91.9218)
		(width 0.1016)
		(layer "In2.Cu")
		(net 45)
	)
	(segment
		(start 146.6 89.1)
		(end 146.375 89.325)
		(width 0.1016)
		(layer "In2.Cu")
		(net 45)
	)
	(segment
		(start 146.31669 89.609719)
		(end 146.283311 89.61348)
		(width 0.1016)
		(layer "In2.Cu")
		(net 45)
	)
	(segment
		(start 147.143053 89.122165)
		(end 147.126965 89.138253)
		(width 0.1016)
		(layer "In2.Cu")
		(net 45)
	)
	(segment
		(start 146.466689 90.828919)
		(end 146.45 90.8308)
		(width 0.1016)
		(layer "In2.Cu")
		(net 45)
	)
	(segment
		(start 147.967483 88.683461)
		(end 147.986747 88.695565)
		(width 0.1016)
		(layer "In2.Cu")
		(net 45)
	)
	(segment
		(start 147.986747 88.448034)
		(end 147.967483 88.460138)
		(width 0.1016)
		(layer "In2.Cu")
		(net 45)
	)
	(segment
		(start 146.241363 91.671838)
		(end 146.232428 91.686058)
		(width 0.1016)
		(layer "In2.Cu")
		(net 45)
	)
	(segment
		(start 146.3 90.2212)
		(end 146.45 90.2212)
		(width 0.1016)
		(layer "In2.Cu")
		(net 45)
	)
	(segment
		(start 146.225 91.3654)
		(end 146.226881 91.382089)
		(width 0.1016)
		(layer "In2.Cu")
		(net 45)
	)
	(segment
		(start 146.496761 90.814437)
		(end 146.482541 90.823372)
		(width 0.1016)
		(layer "In2.Cu")
		(net 45)
	)
	(segment
		(start 146.267459 91.651027)
		(end 146.253239 91.659962)
		(width 0.1016)
		(layer "In2.Cu")
		(net 45)
	)
	(segment
		(start 146.241363 90.452638)
		(end 146.232428 90.466858)
		(width 0.1016)
		(layer "In2.Cu")
		(net 45)
	)
	(segment
		(start 146.283311 90.219319)
		(end 146.3 90.2212)
		(width 0.1016)
		(layer "In2.Cu")
		(net 45)
	)
	(segment
		(start 146.232428 91.397941)
		(end 146.241363 91.412161)
		(width 0.1016)
		(layer "In2.Cu")
		(net 45)
	)
	(segment
		(start 146.225 90.4994)
		(end 146.225 90.5526)
		(width 0.1016)
		(layer "In2.Cu")
		(net 45)
	)
	(segment
		(start 147.308 89.2016)
		(end 147.305452 89.178991)
		(width 0.1016)
		(layer "In2.Cu")
		(net 45)
	)
	(segment
		(start 147.549453 89.122165)
		(end 147.533365 89.138253)
		(width 0.1016)
		(layer "In2.Cu")
		(net 45)
	)
	(segment
		(start 146.466689 89.81668)
		(end 146.482541 89.822227)
		(width 0.1016)
		(layer "In2.Cu")
		(net 45)
	)
	(segment
		(start 148.002835 88.431946)
		(end 147.986747 88.448034)
		(width 0.1016)
		(layer "In2.Cu")
		(net 45)
	)
	(segment
		(start 146.226881 90.48271)
		(end 146.225 90.4994)
		(width 0.1016)
		(layer "In2.Cu")
		(net 45)
	)
	(segment
		(start 147.553992 88.472747)
		(end 147.532518 88.480261)
		(width 0.1016)
		(layer "In2.Cu")
		(net 45)
	)
	(segment
		(start 146.3 90.6276)
		(end 146.45 90.6276)
		(width 0.1016)
		(layer "In2.Cu")
		(net 45)
	)
	(segment
		(start 146.466689 92.048119)
		(end 146.43331 92.05188)
		(width 0.1016)
		(layer "In2.Cu")
		(net 45)
	)
	(segment
		(start 146.466689 90.016119)
		(end 146.45 90.018)
		(width 0.1016)
		(layer "In2.Cu")
		(net 45)
	)
	(segment
		(start 146.3 91.034)
		(end 146.45 91.034)
		(width 0.1016)
		(layer "In2.Cu")
		(net 45)
	)
	(segment
		(start 146.466689 90.62948)
		(end 146.482541 90.635027)
		(width 0.1016)
		(layer "In2.Cu")
		(net 45)
	)
	(segment
		(start 146.332542 89.604172)
		(end 146.31669 89.609719)
		(width 0.1016)
		(layer "In2.Cu")
		(net 45)
	)
	(segment
		(start 147.432208 89.591764)
		(end 147.4096 89.594312)
		(width 0.1016)
		(layer "In2.Cu")
		(net 45)
	)
	(segment
		(start 146.346762 89.595237)
		(end 146.332542 89.604172)
		(width 0.1016)
		(layer "In2.Cu")
		(net 45)
	)
	(segment
		(start 146.226881 91.29551)
		(end 146.225 91.3122)
		(width 0.1016)
		(layer "In2.Cu")
		(net 45)
	)
	(segment
		(start 146.375 89.5366)
		(end 146.37312 89.553289)
		(width 0.1016)
		(layer "In2.Cu")
		(net 45)
	)
	(segment
		(start 146.253239 89.627962)
		(end 146.241363 89.639838)
		(width 0.1016)
		(layer "In2.Cu")
		(net 45)
	)
	(segment
		(start 146.3 91.4404)
		(end 146.45 91.4404)
		(width 0.1016)
		(layer "In2.Cu")
		(net 45)
	)
	(segment
		(start 146.43331 92.05188)
		(end 146.417458 92.057427)
		(width 0.1016)
		(layer "In2.Cu")
		(net 45)
	)
	(segment
		(start 146.508637 89.843038)
		(end 146.517572 89.857258)
		(width 0.1016)
		(layer "In2.Cu")
		(net 45)
	)
	(segment
		(start 146.241363 89.639838)
		(end 146.232428 89.654058)
		(width 0.1016)
		(layer "In2.Cu")
		(net 45)
	)
	(segment
		(start 147.308 89.492712)
		(end 147.308 89.2016)
		(width 0.1016)
		(layer "In2.Cu")
		(net 45)
	)
	(segment
		(start 146.232428 90.873258)
		(end 146.226881 90.88911)
		(width 0.1016)
		(layer "In2.Cu")
		(net 45)
	)
	(segment
		(start 147.485062 88.527717)
		(end 147.477548 88.549191)
		(width 0.1016)
		(layer "In2.Cu")
		(net 45)
	)
	(segment
		(start 147.513254 88.651234)
		(end 147.532518 88.663338)
		(width 0.1016)
		(layer "In2.Cu")
		(net 45)
	)
	(segment
		(start 146.403238 92.066362)
		(end 146.391362 92.078238)
		(width 0.1016)
		(layer "In2.Cu")
		(net 45)
	)
	(segment
		(start 147.297938 89.157517)
		(end 147.285834 89.138253)
		(width 0.1016)
		(layer "In2.Cu")
		(net 45)
	)
	(segment
		(start 146.45 91.2372)
		(end 146.3 91.2372)
		(width 0.1016)
		(layer "In2.Cu")
		(net 45)
	)
	(segment
		(start 146.267459 90.431827)
		(end 146.253239 90.440762)
		(width 0.1016)
		(layer "In2.Cu")
		(net 45)
	)
	(segment
		(start 147.477548 88.594408)
		(end 147.485062 88.615882)
		(width 0.1016)
		(layer "In2.Cu")
		(net 45)
	)
	(segment
		(start 146.466689 91.84868)
		(end 146.482541 91.854227)
		(width 0.1016)
		(layer "In2.Cu")
		(net 45)
	)
	(segment
		(start 146.232428 91.279658)
		(end 146.226881 91.29551)
		(width 0.1016)
		(layer "In2.Cu")
		(net 45)
	)
	(segment
		(start 146.482541 91.229772)
		(end 146.466689 91.235319)
		(width 0.1016)
		(layer "In2.Cu")
		(net 45)
	)
	(segment
		(start 146.517572 91.076458)
		(end 146.523119 91.09231)
		(width 0.1016)
		(layer "In2.Cu")
		(net 45)
	)
	(segment
		(start 146.45 90.2212)
		(end 146.466689 90.22308)
		(width 0.1016)
		(layer "In2.Cu")
		(net 45)
	)
	(segment
		(start 146.241363 90.192961)
		(end 146.253239 90.204837)
		(width 0.1016)
		(layer "In2.Cu")
		(net 45)
	)
	(segment
		(start 146.525 91.1622)
		(end 146.523119 91.178889)
		(width 0.1016)
		(layer "In2.Cu")
		(net 45)
	)
	(segment
		(start 147.5766 88.4702)
		(end 147.553992 88.472747)
		(width 0.1016)
		(layer "In2.Cu")
		(net 45)
	)
	(segment
		(start 146.37312 89.553289)
		(end 146.367573 89.569141)
		(width 0.1016)
		(layer "In2.Cu")
		(net 45)
	)
	(segment
		(start 146.3 90.018)
		(end 146.283311 90.01988)
		(width 0.1016)
		(layer "In2.Cu")
		(net 45)
	)
	(segment
		(start 146.508637 90.249438)
		(end 146.517572 90.263658)
		(width 0.1016)
		(layer "In2.Cu")
		(net 45)
	)
	(segment
		(start 146.283311 90.42628)
		(end 146.267459 90.431827)
		(width 0.1016)
		(layer "In2.Cu")
		(net 45)
	)
	(segment
		(start 147.9 89.1)
		(end 147.6128 89.1)
		(width 0.1016)
		(layer "In2.Cu")
		(net 45)
	)
	(segment
		(start 146.923765 89.556058)
		(end 146.911661 89.536794)
		(width 0.1016)
		(layer "In2.Cu")
		(net 45)
	)
	(segment
		(start 146.283311 91.844919)
		(end 146.3 91.8468)
		(width 0.1016)
		(layer "In2.Cu")
		(net 45)
	)
	(segment
		(start 148.022453 88.391208)
		(end 148.014939 88.412682)
		(width 0.1016)
		(layer "In2.Cu")
		(net 45)
	)
	(segment
		(start 147.102252 89.51532)
		(end 147.094738 89.536794)
		(width 0.1016)
		(layer "In2.Cu")
		(net 45)
	)
	(segment
		(start 146.496761 91.863162)
		(end 146.508637 91.875038)
		(width 0.1016)
		(layer "In2.Cu")
		(net 45)
	)
	(segment
		(start 146.225 90.1462)
		(end 146.226881 90.162889)
		(width 0.1016)
		(layer "In2.Cu")
		(net 45)
	)
	(segment
		(start 146.496761 90.237562)
		(end 146.508637 90.249438)
		(width 0.1016)
		(layer "In2.Cu")
		(net 45)
	)
	(segment
		(start 146.253239 91.830437)
		(end 146.267459 91.839372)
		(width 0.1016)
		(layer "In2.Cu")
		(net 45)
	)
	(segment
		(start 147.497166 88.635146)
		(end 147.513254 88.651234)
		(width 0.1016)
		(layer "In2.Cu")
		(net 45)
	)
	(segment
		(start 146.525 91.5154)
		(end 146.525 91.5686)
		(width 0.1016)
		(layer "In2.Cu")
		(net 45)
	)
	(segment
		(start 146.482541 90.823372)
		(end 146.466689 90.828919)
		(width 0.1016)
		(layer "In2.Cu")
		(net 45)
	)
	(segment
		(start 146.253239 89.798437)
		(end 146.267459 89.807372)
		(width 0.1016)
		(layer "In2.Cu")
		(net 45)
	)
	(segment
		(start 146.525 90.7026)
		(end 146.525 90.7558)
		(width 0.1016)
		(layer "In2.Cu")
		(net 45)
	)
	(segment
		(start 147.967483 88.460138)
		(end 147.946009 88.467652)
		(width 0.1016)
		(layer "In2.Cu")
		(net 45)
	)
	(segment
		(start 146.391362 92.078238)
		(end 146.382427 92.092458)
		(width 0.1016)
		(layer "In2.Cu")
		(net 45)
	)
	(segment
		(start 146.283311 91.23908)
		(end 146.267459 91.244627)
		(width 0.1016)
		(layer "In2.Cu")
		(net 45)
	)
	(segment
		(start 146.253239 90.034362)
		(end 146.241363 90.046238)
		(width 0.1016)
		(layer "In2.Cu")
		(net 45)
	)
	(segment
		(start 146.3 91.8468)
		(end 146.45 91.8468)
		(width 0.1016)
		(layer "In2.Cu")
		(net 45)
	)
	(segment
		(start 146.939853 89.572146)
		(end 146.923765 89.556058)
		(width 0.1016)
		(layer "In2.Cu")
		(net 45)
	)
	(segment
		(start 146.241363 91.818561)
		(end 146.253239 91.830437)
		(width 0.1016)
		(layer "In2.Cu")
		(net 45)
	)
	(segment
		(start 146.822608 89.102547)
		(end 146.8 89.1)
		(width 0.1016)
		(layer "In2.Cu")
		(net 45)
	)
	(segment
		(start 146.517572 90.670058)
		(end 146.523119 90.68591)
		(width 0.1016)
		(layer "In2.Cu")
		(net 45)
	)
	(segment
		(start 147.162317 89.110061)
		(end 147.143053 89.122165)
		(width 0.1016)
		(layer "In2.Cu")
		(net 45)
	)
	(segment
		(start 148.022453 88.752391)
		(end 148.025 88.775)
		(width 0.1016)
		(layer "In2.Cu")
		(net 45)
	)
	(segment
		(start 147.107347 89.178991)
		(end 147.1048 89.2016)
		(width 0.1016)
		(layer "In2.Cu")
		(net 45)
	)
	(segment
		(start 146.523119 90.27951)
		(end 146.525 90.2962)
		(width 0.1016)
		(layer "In2.Cu")
		(net 45)
	)
	(segment
		(start 148.025 88.775)
		(end 148.025 88.975)
		(width 0.1016)
		(layer "In2.Cu")
		(net 45)
	)
	(segment
		(start 146.253239 90.611237)
		(end 146.267459 90.620172)
		(width 0.1016)
		(layer "In2.Cu")
		(net 45)
	)
	(segment
		(start 147.5766 88.6734)
		(end 147.9234 88.6734)
		(width 0.1016)
		(layer "In2.Cu")
		(net 45)
	)
	(segment
		(start 146.232428 89.654058)
		(end 146.226881 89.66991)
		(width 0.1016)
		(layer "In2.Cu")
		(net 45)
	)
	(segment
		(start 147.126965 89.138253)
		(end 147.114861 89.157517)
		(width 0.1016)
		(layer "In2.Cu")
		(net 45)
	)
	(segment
		(start 146.525 91.109)
		(end 146.525 91.1622)
		(width 0.1016)
		(layer "In2.Cu")
		(net 45)
	)
	(segment
		(start 146.523119 91.178889)
		(end 146.517572 91.194741)
		(width 0.1016)
		(layer "In2.Cu")
		(net 45)
	)
	(segment
		(start 146.45 89.8148)
		(end 146.466689 89.81668)
		(width 0.1016)
		(layer "In2.Cu")
		(net 45)
	)
	(segment
		(start 146.232428 91.686058)
		(end 146.226881 91.70191)
		(width 0.1016)
		(layer "In2.Cu")
		(net 45)
	)
	(segment
		(start 147.1048 89.492712)
		(end 147.102252 89.51532)
		(width 0.1016)
		(layer "In2.Cu")
		(net 45)
	)
	(segment
		(start 146.9016 89.492712)
		(end 146.9016 89.2016)
		(width 0.1016)
		(layer "In2.Cu")
		(net 45)
	)
	(segment
		(start 146.241363 90.046238)
		(end 146.232428 90.060458)
		(width 0.1016)
		(layer "In2.Cu")
		(net 45)
	)
	(segment
		(start 146.283311 89.812919)
		(end 146.3 89.8148)
		(width 0.1016)
		(layer "In2.Cu")
		(net 45)
	)
	(segment
		(start 146.225 90.5526)
		(end 146.226881 90.569289)
		(width 0.1016)
		(layer "In2.Cu")
		(net 45)
	)
	(segment
		(start 146.517572 92.007541)
		(end 146.508637 92.021761)
		(width 0.1016)
		(layer "In2.Cu")
		(net 45)
	)
	(segment
		(start 146.863346 89.122165)
		(end 146.844082 89.110061)
		(width 0.1016)
		(layer "In2.Cu")
		(net 45)
	)
	(segment
		(start 147.0032 89.594312)
		(end 146.980591 89.591764)
		(width 0.1016)
		(layer "In2.Cu")
		(net 45)
	)
	(segment
		(start 146.45 91.8468)
		(end 146.466689 91.84868)
		(width 0.1016)
		(layer "In2.Cu")
		(net 45)
	)
	(segment
		(start 146.899052 89.178991)
		(end 146.891538 89.157517)
		(width 0.1016)
		(layer "In2.Cu")
		(net 45)
	)
	(segment
		(start 147.250482 89.110061)
		(end 147.229008 89.102547)
		(width 0.1016)
		(layer "In2.Cu")
		(net 45)
	)
	(segment
		(start 147.346253 89.572146)
		(end 147.330165 89.556058)
		(width 0.1016)
		(layer "In2.Cu")
		(net 45)
	)
	(segment
		(start 147.532518 88.480261)
		(end 147.513254 88.492365)
		(width 0.1016)
		(layer "In2.Cu")
		(net 45)
	)
	(segment
		(start 146.523119 89.87311)
		(end 146.525 89.8898)
		(width 0.1016)
		(layer "In2.Cu")
		(net 45)
	)
	(segment
		(start 148.014939 88.412682)
		(end 148.002835 88.431946)
		(width 0.1016)
		(layer "In2.Cu")
		(net 45)
	)
	(segment
		(start 147.532518 88.663338)
		(end 147.553992 88.670852)
		(width 0.1016)
		(layer "In2.Cu")
		(net 45)
	)
	(segment
		(start 146.525 91.5686)
		(end 146.523119 91.585289)
		(width 0.1016)
		(layer "In2.Cu")
		(net 45)
	)
	(segment
		(start 146.226881 90.162889)
		(end 146.232428 90.178741)
		(width 0.1016)
		(layer "In2.Cu")
		(net 45)
	)
	(segment
		(start 146.959117 89.58425)
		(end 146.939853 89.572146)
		(width 0.1016)
		(layer "In2.Cu")
		(net 45)
	)
	(segment
		(start 146.508637 91.062238)
		(end 146.517572 91.076458)
		(width 0.1016)
		(layer "In2.Cu")
		(net 45)
	)
	(segment
		(start 146.525 90.2962)
		(end 146.525 90.3494)
		(width 0.1016)
		(layer "In2.Cu")
		(net 45)
	)
	(segment
		(start 147.946009 88.675947)
		(end 147.967483 88.683461)
		(width 0.1016)
		(layer "In2.Cu")
		(net 45)
	)
	(segment
		(start 146.253239 91.659962)
		(end 146.241363 91.671838)
		(width 0.1016)
		(layer "In2.Cu")
		(net 45)
	)
	(segment
		(start 147.9234 88.6734)
		(end 147.946009 88.675947)
		(width 0.1016)
		(layer "In2.Cu")
		(net 45)
	)
	(segment
		(start 146.267459 90.025427)
		(end 146.253239 90.034362)
		(width 0.1016)
		(layer "In2.Cu")
		(net 45)
	)
	(segment
		(start 146.517572 89.857258)
		(end 146.523119 89.87311)
		(width 0.1016)
		(layer "In2.Cu")
		(net 45)
	)
	(segment
		(start 146.496761 90.408037)
		(end 146.482541 90.416972)
		(width 0.1016)
		(layer "In2.Cu")
		(net 45)
	)
	(segment
		(start 146.525 89.8898)
		(end 146.525 89.943)
		(width 0.1016)
		(layer "In2.Cu")
		(net 45)
	)
	(segment
		(start 146.45 90.6276)
		(end 146.466689 90.62948)
		(width 0.1016)
		(layer "In2.Cu")
		(net 45)
	)
	(segment
		(start 146.45 91.6436)
		(end 146.3 91.6436)
		(width 0.1016)
		(layer "In2.Cu")
		(net 45)
	)
	(segment
		(start 146.253239 90.847162)
		(end 146.241363 90.859038)
		(width 0.1016)
		(layer "In2.Cu")
		(net 45)
	)
	(segment
		(start 146.523119 91.09231)
		(end 146.525 91.109)
		(width 0.1016)
		(layer "In2.Cu")
		(net 45)
	)
	(segment
		(start 147.533365 89.138253)
		(end 147.521261 89.157517)
		(width 0.1016)
		(layer "In2.Cu")
		(net 45)
	)
	(segment
		(start 148.025 88.975)
		(end 147.9 89.1)
		(width 0.1016)
		(layer "In2.Cu")
		(net 45)
	)
	(segment
		(start 146.482541 90.635027)
		(end 146.496761 90.643962)
		(width 0.1016)
		(layer "In2.Cu")
		(net 45)
	)
	(segment
		(start 146.241363 91.005761)
		(end 146.253239 91.017637)
		(width 0.1016)
		(layer "In2.Cu")
		(net 45)
	)
	(segment
		(start 146.226881 90.569289)
		(end 146.232428 90.585141)
		(width 0.1016)
		(layer "In2.Cu")
		(net 45)
	)
	(segment
		(start 146.517572 90.263658)
		(end 146.523119 90.27951)
		(width 0.1016)
		(layer "In2.Cu")
		(net 45)
	)
	(segment
		(start 146.904147 89.51532)
		(end 146.9016 89.492712)
		(width 0.1016)
		(layer "In2.Cu")
		(net 45)
	)
	(segment
		(start 146.466689 91.44228)
		(end 146.482541 91.447827)
		(width 0.1016)
		(layer "In2.Cu")
		(net 45)
	)
	(segment
		(start 147.365517 89.58425)
		(end 147.346253 89.572146)
		(width 0.1016)
		(layer "In2.Cu")
		(net 45)
	)
	(segment
		(start 146.267459 89.619027)
		(end 146.253239 89.627962)
		(width 0.1016)
		(layer "In2.Cu")
		(net 45)
	)
	(segment
		(start 147.513254 88.492365)
		(end 147.497166 88.508453)
		(width 0.1016)
		(layer "In2.Cu")
		(net 45)
	)
	(segment
		(start 146.482541 90.010572)
		(end 146.466689 90.016119)
		(width 0.1016)
		(layer "In2.Cu")
		(net 45)
	)
	(segment
		(start 147.489034 89.556058)
		(end 147.472946 89.572146)
		(width 0.1016)
		(layer "In2.Cu")
		(net 45)
	)
	(segment
		(start 147.082634 89.556058)
		(end 147.066546 89.572146)
		(width 0.1016)
		(layer "In2.Cu")
		(net 45)
	)
	(segment
		(start 146.267459 91.839372)
		(end 146.283311 91.844919)
		(width 0.1016)
		(layer "In2.Cu")
		(net 45)
	)
	(segment
		(start 146.253239 90.440762)
		(end 146.241363 90.452638)
		(width 0.1016)
		(layer "In2.Cu")
		(net 45)
	)
	(segment
		(start 147.066546 89.572146)
		(end 147.047282 89.58425)
		(width 0.1016)
		(layer "In2.Cu")
		(net 45)
	)
	(segment
		(start 147.590191 89.102547)
		(end 147.568717 89.110061)
		(width 0.1016)
		(layer "In2.Cu")
		(net 45)
	)
	(segment
		(start 146.267459 90.213772)
		(end 146.283311 90.219319)
		(width 0.1016)
		(layer "In2.Cu")
		(net 45)
	)
	(segment
		(start 146.225 91.7718)
		(end 146.226881 91.788489)
		(width 0.1016)
		(layer "In2.Cu")
		(net 45)
	)
	(segment
		(start 147.485062 88.615882)
		(end 147.497166 88.635146)
		(width 0.1016)
		(layer "In2.Cu")
		(net 45)
	)
	(segment
		(start 146.525 90.3494)
		(end 146.523119 90.366089)
		(width 0.1016)
		(layer "In2.Cu")
		(net 45)
	)
	(segment
		(start 146.911661 89.536794)
		(end 146.904147 89.51532)
		(width 0.1016)
		(layer "In2.Cu")
		(net 45)
	)
	(segment
		(start 146.508637 89.989761)
		(end 146.496761 90.001637)
		(width 0.1016)
		(layer "In2.Cu")
		(net 45)
	)
	(segment
		(start 146.226881 91.382089)
		(end 146.232428 91.397941)
		(width 0.1016)
		(layer "In2.Cu")
		(net 45)
	)
	(segment
		(start 146.225 90.093)
		(end 146.225 90.1462)
		(width 0.1016)
		(layer "In2.Cu")
		(net 45)
	)
	(segment
		(start 144.375 94.775)
		(end 145.925 96.325)
		(width 0.145)
		(layer "F.Cu")
		(net 46)
	)
	(segment
		(start 144.375 92.3)
		(end 144.375 94.775)
		(width 0.145)
		(layer "F.Cu")
		(net 46)
	)
	(segment
		(start 148.825 83.65)
		(end 148.825 84.21)
		(width 0.145)
		(layer "F.Cu")
		(net 46)
	)
	(segment
		(start 145.925 96.325)
		(end 145.925 98.7)
		(width 0.145)
		(layer "F.Cu")
		(net 46)
	)
	(via
		(at 148.825 84.21)
		(size 0.45)
		(drill 0.15)
		(layers "F.Cu" "B.Cu")
		(net 46)
	)
	(via
		(at 144.375 92.3)
		(size 0.45)
		(drill 0.15)
		(layers "F.Cu" "B.Cu")
		(net 46)
	)
	(segment
		(start 144.226591 86.585396)
		(end 144.226591 86.530604)
		(width 0.1016)
		(layer "In2.Cu")
		(net 46)
	)
	(segment
		(start 144.228451 86.514092)
		(end 144.233939 86.498408)
		(width 0.1016)
		(layer "In2.Cu")
		(net 46)
	)
	(segment
		(start 144.495471 86.846611)
		(end 144.507221 86.834861)
		(width 0.1016)
		(layer "In2.Cu")
		(net 46)
	)
	(segment
		(start 144.516061 87.227191)
		(end 144.521549 87.211507)
		(width 0.1016)
		(layer "In2.Cu")
		(net 46)
	)
	(segment
		(start 144.254529 87.049811)
		(end 144.242779 87.038061)
		(width 0.1016)
		(layer "In2.Cu")
		(net 46)
	)
	(segment
		(start 144.233939 86.617591)
		(end 144.228451 86.601907)
		(width 0.1016)
		(layer "In2.Cu")
		(net 46)
	)
	(segment
		(start 144.242779 86.224465)
		(end 144.233939 86.210395)
		(width 0.1016)
		(layer "In2.Cu")
		(net 46)
	)
	(segment
		(start 144.242779 87.850861)
		(end 144.233939 87.836791)
		(width 0.1016)
		(layer "In2.Cu")
		(net 46)
	)
	(segment
		(start 144.521549 86.310892)
		(end 144.516061 86.295208)
		(width 0.1016)
		(layer "In2.Cu")
		(net 46)
	)
	(segment
		(start 144.228451 86.194711)
		(end 144.226591 86.1782)
		(width 0.1016)
		(layer "In2.Cu")
		(net 46)
	)
	(segment
		(start 144.521549 87.617907)
		(end 144.523409 87.601396)
		(width 0.1016)
		(layer "In2.Cu")
		(net 46)
	)
	(segment
		(start 144.228451 87.008307)
		(end 144.226591 86.991796)
		(width 0.1016)
		(layer "In2.Cu")
		(net 46)
	)
	(segment
		(start 144.300795 86.6596)
		(end 144.284283 86.657739)
		(width 0.1016)
		(layer "In2.Cu")
		(net 46)
	)
	(segment
		(start 144.254529 86.643411)
		(end 144.242779 86.631661)
		(width 0.1016)
		(layer "In2.Cu")
		(net 46)
	)
	(segment
		(start 144.233939 86.904808)
		(end 144.242779 86.890738)
		(width 0.1016)
		(layer "In2.Cu")
		(net 46)
	)
	(segment
		(start 144.268599 87.465051)
		(end 144.254529 87.456211)
		(width 0.1016)
		(layer "In2.Cu")
		(net 46)
	)
	(segment
		(start 144.507221 86.687538)
		(end 144.495471 86.675788)
		(width 0.1016)
		(layer "In2.Cu")
		(net 46)
	)
	(segment
		(start 144.465717 86.66146)
		(end 144.449205 86.6596)
		(width 0.1016)
		(layer "In2.Cu")
		(net 46)
	)
	(segment
		(start 144.449205 87.8788)
		(end 144.300795 87.8788)
		(width 0.1016)
		(layer "In2.Cu")
		(net 46)
	)
	(segment
		(start 144.523409 87.953004)
		(end 144.521549 87.936492)
		(width 0.1016)
		(layer "In2.Cu")
		(net 46)
	)
	(segment
		(start 144.254529 86.472588)
		(end 144.268599 86.463748)
		(width 0.1016)
		(layer "In2.Cu")
		(net 46)
	)
	(segment
		(start 144.254529 87.456211)
		(end 144.242779 87.444461)
		(width 0.1016)
		(layer "In2.Cu")
		(net 46)
	)
	(segment
		(start 148.575 85.34358)
		(end 148.825 85.09358)
		(width 0.1016)
		(layer "In2.Cu")
		(net 46)
	)
	(segment
		(start 144.226591 86.1782)
		(end 144.226591 86.123408)
		(width 0.1016)
		(layer "In2.Cu")
		(net 46)
	)
	(segment
		(start 144.300795 86.8628)
		(end 144.449205 86.8628)
		(width 0.1016)
		(layer "In2.Cu")
		(net 46)
	)
	(segment
		(start 144.449205 87.2692)
		(end 144.465717 87.267339)
		(width 0.1016)
		(layer "In2.Cu")
		(net 46)
	)
	(segment
		(start 144.233939 87.430391)
		(end 144.228451 87.414707)
		(width 0.1016)
		(layer "In2.Cu")
		(net 46)
	)
	(segment
		(start 144.268599 87.682948)
		(end 144.284283 87.67746)
		(width 0.1016)
		(layer "In2.Cu")
		(net 46)
	)
	(segment
		(start 144.242779 87.703538)
		(end 144.254529 87.691788)
		(width 0.1016)
		(layer "In2.Cu")
		(net 46)
	)
	(segment
		(start 144.254529 87.862611)
		(end 144.242779 87.850861)
		(width 0.1016)
		(layer "In2.Cu")
		(net 46)
	)
	(segment
		(start 144.300795 87.066)
		(end 144.284283 87.064139)
		(width 0.1016)
		(layer "In2.Cu")
		(net 46)
	)
	(segment
		(start 144.233939 86.091212)
		(end 144.242779 86.077142)
		(width 0.1016)
		(layer "In2.Cu")
		(net 46)
	)
	(segment
		(start 144.523409 86.327404)
		(end 144.521549 86.310892)
		(width 0.1016)
		(layer "In2.Cu")
		(net 46)
	)
	(segment
		(start 144.268599 86.463748)
		(end 144.284283 86.45826)
		(width 0.1016)
		(layer "In2.Cu")
		(net 46)
	)
	(segment
		(start 144.347061 86.033015)
		(end 144.358811 86.021265)
		(width 0.1016)
		(layer "In2.Cu")
		(net 46)
	)
	(segment
		(start 144.375 85.75)
		(end 144.78142 85.34358)
		(width 0.1016)
		(layer "In2.Cu")
		(net 46)
	)
	(segment
		(start 144.523409 88.007796)
		(end 144.523409 87.953004)
		(width 0.1016)
		(layer "In2.Cu")
		(net 46)
	)
	(segment
		(start 144.465717 88.080139)
		(end 144.481401 88.074651)
		(width 0.1016)
		(layer "In2.Cu")
		(net 46)
	)
	(segment
		(start 144.516061 86.295208)
		(end 144.507221 86.281138)
		(width 0.1016)
		(layer "In2.Cu")
		(net 46)
	)
	(segment
		(start 144.78142 85.34358)
		(end 148.575 85.34358)
		(width 0.1016)
		(layer "In2.Cu")
		(net 46)
	)
	(segment
		(start 144.233939 87.836791)
		(end 144.228451 87.821107)
		(width 0.1016)
		(layer "In2.Cu")
		(net 46)
	)
	(segment
		(start 144.268599 87.276548)
		(end 144.284283 87.27106)
		(width 0.1016)
		(layer "In2.Cu")
		(net 46)
	)
	(segment
		(start 144.242779 87.297138)
		(end 144.254529 87.285388)
		(width 0.1016)
		(layer "In2.Cu")
		(net 46)
	)
	(segment
		(start 144.284283 87.67746)
		(end 144.300795 87.6756)
		(width 0.1016)
		(layer "In2.Cu")
		(net 46)
	)
	(segment
		(start 144.254529 86.236215)
		(end 144.242779 86.224465)
		(width 0.1016)
		(layer "In2.Cu")
		(net 46)
	)
	(segment
		(start 144.523409 87.140204)
		(end 144.521549 87.123692)
		(width 0.1016)
		(layer "In2.Cu")
		(net 46)
	)
	(segment
		(start 144.242779 87.444461)
		(end 144.233939 87.430391)
		(width 0.1016)
		(layer "In2.Cu")
		(net 46)
	)
	(segment
		(start 144.226591 87.804596)
		(end 144.226591 87.749804)
		(width 0.1016)
		(layer "In2.Cu")
		(net 46)
	)
	(segment
		(start 144.507221 87.647661)
		(end 144.516061 87.633591)
		(width 0.1016)
		(layer "In2.Cu")
		(net 46)
	)
	(segment
		(start 144.516061 87.514408)
		(end 144.507221 87.500338)
		(width 0.1016)
		(layer "In2.Cu")
		(net 46)
	)
	(segment
		(start 144.284283 87.27106)
		(end 144.300795 87.2692)
		(width 0.1016)
		(layer "In2.Cu")
		(net 46)
	)
	(segment
		(start 144.449205 86.4564)
		(end 144.465717 86.454539)
		(width 0.1016)
		(layer "In2.Cu")
		(net 46)
	)
	(segment
		(start 144.507221 87.093938)
		(end 144.495471 87.082188)
		(width 0.1016)
		(layer "In2.Cu")
		(net 46)
	)
	(segment
		(start 144.465717 87.673739)
		(end 144.481401 87.668251)
		(width 0.1016)
		(layer "In2.Cu")
		(net 46)
	)
	(segment
		(start 144.228451 86.601907)
		(end 144.226591 86.585396)
		(width 0.1016)
		(layer "In2.Cu")
		(net 46)
	)
	(segment
		(start 144.516061 87.108008)
		(end 144.507221 87.093938)
		(width 0.1016)
		(layer "In2.Cu")
		(net 46)
	)
	(segment
		(start 144.268599 86.245055)
		(end 144.254529 86.236215)
		(width 0.1016)
		(layer "In2.Cu")
		(net 46)
	)
	(segment
		(start 144.495471 87.253011)
		(end 144.507221 87.241261)
		(width 0.1016)
		(layer "In2.Cu")
		(net 46)
	)
	(segment
		(start 144.284283 86.250543)
		(end 144.268599 86.245055)
		(width 0.1016)
		(layer "In2.Cu")
		(net 46)
	)
	(segment
		(start 144.516061 87.920808)
		(end 144.507221 87.906738)
		(width 0.1016)
		(layer "In2.Cu")
		(net 46)
	)
	(segment
		(start 144.284283 86.051064)
		(end 144.317307 86.047343)
		(width 0.1016)
		(layer "In2.Cu")
		(net 46)
	)
	(segment
		(start 144.284283 86.86466)
		(end 144.300795 86.8628)
		(width 0.1016)
		(layer "In2.Cu")
		(net 46)
	)
	(segment
		(start 148.825 85.09358)
		(end 148.825 84.21)
		(width 0.1016)
		(layer "In2.Cu")
		(net 46)
	)
	(segment
		(start 144.495471 86.675788)
		(end 144.481401 86.666948)
		(width 0.1016)
		(layer "In2.Cu")
		(net 46)
	)
	(segment
		(start 144.523409 86.382196)
		(end 144.523409 86.327404)
		(width 0.1016)
		(layer "In2.Cu")
		(net 46)
	)
	(segment
		(start 144.228451 87.733292)
		(end 144.233939 87.717608)
		(width 0.1016)
		(layer "In2.Cu")
		(net 46)
	)
	(segment
		(start 144.495471 87.894988)
		(end 144.481401 87.886148)
		(width 0.1016)
		(layer "In2.Cu")
		(net 46)
	)
	(segment
		(start 144.268599 87.871451)
		(end 144.254529 87.862611)
		(width 0.1016)
		(layer "In2.Cu")
		(net 46)
	)
	(segment
		(start 144.521549 86.805107)
		(end 144.523409 86.788596)
		(width 0.1016)
		(layer "In2.Cu")
		(net 46)
	)
	(segment
		(start 144.481401 87.668251)
		(end 144.495471 87.659411)
		(width 0.1016)
		(layer "In2.Cu")
		(net 46)
	)
	(segment
		(start 144.516061 86.414391)
		(end 144.521549 86.398707)
		(width 0.1016)
		(layer "In2.Cu")
		(net 46)
	)
	(segment
		(start 144.516061 87.633591)
		(end 144.521549 87.617907)
		(width 0.1016)
		(layer "In2.Cu")
		(net 46)
	)
	(segment
		(start 144.465717 86.454539)
		(end 144.481401 86.449051)
		(width 0.1016)
		(layer "In2.Cu")
		(net 46)
	)
	(segment
		(start 144.268599 86.652251)
		(end 144.254529 86.643411)
		(width 0.1016)
		(layer "In2.Cu")
		(net 46)
	)
	(segment
		(start 144.284283 87.470539)
		(end 144.268599 87.465051)
		(width 0.1016)
		(layer "In2.Cu")
		(net 46)
	)
	(segment
		(start 144.254529 87.691788)
		(end 144.268599 87.682948)
		(width 0.1016)
		(layer "In2.Cu")
		(net 46)
	)
	(segment
		(start 144.481401 87.073348)
		(end 144.465717 87.06786)
		(width 0.1016)
		(layer "In2.Cu")
		(net 46)
	)
	(segment
		(start 144.465717 86.25506)
		(end 144.449205 86.2532)
		(width 0.1016)
		(layer "In2.Cu")
		(net 46)
	)
	(segment
		(start 144.242779 87.038061)
		(end 144.233939 87.023991)
		(width 0.1016)
		(layer "In2.Cu")
		(net 46)
	)
	(segment
		(start 144.233939 87.023991)
		(end 144.228451 87.008307)
		(width 0.1016)
		(layer "In2.Cu")
		(net 46)
	)
	(segment
		(start 144.226591 86.123408)
		(end 144.228451 86.106896)
		(width 0.1016)
		(layer "In2.Cu")
		(net 46)
	)
	(segment
		(start 144.317307 86.047343)
		(end 144.332991 86.041855)
		(width 0.1016)
		(layer "In2.Cu")
		(net 46)
	)
	(segment
		(start 144.449205 87.6756)
		(end 144.465717 87.673739)
		(width 0.1016)
		(layer "In2.Cu")
		(net 46)
	)
	(segment
		(start 144.228451 86.920492)
		(end 144.233939 86.904808)
		(width 0.1016)
		(layer "In2.Cu")
		(net 46)
	)
	(segment
		(start 144.481401 86.666948)
		(end 144.465717 86.66146)
		(width 0.1016)
		(layer "In2.Cu")
		(net 46)
	)
	(segment
		(start 144.228451 87.326892)
		(end 144.233939 87.311208)
		(width 0.1016)
		(layer "In2.Cu")
		(net 46)
	)
	(segment
		(start 144.516061 86.820791)
		(end 144.521549 86.805107)
		(width 0.1016)
		(layer "In2.Cu")
		(net 46)
	)
	(segment
		(start 144.507221 87.241261)
		(end 144.516061 87.227191)
		(width 0.1016)
		(layer "In2.Cu")
		(net 46)
	)
	(segment
		(start 144.300795 87.2692)
		(end 144.449205 87.2692)
		(width 0.1016)
		(layer "In2.Cu")
		(net 46)
	)
	(segment
		(start 144.521549 88.024307)
		(end 144.523409 88.007796)
		(width 0.1016)
		(layer "In2.Cu")
		(net 46)
	)
	(segment
		(start 144.228451 87.414707)
		(end 144.226591 87.398196)
		(width 0.1016)
		(layer "In2.Cu")
		(net 46)
	)
	(segment
		(start 144.495471 86.440211)
		(end 144.507221 86.428461)
		(width 0.1016)
		(layer "In2.Cu")
		(net 46)
	)
	(segment
		(start 144.521549 87.123692)
		(end 144.516061 87.108008)
		(width 0.1016)
		(layer "In2.Cu")
		(net 46)
	)
	(segment
		(start 144.481401 87.886148)
		(end 144.465717 87.88066)
		(width 0.1016)
		(layer "In2.Cu")
		(net 46)
	)
	(segment
		(start 144.507221 88.054061)
		(end 144.516061 88.039991)
		(width 0.1016)
		(layer "In2.Cu")
		(net 46)
	)
	(segment
		(start 144.375 86.252404)
		(end 144.300796 86.252404)
		(width 0.1016)
		(layer "In2.Cu")
		(net 46)
	)
	(segment
		(start 144.432693 88.08386)
		(end 144.465717 88.080139)
		(width 0.1016)
		(layer "In2.Cu")
		(net 46)
	)
	(segment
		(start 144.391189 88.109938)
		(end 144.402939 88.098188)
		(width 0.1016)
		(layer "In2.Cu")
		(net 46)
	)
	(segment
		(start 144.375 86.2532)
		(end 144.375 86.252404)
		(width 0.1016)
		(layer "In2.Cu")
		(net 46)
	)
	(segment
		(start 144.449205 86.8628)
		(end 144.465717 86.860939)
		(width 0.1016)
		(layer "In2.Cu")
		(net 46)
	)
	(segment
		(start 144.358811 86.021265)
		(end 144.367651 86.007195)
		(width 0.1016)
		(layer "In2.Cu")
		(net 46)
	)
	(segment
		(start 144.521549 87.211507)
		(end 144.523409 87.194996)
		(width 0.1016)
		(layer "In2.Cu")
		(net 46)
	)
	(segment
		(start 144.507221 86.834861)
		(end 144.516061 86.820791)
		(width 0.1016)
		(layer "In2.Cu")
		(net 46)
	)
	(segment
		(start 144.449205 86.6596)
		(end 144.300795 86.6596)
		(width 0.1016)
		(layer "In2.Cu")
		(net 46)
	)
	(segment
		(start 144.300796 86.252404)
		(end 144.284283 86.250543)
		(width 0.1016)
		(layer "In2.Cu")
		(net 46)
	)
	(segment
		(start 144.284283 87.064139)
		(end 144.268599 87.058651)
		(width 0.1016)
		(layer "In2.Cu")
		(net 46)
	)
	(segment
		(start 144.226591 86.937004)
		(end 144.228451 86.920492)
		(width 0.1016)
		(layer "In2.Cu")
		(net 46)
	)
	(segment
		(start 144.233939 87.717608)
		(end 144.242779 87.703538)
		(width 0.1016)
		(layer "In2.Cu")
		(net 46)
	)
	(segment
		(start 144.226591 86.530604)
		(end 144.228451 86.514092)
		(width 0.1016)
		(layer "In2.Cu")
		(net 46)
	)
	(segment
		(start 144.254529 86.878988)
		(end 144.268599 86.870148)
		(width 0.1016)
		(layer "In2.Cu")
		(net 46)
	)
	(segment
		(start 144.233939 86.498408)
		(end 144.242779 86.484338)
		(width 0.1016)
		(layer "In2.Cu")
		(net 46)
	)
	(segment
		(start 144.495471 87.659411)
		(end 144.507221 87.647661)
		(width 0.1016)
		(layer "In2.Cu")
		(net 46)
	)
	(segment
		(start 144.495471 87.488588)
		(end 144.481401 87.479748)
		(width 0.1016)
		(layer "In2.Cu")
		(net 46)
	)
	(segment
		(start 144.516061 88.039991)
		(end 144.521549 88.024307)
		(width 0.1016)
		(layer "In2.Cu")
		(net 46)
	)
	(segment
		(start 144.521549 87.936492)
		(end 144.516061 87.920808)
		(width 0.1016)
		(layer "In2.Cu")
		(net 46)
	)
	(segment
		(start 144.375 88.156204)
		(end 144.376861 88.139692)
		(width 0.1016)
		(layer "In2.Cu")
		(net 46)
	)
	(segment
		(start 144.495471 88.065811)
		(end 144.507221 88.054061)
		(width 0.1016)
		(layer "In2.Cu")
		(net 46)
	)
	(segment
		(start 144.521549 86.398707)
		(end 144.523409 86.382196)
		(width 0.1016)
		(layer "In2.Cu")
		(net 46)
	)
	(segment
		(start 144.242779 86.077142)
		(end 144.254529 86.065392)
		(width 0.1016)
		(layer "In2.Cu")
		(net 46)
	)
	(segment
		(start 144.254529 87.285388)
		(end 144.268599 87.276548)
		(width 0.1016)
		(layer "In2.Cu")
		(net 46)
	)
	(segment
		(start 144.300795 86.4564)
		(end 144.449205 86.4564)
		(width 0.1016)
		(layer "In2.Cu")
		(net 46)
	)
	(segment
		(start 144.523409 86.733804)
		(end 144.521549 86.717292)
		(width 0.1016)
		(layer "In2.Cu")
		(net 46)
	)
	(segment
		(start 144.284283 86.45826)
		(end 144.300795 86.4564)
		(width 0.1016)
		(layer "In2.Cu")
		(net 46)
	)
	(segment
		(start 144.523409 87.546604)
		(end 144.521549 87.530092)
		(width 0.1016)
		(layer "In2.Cu")
		(net 46)
	)
	(segment
		(start 144.417009 88.089348)
		(end 144.432693 88.08386)
		(width 0.1016)
		(layer "In2.Cu")
		(net 46)
	)
	(segment
		(start 144.284283 87.876939)
		(end 144.268599 87.871451)
		(width 0.1016)
		(layer "In2.Cu")
		(net 46)
	)
	(segment
		(start 144.465717 87.47426)
		(end 144.449205 87.4724)
		(width 0.1016)
		(layer "In2.Cu")
		(net 46)
	)
	(segment
		(start 144.242779 86.631661)
		(end 144.233939 86.617591)
		(width 0.1016)
		(layer "In2.Cu")
		(net 46)
	)
	(segment
		(start 144.495471 86.269388)
		(end 144.481401 86.260548)
		(width 0.1016)
		(layer "In2.Cu")
		(net 46)
	)
	(segment
		(start 144.481401 86.855451)
		(end 144.495471 86.846611)
		(width 0.1016)
		(layer "In2.Cu")
		(net 46)
	)
	(segment
		(start 144.233939 86.210395)
		(end 144.228451 86.194711)
		(width 0.1016)
		(layer "In2.Cu")
		(net 46)
	)
	(segment
		(start 144.507221 87.500338)
		(end 144.495471 87.488588)
		(width 0.1016)
		(layer "In2.Cu")
		(net 46)
	)
	(segment
		(start 144.465717 87.267339)
		(end 144.481401 87.261851)
		(width 0.1016)
		(layer "In2.Cu")
		(net 46)
	)
	(segment
		(start 144.254529 86.065392)
		(end 144.268599 86.056552)
		(width 0.1016)
		(layer "In2.Cu")
		(net 46)
	)
	(segment
		(start 144.300795 87.4724)
		(end 144.284283 87.470539)
		(width 0.1016)
		(layer "In2.Cu")
		(net 46)
	)
	(segment
		(start 144.375 85.975)
		(end 144.375 85.75)
		(width 0.1016)
		(layer "In2.Cu")
		(net 46)
	)
	(segment
		(start 144.481401 86.449051)
		(end 144.495471 86.440211)
		(width 0.1016)
		(layer "In2.Cu")
		(net 46)
	)
	(segment
		(start 144.507221 86.281138)
		(end 144.495471 86.269388)
		(width 0.1016)
		(layer "In2.Cu")
		(net 46)
	)
	(segment
		(start 144.449205 87.066)
		(end 144.300795 87.066)
		(width 0.1016)
		(layer "In2.Cu")
		(net 46)
	)
	(segment
		(start 144.382349 88.124008)
		(end 144.391189 88.109938)
		(width 0.1016)
		(layer "In2.Cu")
		(net 46)
	)
	(segment
		(start 144.226591 87.749804)
		(end 144.228451 87.733292)
		(width 0.1016)
		(layer "In2.Cu")
		(net 46)
	)
	(segment
		(start 144.521549 86.717292)
		(end 144.516061 86.701608)
		(width 0.1016)
		(layer "In2.Cu")
		(net 46)
	)
	(segment
		(start 144.375 92.3)
		(end 144.375 88.156204)
		(width 0.1016)
		(layer "In2.Cu")
		(net 46)
	)
	(segment
		(start 144.228451 87.821107)
		(end 144.226591 87.804596)
		(width 0.1016)
		(layer "In2.Cu")
		(net 46)
	)
	(segment
		(start 144.373139 85.991511)
		(end 144.375 85.975)
		(width 0.1016)
		(layer "In2.Cu")
		(net 46)
	)
	(segment
		(start 144.226591 87.398196)
		(end 144.226591 87.343404)
		(width 0.1016)
		(layer "In2.Cu")
		(net 46)
	)
	(segment
		(start 144.300795 87.6756)
		(end 144.449205 87.6756)
		(width 0.1016)
		(layer "In2.Cu")
		(net 46)
	)
	(segment
		(start 144.332991 86.041855)
		(end 144.347061 86.033015)
		(width 0.1016)
		(layer "In2.Cu")
		(net 46)
	)
	(segment
		(start 144.449205 87.4724)
		(end 144.300795 87.4724)
		(width 0.1016)
		(layer "In2.Cu")
		(net 46)
	)
	(segment
		(start 144.226591 87.343404)
		(end 144.228451 87.326892)
		(width 0.1016)
		(layer "In2.Cu")
		(net 46)
	)
	(segment
		(start 144.481401 88.074651)
		(end 144.495471 88.065811)
		(width 0.1016)
		(layer "In2.Cu")
		(net 46)
	)
	(segment
		(start 144.516061 86.701608)
		(end 144.507221 86.687538)
		(width 0.1016)
		(layer "In2.Cu")
		(net 46)
	)
	(segment
		(start 144.495471 87.082188)
		(end 144.481401 87.073348)
		(width 0.1016)
		(layer "In2.Cu")
		(net 46)
	)
	(segment
		(start 144.481401 87.261851)
		(end 144.495471 87.253011)
		(width 0.1016)
		(layer "In2.Cu")
		(net 46)
	)
	(segment
		(start 144.465717 86.860939)
		(end 144.481401 86.855451)
		(width 0.1016)
		(layer "In2.Cu")
		(net 46)
	)
	(segment
		(start 144.523409 86.788596)
		(end 144.523409 86.733804)
		(width 0.1016)
		(layer "In2.Cu")
		(net 46)
	)
	(segment
		(start 144.507221 86.428461)
		(end 144.516061 86.414391)
		(width 0.1016)
		(layer "In2.Cu")
		(net 46)
	)
	(segment
		(start 144.268599 87.058651)
		(end 144.254529 87.049811)
		(width 0.1016)
		(layer "In2.Cu")
		(net 46)
	)
	(segment
		(start 144.268599 86.870148)
		(end 144.284283 86.86466)
		(width 0.1016)
		(layer "In2.Cu")
		(net 46)
	)
	(segment
		(start 144.481401 87.479748)
		(end 144.465717 87.47426)
		(width 0.1016)
		(layer "In2.Cu")
		(net 46)
	)
	(segment
		(start 144.228451 86.106896)
		(end 144.233939 86.091212)
		(width 0.1016)
		(layer "In2.Cu")
		(net 46)
	)
	(segment
		(start 144.284283 86.657739)
		(end 144.268599 86.652251)
		(width 0.1016)
		(layer "In2.Cu")
		(net 46)
	)
	(segment
		(start 144.521549 87.530092)
		(end 144.516061 87.514408)
		(width 0.1016)
		(layer "In2.Cu")
		(net 46)
	)
	(segment
		(start 144.226591 86.991796)
		(end 144.226591 86.937004)
		(width 0.1016)
		(layer "In2.Cu")
		(net 46)
	)
	(segment
		(start 144.449205 86.2532)
		(end 144.375 86.2532)
		(width 0.1016)
		(layer "In2.Cu")
		(net 46)
	)
	(segment
		(start 144.507221 87.906738)
		(end 144.495471 87.894988)
		(width 0.1016)
		(layer "In2.Cu")
		(net 46)
	)
	(segment
		(start 144.376861 88.139692)
		(end 144.382349 88.124008)
		(width 0.1016)
		(layer "In2.Cu")
		(net 46)
	)
	(segment
		(start 144.367651 86.007195)
		(end 144.373139 85.991511)
		(width 0.1016)
		(layer "In2.Cu")
		(net 46)
	)
	(segment
		(start 144.523409 87.194996)
		(end 144.523409 87.140204)
		(width 0.1016)
		(layer "In2.Cu")
		(net 46)
	)
	(segment
		(start 144.465717 87.06786)
		(end 144.449205 87.066)
		(width 0.1016)
		(layer "In2.Cu")
		(net 46)
	)
	(segment
		(start 144.242779 86.890738)
		(end 144.254529 86.878988)
		(width 0.1016)
		(layer "In2.Cu")
		(net 46)
	)
	(segment
		(start 144.300795 87.8788)
		(end 144.284283 87.876939)
		(width 0.1016)
		(layer "In2.Cu")
		(net 46)
	)
	(segment
		(start 144.465717 87.88066)
		(end 144.449205 87.8788)
		(width 0.1016)
		(layer "In2.Cu")
		(net 46)
	)
	(segment
		(start 144.481401 86.260548)
		(end 144.465717 86.25506)
		(width 0.1016)
		(layer "In2.Cu")
		(net 46)
	)
	(segment
		(start 144.242779 86.484338)
		(end 144.254529 86.472588)
		(width 0.1016)
		(layer "In2.Cu")
		(net 46)
	)
	(segment
		(start 144.233939 87.311208)
		(end 144.242779 87.297138)
		(width 0.1016)
		(layer "In2.Cu")
		(net 46)
	)
	(segment
		(start 144.402939 88.098188)
		(end 144.417009 88.089348)
		(width 0.1016)
		(layer "In2.Cu")
		(net 46)
	)
	(segment
		(start 144.268599 86.056552)
		(end 144.284283 86.051064)
		(width 0.1016)
		(layer "In2.Cu")
		(net 46)
	)
	(segment
		(start 144.523409 87.601396)
		(end 144.523409 87.546604)
		(width 0.1016)
		(layer "In2.Cu")
		(net 46)
	)
	(segment
		(start 148.825 86.85)
		(end 148.825 86.29)
		(width 0.145)
		(layer "F.Cu")
		(net 47)
	)
	(segment
		(start 150.925 98.7)
		(end 150.925 95.725)
		(width 0.145)
		(layer "F.Cu")
		(net 47)
	)
	(segment
		(start 147.6 93.8)
		(end 147.175 93.375)
		(width 0.145)
		(layer "F.Cu")
		(net 47)
	)
	(segment
		(start 150.925 95.725)
		(end 149 93.8)
		(width 0.145)
		(layer "F.Cu")
		(net 47)
	)
	(segment
		(start 149 93.8)
		(end 147.6 93.8)
		(width 0.145)
		(layer "F.Cu")
		(net 47)
	)
	(segment
		(start 147.175 92.7)
		(end 147.175 93.375)
		(width 0.145)
		(layer "F.Cu")
		(net 47)
	)
	(via
		(at 148.825 86.29)
		(size 0.45)
		(drill 0.15)
		(layers "F.Cu" "B.Cu")
		(net 47)
	)
	(via
		(at 147.175 92.7)
		(size 0.45)
		(drill 0.15)
		(layers "F.Cu" "B.Cu")
		(net 47)
	)
	(segment
		(start 148.539751 90.187039)
		(end 148.557539 90.201224)
		(width 0.1016)
		(layer "In2.Cu")
		(net 47)
	)
	(segment
		(start 148.822453 86.902391)
		(end 148.814939 86.880917)
		(width 0.1016)
		(layer "In2.Cu")
		(net 47)
	)
	(segment
		(start 148.252384 90.474407)
		(end 148.270172 90.488592)
		(width 0.1016)
		(layer "In2.Cu")
		(net 47)
	)
	(segment
		(start 147.57013 91.5941)
		(end 147.592312 91.589037)
		(width 0.1016)
		(layer "In2.Cu")
		(net 47)
	)
	(segment
		(start 148.721876 90.908947)
		(end 148.744626 90.908948)
		(width 0.1016)
		(layer "In2.Cu")
		(net 47)
	)
	(segment
		(start 148.7234 86.6202)
		(end 148.746009 86.617652)
		(width 0.1016)
		(layer "In2.Cu")
		(net 47)
	)
	(segment
		(start 147.175 91.975)
		(end 147.531845 91.618157)
		(width 0.1016)
		(layer "In2.Cu")
		(net 47)
	)
	(segment
		(start 147.899586 90.746841)
		(end 147.922337 90.746841)
		(width 0.1016)
		(layer "In2.Cu")
		(net 47)
	)
	(segment
		(start 148.313254 86.801234)
		(end 148.297166 86.785146)
		(width 0.1016)
		(layer "In2.Cu")
		(net 47)
	)
	(segment
		(start 147.637244 91.594099)
		(end 147.657742 91.603971)
		(width 0.1016)
		(layer "In2.Cu")
		(net 47)
	)
	(segment
		(start 148.517724 91.167196)
		(end 148.531909 91.149409)
		(width 0.1016)
		(layer "In2.Cu")
		(net 47)
	)
	(segment
		(start 148.546844 91.106729)
		(end 148.546843 91.083979)
		(width 0.1016)
		(layer "In2.Cu")
		(net 47)
	)
	(segment
		(start 148.353992 86.622747)
		(end 148.3766 86.6202)
		(width 0.1016)
		(layer "In2.Cu")
		(net 47)
	)
	(segment
		(start 147.76688 91.695277)
		(end 147.789061 91.70034)
		(width 0.1016)
		(layer "In2.Cu")
		(net 47)
	)
	(segment
		(start 147.537566 91.081115)
		(end 147.551752 91.063328)
		(width 0.1016)
		(layer "In2.Cu")
		(net 47)
	)
	(segment
		(start 147.824934 90.793747)
		(end 147.83912 90.77596)
		(width 0.1016)
		(layer "In2.Cu")
		(net 47)
	)
	(segment
		(start 148.097368 90.549058)
		(end 148.102431 90.526877)
		(width 0.1016)
		(layer "In2.Cu")
		(net 47)
	)
	(segment
		(start 148.270172 90.488592)
		(end 148.661408 90.879828)
		(width 0.1016)
		(layer "In2.Cu")
		(net 47)
	)
	(segment
		(start 147.854491 91.685406)
		(end 147.872277 91.671221)
		(width 0.1016)
		(layer "In2.Cu")
		(net 47)
	)
	(segment
		(start 148.277548 86.744408)
		(end 148.275 86.7218)
		(width 0.1016)
		(layer "In2.Cu")
		(net 47)
	)
	(segment
		(start 148.297166 86.658453)
		(end 148.313254 86.642365)
		(width 0.1016)
		(layer "In2.Cu")
		(net 47)
	)
	(segment
		(start 147.901396 91.588004)
		(end 147.896335 91.565822)
		(width 0.1016)
		(layer "In2.Cu")
		(net 47)
	)
	(segment
		(start 148.822453 86.541208)
		(end 148.825 86.5186)
		(width 0.1016)
		(layer "In2.Cu")
		(net 47)
	)
	(segment
		(start 148.313254 86.642365)
		(end 148.332518 86.630261)
		(width 0.1016)
		(layer "In2.Cu")
		(net 47)
	)
	(segment
		(start 148.805092 90.736144)
		(end 148.413855 90.344908)
		(width 0.1016)
		(layer "In2.Cu")
		(net 47)
	)
	(segment
		(start 147.922337 90.746841)
		(end 147.944518 90.751903)
		(width 0.1016)
		(layer "In2.Cu")
		(net 47)
	)
	(segment
		(start 147.982804 90.77596)
		(end 148.37404 91.167196)
		(width 0.1016)
		(layer "In2.Cu")
		(net 47)
	)
	(segment
		(start 147.746381 91.685407)
		(end 147.76688 91.695277)
		(width 0.1016)
		(layer "In2.Cu")
		(net 47)
	)
	(segment
		(start 147.896335 91.565822)
		(end 147.886463 91.545325)
		(width 0.1016)
		(layer "In2.Cu")
		(net 47)
	)
	(segment
		(start 148.557539 90.201224)
		(end 148.681315 90.325)
		(width 0.1016)
		(layer "In2.Cu")
		(net 47)
	)
	(segment
		(start 148.452141 90.177167)
		(end 148.474321 90.172105)
		(width 0.1016)
		(layer "In2.Cu")
		(net 47)
	)
	(segment
		(start 148.231886 90.464535)
		(end 148.252384 90.474407)
		(width 0.1016)
		(layer "In2.Cu")
		(net 47)
	)
	(segment
		(start 148.531909 91.149409)
		(end 148.541782 91.128909)
		(width 0.1016)
		(layer "In2.Cu")
		(net 47)
	)
	(segment
		(start 148.144275 90.474407)
		(end 148.164774 90.464535)
		(width 0.1016)
		(layer "In2.Cu")
		(net 47)
	)
	(segment
		(start 147.83912 90.77596)
		(end 147.856907 90.761775)
		(width 0.1016)
		(layer "In2.Cu")
		(net 47)
	)
	(segment
		(start 148.124959 91.47862)
		(end 148.14714 91.483683)
		(width 0.1016)
		(layer "In2.Cu")
		(net 47)
	)
	(segment
		(start 148.244541 91.436777)
		(end 148.254414 91.416277)
		(width 0.1016)
		(layer "In2.Cu")
		(net 47)
	)
	(segment
		(start 147.81 90.859177)
		(end 147.81 90.836426)
		(width 0.1016)
		(layer "In2.Cu")
		(net 47)
	)
	(segment
		(start 147.527695 91.101613)
		(end 147.537566 91.081115)
		(width 0.1016)
		(layer "In2.Cu")
		(net 47)
	)
	(segment
		(start 147.872277 91.527537)
		(end 147.551752 91.207012)
		(width 0.1016)
		(layer "In2.Cu")
		(net 47)
	)
	(segment
		(start 147.537566 91.189224)
		(end 147.527695 91.168726)
		(width 0.1016)
		(layer "In2.Cu")
		(net 47)
	)
	(segment
		(start 148.825 86.925)
		(end 148.822453 86.902391)
		(width 0.1016)
		(layer "In2.Cu")
		(net 47)
	)
	(segment
		(start 148.10446 91.46875)
		(end 148.124959 91.47862)
		(width 0.1016)
		(layer "In2.Cu")
		(net 47)
	)
	(segment
		(start 148.254414 91.416277)
		(end 148.259476 91.394097)
		(width 0.1016)
		(layer "In2.Cu")
		(net 47)
	)
	(segment
		(start 148.814939 86.562682)
		(end 148.822453 86.541208)
		(width 0.1016)
		(layer "In2.Cu")
		(net 47)
	)
	(segment
		(start 148.7234 86.8234)
		(end 148.3766 86.8234)
		(width 0.1016)
		(layer "In2.Cu")
		(net 47)
	)
	(segment
		(start 148.097368 90.571809)
		(end 148.097368 90.549058)
		(width 0.1016)
		(layer "In2.Cu")
		(net 47)
	)
	(segment
		(start 148.285062 86.677717)
		(end 148.297166 86.658453)
		(width 0.1016)
		(layer "In2.Cu")
		(net 47)
	)
	(segment
		(start 148.53191 91.041299)
		(end 148.517724 91.023512)
		(width 0.1016)
		(layer "In2.Cu")
		(net 47)
	)
	(segment
		(start 148.719601 90.349056)
		(end 148.741782 90.354119)
		(width 0.1016)
		(layer "In2.Cu")
		(net 47)
	)
	(segment
		(start 148.254414 91.349165)
		(end 148.244542 91.328667)
		(width 0.1016)
		(layer "In2.Cu")
		(net 47)
	)
	(segment
		(start 147.896334 91.632936)
		(end 147.901397 91.610754)
		(width 0.1016)
		(layer "In2.Cu")
		(net 47)
	)
	(segment
		(start 147.634969 91.034209)
		(end 147.65715 91.039271)
		(width 0.1016)
		(layer "In2.Cu")
		(net 47)
	)
	(segment
		(start 148.767483 86.833461)
		(end 148.746009 86.825947)
		(width 0.1016)
		(layer "In2.Cu")
		(net 47)
	)
	(segment
		(start 148.814939 86.880917)
		(end 148.802835 86.861653)
		(width 0.1016)
		(layer "In2.Cu")
		(net 47)
	)
	(segment
		(start 148.230356 91.31088)
		(end 147.83912 90.919644)
		(width 0.1016)
		(layer "In2.Cu")
		(net 47)
	)
	(segment
		(start 148.391828 91.181382)
		(end 148.412327 91.191252)
		(width 0.1016)
		(layer "In2.Cu")
		(net 47)
	)
	(segment
		(start 148.786747 86.845565)
		(end 148.767483 86.833461)
		(width 0.1016)
		(layer "In2.Cu")
		(net 47)
	)
	(segment
		(start 148.786714 90.349056)
		(end 148.807212 90.339185)
		(width 0.1016)
		(layer "In2.Cu")
		(net 47)
	)
	(segment
		(start 148.766807 90.903885)
		(end 148.787306 90.894013)
		(width 0.1016)
		(layer "In2.Cu")
		(net 47)
	)
	(segment
		(start 148.16989 91.483684)
		(end 148.192071 91.478621)
		(width 0.1016)
		(layer "In2.Cu")
		(net 47)
	)
	(segment
		(start 148.332518 86.813338)
		(end 148.313254 86.801234)
		(width 0.1016)
		(layer "In2.Cu")
		(net 47)
	)
	(segment
		(start 148.541782 91.061797)
		(end 148.53191 91.041299)
		(width 0.1016)
		(layer "In2.Cu")
		(net 47)
	)
	(segment
		(start 148.164774 90.464535)
		(end 148.186954 90.459473)
		(width 0.1016)
		(layer "In2.Cu")
		(net 47)
	)
	(segment
		(start 148.474321 90.172105)
		(end 148.497073 90.172105)
		(width 0.1016)
		(layer "In2.Cu")
		(net 47)
	)
	(segment
		(start 147.675529 91.618157)
		(end 147.728593 91.671221)
		(width 0.1016)
		(layer "In2.Cu")
		(net 47)
	)
	(segment
		(start 148.457258 91.196316)
		(end 148.479439 91.191253)
		(width 0.1016)
		(layer "In2.Cu")
		(net 47)
	)
	(segment
		(start 148.21257 91.468749)
		(end 148.230356 91.454564)
		(width 0.1016)
		(layer "In2.Cu")
		(net 47)
	)
	(segment
		(start 147.65715 91.039271)
		(end 147.677648 91.049143)
		(width 0.1016)
		(layer "In2.Cu")
		(net 47)
	)
	(segment
		(start 147.522632 91.146545)
		(end 147.522632 91.123794)
		(width 0.1016)
		(layer "In2.Cu")
		(net 47)
	)
	(segment
		(start 148.786747 86.598034)
		(end 148.802835 86.581946)
		(width 0.1016)
		(layer "In2.Cu")
		(net 47)
	)
	(segment
		(start 147.728593 91.671221)
		(end 147.746381 91.685407)
		(width 0.1016)
		(layer "In2.Cu")
		(net 47)
	)
	(segment
		(start 147.811811 91.700341)
		(end 147.833992 91.695278)
		(width 0.1016)
		(layer "In2.Cu")
		(net 47)
	)
	(segment
		(start 148.259475 91.371347)
		(end 148.254414 91.349165)
		(width 0.1016)
		(layer "In2.Cu")
		(net 47)
	)
	(segment
		(start 148.112302 90.506379)
		(end 148.126488 90.488592)
		(width 0.1016)
		(layer "In2.Cu")
		(net 47)
	)
	(segment
		(start 148.819278 90.753931)
		(end 148.805092 90.736144)
		(width 0.1016)
		(layer "In2.Cu")
		(net 47)
	)
	(segment
		(start 148.186954 90.459473)
		(end 148.209705 90.459473)
		(width 0.1016)
		(layer "In2.Cu")
		(net 47)
	)
	(segment
		(start 148.661408 90.879828)
		(end 148.679196 90.894014)
		(width 0.1016)
		(layer "In2.Cu")
		(net 47)
	)
	(segment
		(start 147.877406 90.751903)
		(end 147.899586 90.746841)
		(width 0.1016)
		(layer "In2.Cu")
		(net 47)
	)
	(segment
		(start 148.805092 90.879828)
		(end 148.819277 90.862041)
		(width 0.1016)
		(layer "In2.Cu")
		(net 47)
	)
	(segment
		(start 148.126488 90.488592)
		(end 148.144275 90.474407)
		(width 0.1016)
		(layer "In2.Cu")
		(net 47)
	)
	(segment
		(start 148.746009 86.617652)
		(end 148.767483 86.610138)
		(width 0.1016)
		(layer "In2.Cu")
		(net 47)
	)
	(segment
		(start 148.399669 90.219011)
		(end 148.413855 90.201224)
		(width 0.1016)
		(layer "In2.Cu")
		(net 47)
	)
	(segment
		(start 148.479439 91.191253)
		(end 148.499938 91.181381)
		(width 0.1016)
		(layer "In2.Cu")
		(net 47)
	)
	(segment
		(start 148.497073 90.172105)
		(end 148.519253 90.177167)
		(width 0.1016)
		(layer "In2.Cu")
		(net 47)
	)
	(segment
		(start 148.541782 91.128909)
		(end 148.546844 91.106729)
		(width 0.1016)
		(layer "In2.Cu")
		(net 47)
	)
	(segment
		(start 148.086672 91.454564)
		(end 148.10446 91.46875)
		(width 0.1016)
		(layer "In2.Cu")
		(net 47)
	)
	(segment
		(start 148.3766 86.8234)
		(end 148.353992 86.820852)
		(width 0.1016)
		(layer "In2.Cu")
		(net 47)
	)
	(segment
		(start 148.819277 90.862041)
		(end 148.82915 90.841541)
		(width 0.1016)
		(layer "In2.Cu")
		(net 47)
	)
	(segment
		(start 147.612218 91.034209)
		(end 147.634969 91.034209)
		(width 0.1016)
		(layer "In2.Cu")
		(net 47)
	)
	(segment
		(start 148.353992 86.820852)
		(end 148.332518 86.813338)
		(width 0.1016)
		(layer "In2.Cu")
		(net 47)
	)
	(segment
		(start 148.413855 90.344908)
		(end 148.399669 90.32712)
		(width 0.1016)
		(layer "In2.Cu")
		(net 47)
	)
	(segment
		(start 147.569539 91.049143)
		(end 147.590038 91.039271)
		(width 0.1016)
		(layer "In2.Cu")
		(net 47)
	)
	(segment
		(start 148.230356 91.454564)
		(end 148.244541 91.436777)
		(width 0.1016)
		(layer "In2.Cu")
		(net 47)
	)
	(segment
		(start 148.699695 90.903884)
		(end 148.721876 90.908947)
		(width 0.1016)
		(layer "In2.Cu")
		(net 47)
	)
	(segment
		(start 148.807212 90.339185)
		(end 148.825 90.325)
		(width 0.1016)
		(layer "In2.Cu")
		(net 47)
	)
	(segment
		(start 148.37404 91.167196)
		(end 148.391828 91.181382)
		(width 0.1016)
		(layer "In2.Cu")
		(net 47)
	)
	(segment
		(start 148.384735 90.26169)
		(end 148.389798 90.239509)
		(width 0.1016)
		(layer "In2.Cu")
		(net 47)
	)
	(segment
		(start 148.431642 90.187039)
		(end 148.452141 90.177167)
		(width 0.1016)
		(layer "In2.Cu")
		(net 47)
	)
	(segment
		(start 147.551752 91.207012)
		(end 147.537566 91.189224)
		(width 0.1016)
		(layer "In2.Cu")
		(net 47)
	)
	(segment
		(start 148.517724 91.023512)
		(end 148.126488 90.632276)
		(width 0.1016)
		(layer "In2.Cu")
		(net 47)
	)
	(segment
		(start 148.825 90.325)
		(end 148.825 86.925)
		(width 0.1016)
		(layer "In2.Cu")
		(net 47)
	)
	(segment
		(start 148.546843 91.083979)
		(end 148.541782 91.061797)
		(width 0.1016)
		(layer "In2.Cu")
		(net 47)
	)
	(segment
		(start 147.531845 91.618157)
		(end 147.549632 91.603972)
		(width 0.1016)
		(layer "In2.Cu")
		(net 47)
	)
	(segment
		(start 147.549632 91.603972)
		(end 147.57013 91.5941)
		(width 0.1016)
		(layer "In2.Cu")
		(net 47)
	)
	(segment
		(start 147.83912 90.919644)
		(end 147.824934 90.901856)
		(width 0.1016)
		(layer "In2.Cu")
		(net 47)
	)
	(segment
		(start 147.815063 90.814245)
		(end 147.824934 90.793747)
		(width 0.1016)
		(layer "In2.Cu")
		(net 47)
	)
	(segment
		(start 147.592312 91.589037)
		(end 147.615062 91.589038)
		(width 0.1016)
		(layer "In2.Cu")
		(net 47)
	)
	(segment
		(start 147.677648 91.049143)
		(end 147.695436 91.063328)
		(width 0.1016)
		(layer "In2.Cu")
		(net 47)
	)
	(segment
		(start 148.82915 90.774429)
		(end 148.819278 90.753931)
		(width 0.1016)
		(layer "In2.Cu")
		(net 47)
	)
	(segment
		(start 147.886463 91.545325)
		(end 147.872277 91.527537)
		(width 0.1016)
		(layer "In2.Cu")
		(net 47)
	)
	(segment
		(start 148.413855 90.201224)
		(end 148.431642 90.187039)
		(width 0.1016)
		(layer "In2.Cu")
		(net 47)
	)
	(segment
		(start 148.389798 90.306622)
		(end 148.384735 90.284441)
		(width 0.1016)
		(layer "In2.Cu")
		(net 47)
	)
	(segment
		(start 147.695436 91.063328)
		(end 148.086672 91.454564)
		(width 0.1016)
		(layer "In2.Cu")
		(net 47)
	)
	(segment
		(start 147.527695 91.168726)
		(end 147.522632 91.146545)
		(width 0.1016)
		(layer "In2.Cu")
		(net 47)
	)
	(segment
		(start 147.872277 91.671221)
		(end 147.886464 91.653433)
		(width 0.1016)
		(layer "In2.Cu")
		(net 47)
	)
	(segment
		(start 148.412327 91.191252)
		(end 148.434508 91.196315)
		(width 0.1016)
		(layer "In2.Cu")
		(net 47)
	)
	(segment
		(start 148.192071 91.478621)
		(end 148.21257 91.468749)
		(width 0.1016)
		(layer "In2.Cu")
		(net 47)
	)
	(segment
		(start 148.297166 86.785146)
		(end 148.285062 86.765882)
		(width 0.1016)
		(layer "In2.Cu")
		(net 47)
	)
	(segment
		(start 147.815063 90.881358)
		(end 147.81 90.859177)
		(width 0.1016)
		(layer "In2.Cu")
		(net 47)
	)
	(segment
		(start 147.824934 90.901856)
		(end 147.815063 90.881358)
		(width 0.1016)
		(layer "In2.Cu")
		(net 47)
	)
	(segment
		(start 147.789061 91.70034)
		(end 147.811811 91.700341)
		(width 0.1016)
		(layer "In2.Cu")
		(net 47)
	)
	(segment
		(start 148.802835 86.861653)
		(end 148.786747 86.845565)
		(width 0.1016)
		(layer "In2.Cu")
		(net 47)
	)
	(segment
		(start 147.886464 91.653433)
		(end 147.896334 91.632936)
		(width 0.1016)
		(layer "In2.Cu")
		(net 47)
	)
	(segment
		(start 147.965016 90.761775)
		(end 147.982804 90.77596)
		(width 0.1016)
		(layer "In2.Cu")
		(net 47)
	)
	(segment
		(start 148.244542 91.328667)
		(end 148.230356 91.31088)
		(width 0.1016)
		(layer "In2.Cu")
		(net 47)
	)
	(segment
		(start 147.551752 91.063328)
		(end 147.569539 91.049143)
		(width 0.1016)
		(layer "In2.Cu")
		(net 47)
	)
	(segment
		(start 147.833992 91.695278)
		(end 147.854491 91.685406)
		(width 0.1016)
		(layer "In2.Cu")
		(net 47)
	)
	(segment
		(start 148.112302 90.614488)
		(end 148.102431 90.59399)
		(width 0.1016)
		(layer "In2.Cu")
		(net 47)
	)
	(segment
		(start 147.81 90.836426)
		(end 147.815063 90.814245)
		(width 0.1016)
		(layer "In2.Cu")
		(net 47)
	)
	(segment
		(start 148.834211 90.796611)
		(end 148.82915 90.774429)
		(width 0.1016)
		(layer "In2.Cu")
		(net 47)
	)
	(segment
		(start 148.764533 90.354119)
		(end 148.786714 90.349056)
		(width 0.1016)
		(layer "In2.Cu")
		(net 47)
	)
	(segment
		(start 148.384735 90.284441)
		(end 148.384735 90.26169)
		(width 0.1016)
		(layer "In2.Cu")
		(net 47)
	)
	(segment
		(start 147.944518 90.751903)
		(end 147.965016 90.761775)
		(width 0.1016)
		(layer "In2.Cu")
		(net 47)
	)
	(segment
		(start 148.399669 90.32712)
		(end 148.389798 90.306622)
		(width 0.1016)
		(layer "In2.Cu")
		(net 47)
	)
	(segment
		(start 148.679196 90.894014)
		(end 148.699695 90.903884)
		(width 0.1016)
		(layer "In2.Cu")
		(net 47)
	)
	(segment
		(start 148.259476 91.394097)
		(end 148.259475 91.371347)
		(width 0.1016)
		(layer "In2.Cu")
		(net 47)
	)
	(segment
		(start 148.102431 90.526877)
		(end 148.112302 90.506379)
		(width 0.1016)
		(layer "In2.Cu")
		(net 47)
	)
	(segment
		(start 148.744626 90.908948)
		(end 148.766807 90.903885)
		(width 0.1016)
		(layer "In2.Cu")
		(net 47)
	)
	(segment
		(start 147.901397 91.610754)
		(end 147.901396 91.588004)
		(width 0.1016)
		(layer "In2.Cu")
		(net 47)
	)
	(segment
		(start 148.767483 86.610138)
		(end 148.786747 86.598034)
		(width 0.1016)
		(layer "In2.Cu")
		(net 47)
	)
	(segment
		(start 148.332518 86.630261)
		(end 148.353992 86.622747)
		(width 0.1016)
		(layer "In2.Cu")
		(net 47)
	)
	(segment
		(start 148.82915 90.841541)
		(end 148.834212 90.819361)
		(width 0.1016)
		(layer "In2.Cu")
		(net 47)
	)
	(segment
		(start 148.277548 86.699191)
		(end 148.285062 86.677717)
		(width 0.1016)
		(layer "In2.Cu")
		(net 47)
	)
	(segment
		(start 147.590038 91.039271)
		(end 147.612218 91.034209)
		(width 0.1016)
		(layer "In2.Cu")
		(net 47)
	)
	(segment
		(start 148.102431 90.59399)
		(end 148.097368 90.571809)
		(width 0.1016)
		(layer "In2.Cu")
		(net 47)
	)
	(segment
		(start 148.825 86.5186)
		(end 148.825 86.29)
		(width 0.1016)
		(layer "In2.Cu")
		(net 47)
	)
	(segment
		(start 147.175 92.7)
		(end 147.175 91.975)
		(width 0.1016)
		(layer "In2.Cu")
		(net 47)
	)
	(segment
		(start 148.787306 90.894013)
		(end 148.805092 90.879828)
		(width 0.1016)
		(layer "In2.Cu")
		(net 47)
	)
	(segment
		(start 147.615062 91.589038)
		(end 147.637244 91.594099)
		(width 0.1016)
		(layer "In2.Cu")
		(net 47)
	)
	(segment
		(start 148.699103 90.339185)
		(end 148.719601 90.349056)
		(width 0.1016)
		(layer "In2.Cu")
		(net 47)
	)
	(segment
		(start 148.434508 91.196315)
		(end 148.457258 91.196316)
		(width 0.1016)
		(layer "In2.Cu")
		(net 47)
	)
	(segment
		(start 148.275 86.7218)
		(end 148.277548 86.699191)
		(width 0.1016)
		(layer "In2.Cu")
		(net 47)
	)
	(segment
		(start 148.209705 90.459473)
		(end 148.231886 90.464535)
		(width 0.1016)
		(layer "In2.Cu")
		(net 47)
	)
	(segment
		(start 148.746009 86.825947)
		(end 148.7234 86.8234)
		(width 0.1016)
		(layer "In2.Cu")
		(net 47)
	)
	(segment
		(start 148.3766 86.6202)
		(end 148.7234 86.6202)
		(width 0.1016)
		(layer "In2.Cu")
		(net 47)
	)
	(segment
		(start 148.519253 90.177167)
		(end 148.539751 90.187039)
		(width 0.1016)
		(layer "In2.Cu")
		(net 47)
	)
	(segment
		(start 147.657742 91.603971)
		(end 147.675529 91.618157)
		(width 0.1016)
		(layer "In2.Cu")
		(net 47)
	)
	(segment
		(start 148.126488 90.632276)
		(end 148.112302 90.614488)
		(width 0.1016)
		(layer "In2.Cu")
		(net 47)
	)
	(segment
		(start 148.285062 86.765882)
		(end 148.277548 86.744408)
		(width 0.1016)
		(layer "In2.Cu")
		(net 47)
	)
	(segment
		(start 148.802835 86.581946)
		(end 148.814939 86.562682)
		(width 0.1016)
		(layer "In2.Cu")
		(net 47)
	)
	(segment
		(start 148.389798 90.239509)
		(end 148.399669 90.219011)
		(width 0.1016)
		(layer "In2.Cu")
		(net 47)
	)
	(segment
		(start 148.14714 91.483683)
		(end 148.16989 91.483684)
		(width 0.1016)
		(layer "In2.Cu")
		(net 47)
	)
	(segment
		(start 148.741782 90.354119)
		(end 148.764533 90.354119)
		(width 0.1016)
		(layer "In2.Cu")
		(net 47)
	)
	(segment
		(start 147.856907 90.761775)
		(end 147.877406 90.751903)
		(width 0.1016)
		(layer "In2.Cu")
		(net 47)
	)
	(segment
		(start 148.681315 90.325)
		(end 148.699103 90.339185)
		(width 0.1016)
		(layer "In2.Cu")
		(net 47)
	)
	(segment
		(start 147.522632 91.123794)
		(end 147.527695 91.101613)
		(width 0.1016)
		(layer "In2.Cu")
		(net 47)
	)
	(segment
		(start 148.834212 90.819361)
		(end 148.834211 90.796611)
		(width 0.1016)
		(layer "In2.Cu")
		(net 47)
	)
	(segment
		(start 148.499938 91.181381)
		(end 148.517724 91.167196)
		(width 0.1016)
		(layer "In2.Cu")
		(net 47)
	)
	(segment
		(start 146.375 96.175)
		(end 144.775 94.575)
		(width 0.145)
		(layer "F.Cu")
		(net 48)
	)
	(segment
		(start 149.225899 84.624101)
		(end 149.225 84.625)
		(width 0.145)
		(layer "F.Cu")
		(net 48)
	)
	(segment
		(start 144.775 94.575)
		(end 144.775 92.7)
		(width 0.145)
		(layer "F.Cu")
		(net 48)
	)
	(segment
		(start 147.925 98.7)
		(end 147.925 96.65933)
		(width 0.145)
		(layer "F.Cu")
		(net 48)
	)
	(segment
		(start 149.225899 83.249101)
		(end 149.225899 84.624101)
		(width 0.145)
		(layer "F.Cu")
		(net 48)
	)
	(segment
		(start 149.625 82.85)
		(end 149.225899 83.249101)
		(width 0.145)
		(layer "F.Cu")
		(net 48)
	)
	(segment
		(start 147.925 96.65933)
		(end 147.44067 96.175)
		(width 0.145)
		(layer "F.Cu")
		(net 48)
	)
	(segment
		(start 147.44067 96.175)
		(end 146.375 96.175)
		(width 0.145)
		(layer "F.Cu")
		(net 48)
	)
	(via
		(at 144.775 92.7)
		(size 0.45)
		(drill 0.15)
		(layers "F.Cu" "B.Cu")
		(net 48)
	)
	(via
		(at 149.225 84.625)
		(size 0.45)
		(drill 0.15)
		(layers "F.Cu" "B.Cu")
		(net 48)
	)
	(segment
		(start 144.775 85.95)
		(end 145.17821 85.54679)
		(width 0.1016)
		(layer "In2.Cu")
		(net 48)
	)
	(segment
		(start 148.975 85.54679)
		(end 149.225 85.29679)
		(width 0.1016)
		(layer "In2.Cu")
		(net 48)
	)
	(segment
		(start 145.17821 85.54679)
		(end 148.975 85.54679)
		(width 0.1016)
		(layer "In2.Cu")
		(net 48)
	)
	(segment
		(start 144.775 92.7)
		(end 144.775 85.95)
		(width 0.1016)
		(layer "In2.Cu")
		(net 48)
	)
	(segment
		(start 149.225 84.625)
		(end 149.225 85.29679)
		(width 0.1016)
		(layer "In2.Cu")
		(net 48)
	)
	(segment
		(start 147.575899 93.175899)
		(end 147.575899 92.300899)
		(width 0.145)
		(layer "F.Cu")
		(net 49)
	)
	(segment
		(start 151.425 95.625)
		(end 149.2 93.4)
		(width 0.145)
		(layer "F.Cu")
		(net 49)
	)
	(segment
		(start 151.425 98.7)
		(end 151.425 95.625)
		(width 0.145)
		(layer "F.Cu")
		(net 49)
	)
	(segment
		(start 149.2 93.4)
		(end 147.8 93.4)
		(width 0.145)
		(layer "F.Cu")
		(net 49)
	)
	(segment
		(start 147.8 93.4)
		(end 147.575899 93.175899)
		(width 0.145)
		(layer "F.Cu")
		(net 49)
	)
	(segment
		(start 147.575899 92.300899)
		(end 147.575 92.3)
		(width 0.145)
		(layer "F.Cu")
		(net 49)
	)
	(segment
		(start 149.625 87.65)
		(end 149.225 87.25)
		(width 0.145)
		(layer "F.Cu")
		(net 49)
	)
	(via
		(at 149.225 87.25)
		(size 0.45)
		(drill 0.15)
		(layers "F.Cu" "B.Cu")
		(net 49)
	)
	(via
		(at 147.575 92.3)
		(size 0.45)
		(drill 0.15)
		(layers "F.Cu" "B.Cu")
		(net 49)
	)
	(segment
		(start 149.15 88.6488)
		(end 149.3 88.6488)
		(width 0.1016)
		(layer "In2.Cu")
		(net 49)
	)
	(segment
		(start 149.367572 88.488058)
		(end 149.358637 88.473838)
		(width 0.1016)
		(layer "In2.Cu")
		(net 49)
	)
	(segment
		(start 149.103239 89.648437)
		(end 149.091363 89.636561)
		(width 0.1016)
		(layer "In2.Cu")
		(net 49)
	)
	(segment
		(start 149.133311 89.86988)
		(end 149.15 89.868)
		(width 0.1016)
		(layer "In2.Cu")
		(net 49)
	)
	(segment
		(start 149.082428 89.215941)
		(end 149.076881 89.200089)
		(width 0.1016)
		(layer "In2.Cu")
		(net 49)
	)
	(segment
		(start 149.15 88.2424)
		(end 149.3 88.2424)
		(width 0.1016)
		(layer "In2.Cu")
		(net 49)
	)
	(segment
		(start 149.075 87.9642)
		(end 149.075 87.911)
		(width 0.1016)
		(layer "In2.Cu")
		(net 49)
	)
	(segment
		(start 149.075 89.5366)
		(end 149.076881 89.51991)
		(width 0.1016)
		(layer "In2.Cu")
		(net 49)
	)
	(segment
		(start 149.103239 88.022837)
		(end 149.091363 88.010961)
		(width 0.1016)
		(layer "In2.Cu")
		(net 49)
	)
	(segment
		(start 149.082428 89.622341)
		(end 149.076881 89.606489)
		(width 0.1016)
		(layer "In2.Cu")
		(net 49)
	)
	(segment
		(start 149.358637 89.286638)
		(end 149.346761 89.274762)
		(width 0.1016)
		(layer "In2.Cu")
		(net 49)
	)
	(segment
		(start 149.082428 89.910458)
		(end 149.091363 89.896238)
		(width 0.1016)
		(layer "In2.Cu")
		(net 49)
	)
	(segment
		(start 149.373119 88.50391)
		(end 149.367572 88.488058)
		(width 0.1016)
		(layer "In2.Cu")
		(net 49)
	)
	(segment
		(start 149.367572 90.231941)
		(end 149.373119 90.216089)
		(width 0.1016)
		(layer "In2.Cu")
		(net 49)
	)
	(segment
		(start 149.332541 88.046627)
		(end 149.316689 88.04108)
		(width 0.1016)
		(layer "In2.Cu")
		(net 49)
	)
	(segment
		(start 149.375 91.825)
		(end 149.375 91.7718)
		(width 0.1016)
		(layer "In2.Cu")
		(net 49)
	)
	(segment
		(start 149.082428 91.536058)
		(end 149.091363 91.521838)
		(width 0.1016)
		(layer "In2.Cu")
		(net 49)
	)
	(segment
		(start 148.501138 91.957317)
		(end 148.508652 91.978791)
		(width 0.1016)
		(layer "In2.Cu")
		(net 49)
	)
	(segment
		(start 149.332541 90.078627)
		(end 149.316689 90.07308)
		(width 0.1016)
		(layer "In2.Cu")
		(net 49)
	)
	(segment
		(start 149.367572 89.012741)
		(end 149.373119 88.996889)
		(width 0.1016)
		(layer "In2.Cu")
		(net 49)
	)
	(segment
		(start 149.133311 88.037319)
		(end 149.117459 88.031772)
		(width 0.1016)
		(layer "In2.Cu")
		(net 49)
	)
	(segment
		(start 149.375 90.959)
		(end 149.373119 90.94231)
		(width 0.1016)
		(layer "In2.Cu")
		(net 49)
	)
	(segment
		(start 149.375 89.3866)
		(end 149.375 89.3334)
		(width 0.1016)
		(layer "In2.Cu")
		(net 49)
	)
	(segment
		(start 149.133311 91.288519)
		(end 149.117459 91.282972)
		(width 0.1016)
		(layer "In2.Cu")
		(net 49)
	)
	(segment
		(start 149.375 90.5526)
		(end 149.373119 90.53591)
		(width 0.1016)
		(layer "In2.Cu")
		(net 49)
	)
	(segment
		(start 149.3 88.852)
		(end 149.15 88.852)
		(width 0.1016)
		(layer "In2.Cu")
		(net 49)
	)
	(segment
		(start 149.117459 91.501027)
		(end 149.133311 91.49548)
		(width 0.1016)
		(layer "In2.Cu")
		(net 49)
	)
	(segment
		(start 149.367572 90.113658)
		(end 149.358637 90.099438)
		(width 0.1016)
		(layer "In2.Cu")
		(net 49)
	)
	(segment
		(start 149.3 89.2584)
		(end 149.15 89.2584)
		(width 0.1016)
		(layer "In2.Cu")
		(net 49)
	)
	(segment
		(start 149.091363 88.823761)
		(end 149.082428 88.809541)
		(width 0.1016)
		(layer "In2.Cu")
		(net 49)
	)
	(segment
		(start 149.346761 91.477237)
		(end 149.358637 91.465361)
		(width 0.1016)
		(layer "In2.Cu")
		(net 49)
	)
	(segment
		(start 149.15 89.2584)
		(end 149.133311 89.256519)
		(width 0.1016)
		(layer "In2.Cu")
		(net 49)
	)
	(segment
		(start 147.575 92.3)
		(end 147.8 92.3)
		(width 0.1016)
		(layer "In2.Cu")
		(net 49)
	)
	(segment
		(start 149.117459 89.062627)
		(end 149.133311 89.05708)
		(width 0.1016)
		(layer "In2.Cu")
		(net 49)
	)
	(segment
		(start 149.103239 89.071562)
		(end 149.117459 89.062627)
		(width 0.1016)
		(layer "In2.Cu")
		(net 49)
	)
	(segment
		(start 148.9 92.3)
		(end 149.225 91.975)
		(width 0.1016)
		(layer "In2.Cu")
		(net 49)
	)
	(segment
		(start 149.367572 89.707258)
		(end 149.358637 89.693038)
		(width 0.1016)
		(layer "In2.Cu")
		(net 49)
	)
	(segment
		(start 149.076881 91.232089)
		(end 149.075 91.2154)
		(width 0.1016)
		(layer "In2.Cu")
		(net 49)
	)
	(segment
		(start 149.082428 87.996741)
		(end 149.076881 87.980889)
		(width 0.1016)
		(layer "In2.Cu")
		(net 49)
	)
	(segment
		(start 149.373119 89.809689)
		(end 149.375 89.793)
		(width 0.1016)
		(layer "In2.Cu")
		(net 49)
	)
	(segment
		(start 149.3 90.884)
		(end 149.15 90.884)
		(width 0.1016)
		(layer "In2.Cu")
		(net 49)
	)
	(segment
		(start 149.367572 90.926458)
		(end 149.358637 90.912238)
		(width 0.1016)
		(layer "In2.Cu")
		(net 49)
	)
	(segment
		(start 148.308 92.001399)
		(end 148.310547 91.978791)
		(width 0.1016)
		(layer "In2.Cu")
		(net 49)
	)
	(segment
		(start 149.316689 89.26028)
		(end 149.3 89.2584)
		(width 0.1016)
		(layer "In2.Cu")
		(net 49)
	)
	(segment
		(start 149.075 89.5898)
		(end 149.075 89.5366)
		(width 0.1016)
		(layer "In2.Cu")
		(net 49)
	)
	(segment
		(start 149.375 91.0122)
		(end 149.375 90.959)
		(width 0.1016)
		(layer "In2.Cu")
		(net 49)
	)
	(segment
		(start 149.103239 90.054837)
		(end 149.091363 90.042961)
		(width 0.1016)
		(layer "In2.Cu")
		(net 49)
	)
	(segment
		(start 149.091363 90.302638)
		(end 149.103239 90.290762)
		(width 0.1016)
		(layer "In2.Cu")
		(net 49)
	)
	(segment
		(start 149.267458 87.625372)
		(end 149.253238 87.616437)
		(width 0.1016)
		(layer "In2.Cu")
		(net 49)
	)
	(segment
		(start 149.091363 90.042961)
		(end 149.082428 90.028741)
		(width 0.1016)
		(layer "In2.Cu")
		(net 49)
	)
	(segment
		(start 149.225 91.975)
		(end 149.22688 91.95831)
		(width 0.1016)
		(layer "In2.Cu")
		(net 49)
	)
	(segment
		(start 149.346761 88.868362)
		(end 149.332541 88.859427)
		(width 0.1016)
		(layer "In2.Cu")
		(net 49)
	)
	(segment
		(start 149.117459 91.282972)
		(end 149.103239 91.274037)
		(width 0.1016)
		(layer "In2.Cu")
		(net 49)
	)
	(segment
		(start 147.923765 91.938053)
		(end 147.939853 91.921965)
		(width 0.1016)
		(layer "In2.Cu")
		(net 49)
	)
	(segment
		(start 149.375 90.1462)
		(end 149.373119 90.12951)
		(width 0.1016)
		(layer "In2.Cu")
		(net 49)
	)
	(segment
		(start 149.075 91.2154)
		(end 149.075 91.1622)
		(width 0.1016)
		(layer "In2.Cu")
		(net 49)
	)
	(segment
		(start 149.358637 89.433361)
		(end 149.367572 89.419141)
		(width 0.1016)
		(layer "In2.Cu")
		(net 49)
	)
	(segment
		(start 149.3 89.0552)
		(end 149.316689 89.053319)
		(width 0.1016)
		(layer "In2.Cu")
		(net 49)
	)
	(segment
		(start 148.1048 92.1984)
		(end 148.107347 92.221009)
		(width 0.1016)
		(layer "In2.Cu")
		(net 49)
	)
	(segment
		(start 149.358637 90.246161)
		(end 149.367572 90.231941)
		(width 0.1016)
		(layer "In2.Cu")
		(net 49)
	)
	(segment
		(start 149.133311 89.05708)
		(end 149.15 89.0552)
		(width 0.1016)
		(layer "In2.Cu")
		(net 49)
	)
	(segment
		(start 149.076881 87.89431)
		(end 149.082428 87.878458)
		(width 0.1016)
		(layer "In2.Cu")
		(net 49)
	)
	(segment
		(start 149.332541 87.828572)
		(end 149.346761 87.819637)
		(width 0.1016)
		(layer "In2.Cu")
		(net 49)
	)
	(segment
		(start 149.367572 91.332858)
		(end 149.358637 91.318638)
		(width 0.1016)
		(layer "In2.Cu")
		(net 49)
	)
	(segment
		(start 149.103239 90.290762)
		(end 149.117459 90.281827)
		(width 0.1016)
		(layer "In2.Cu")
		(net 49)
	)
	(segment
		(start 148.102252 91.978791)
		(end 148.1048 92.001399)
		(width 0.1016)
		(layer "In2.Cu")
		(net 49)
	)
	(segment
		(start 149.117459 89.250972)
		(end 149.103239 89.242037)
		(width 0.1016)
		(layer "In2.Cu")
		(net 49)
	)
	(segment
		(start 149.075 91.1622)
		(end 149.076881 91.14551)
		(width 0.1016)
		(layer "In2.Cu")
		(net 49)
	)
	(segment
		(start 148.082634 91.938053)
		(end 148.094738 91.957317)
		(width 0.1016)
		(layer "In2.Cu")
		(net 49)
	)
	(segment
		(start 149.082428 88.809541)
		(end 149.076881 88.793689)
		(width 0.1016)
		(layer "In2.Cu")
		(net 49)
	)
	(segment
		(start 149.133311 90.069319)
		(end 149.117459 90.063772)
		(width 0.1016)
		(layer "In2.Cu")
		(net 49)
	)
	(segment
		(start 149.076881 89.200089)
		(end 149.075 89.1834)
		(width 0.1016)
		(layer "In2.Cu")
		(net 49)
	)
	(segment
		(start 148.143053 92.277835)
		(end 148.162317 92.289939)
		(width 0.1016)
		(layer "In2.Cu")
		(net 49)
	)
	(segment
		(start 149.316689 91.898119)
		(end 149.332541 91.892572)
		(width 0.1016)
		(layer "In2.Cu")
		(net 49)
	)
	(segment
		(start 149.133311 89.662919)
		(end 149.117459 89.657372)
		(width 0.1016)
		(layer "In2.Cu")
		(net 49)
	)
	(segment
		(start 149.332541 89.265827)
		(end 149.316689 89.26028)
		(width 0.1016)
		(layer "In2.Cu")
		(net 49)
	)
	(segment
		(start 148.432208 91.902347)
		(end 148.453682 91.909861)
		(width 0.1016)
		(layer "In2.Cu")
		(net 49)
	)
	(segment
		(start 149.225 87.377927)
		(end 149.225 87.25)
		(width 0.1016)
		(layer "In2.Cu")
		(net 49)
	)
	(segment
		(start 149.346761 90.664437)
		(end 149.358637 90.652561)
		(width 0.1016)
		(layer "In2.Cu")
		(net 49)
	)
	(segment
		(start 149.075 88.3706)
		(end 149.075 88.3174)
		(width 0.1016)
		(layer "In2.Cu")
		(net 49)
	)
	(segment
		(start 149.076881 88.793689)
		(end 149.075 88.777)
		(width 0.1016)
		(layer "In2.Cu")
		(net 49)
	)
	(segment
		(start 148.513747 92.221009)
		(end 148.521261 92.242483)
		(width 0.1016)
		(layer "In2.Cu")
		(net 49)
	)
	(segment
		(start 148.386991 91.902347)
		(end 148.4096 91.899799)
		(width 0.1016)
		(layer "In2.Cu")
		(net 49)
	)
	(segment
		(start 149.22688 87.574489)
		(end 149.225 87.5578)
		(width 0.1016)
		(layer "In2.Cu")
		(net 49)
	)
	(segment
		(start 148.472946 91.921965)
		(end 148.489034 91.938053)
		(width 0.1016)
		(layer "In2.Cu")
		(net 49)
	)
	(segment
		(start 149.3 89.868)
		(end 149.316689 89.866119)
		(width 0.1016)
		(layer "In2.Cu")
		(net 49)
	)
	(segment
		(start 149.091363 90.855761)
		(end 149.082428 90.841541)
		(width 0.1016)
		(layer "In2.Cu")
		(net 49)
	)
	(segment
		(start 149.367572 87.675258)
		(end 149.358637 87.661038)
		(width 0.1016)
		(layer "In2.Cu")
		(net 49)
	)
	(segment
		(start 149.15 90.6808)
		(end 149.3 90.6808)
		(width 0.1016)
		(layer "In2.Cu")
		(net 49)
	)
	(segment
		(start 149.076881 90.73911)
		(end 149.082428 90.723258)
		(width 0.1016)
		(layer "In2.Cu")
		(net 49)
	)
	(segment
		(start 149.346761 88.226037)
		(end 149.358637 88.214161)
		(width 0.1016)
		(layer "In2.Cu")
		(net 49)
	)
	(segment
		(start 149.373119 88.09751)
		(end 149.367572 88.081658)
		(width 0.1016)
		(layer "In2.Cu")
		(net 49)
	)
	(segment
		(start 149.082428 91.247941)
		(end 149.076881 91.232089)
		(width 0.1016)
		(layer "In2.Cu")
		(net 49)
	)
	(segment
		(start 149.117459 88.844572)
		(end 149.103239 88.835637)
		(width 0.1016)
		(layer "In2.Cu")
		(net 49)
	)
	(segment
		(start 149.117459 89.657372)
		(end 149.103239 89.648437)
		(width 0.1016)
		(layer "In2.Cu")
		(net 49)
	)
	(segment
		(start 149.375 88.1142)
		(end 149.373119 88.09751)
		(width 0.1016)
		(layer "In2.Cu")
		(net 49)
	)
	(segment
		(start 149.373119 87.777689)
		(end 149.375 87.761)
		(width 0.1016)
		(layer "In2.Cu")
		(net 49)
	)
	(segment
		(start 149.373119 90.216089)
		(end 149.375 90.1994)
		(width 0.1016)
		(layer "In2.Cu")
		(net 49)
	)
	(segment
		(start 149.117459 91.094627)
		(end 149.133311 91.08908)
		(width 0.1016)
		(layer "In2.Cu")
		(net 49)
	)
	(segment
		(start 148.489034 91.938053)
		(end 148.501138 91.957317)
		(width 0.1016)
		(layer "In2.Cu")
		(net 49)
	)
	(segment
		(start 149.117459 90.688227)
		(end 149.133311 90.68268)
		(width 0.1016)
		(layer "In2.Cu")
		(net 49)
	)
	(segment
		(start 149.332541 89.454172)
		(end 149.346761 89.445237)
		(width 0.1016)
		(layer "In2.Cu")
		(net 49)
	)
	(segment
		(start 149.241362 87.604561)
		(end 149.232427 87.590341)
		(width 0.1016)
		(layer "In2.Cu")
		(net 49)
	)
	(segment
		(start 149.367572 91.857541)
		(end 149.373119 91.841689)
		(width 0.1016)
		(layer "In2.Cu")
		(net 49)
	)
	(segment
		(start 148.250482 92.289939)
		(end 148.269746 92.277835)
		(width 0.1016)
		(layer "In2.Cu")
		(net 49)
	)
	(segment
		(start 149.075 89.943)
		(end 149.076881 89.92631)
		(width 0.1016)
		(layer "In2.Cu")
		(net 49)
	)
	(segment
		(start 149.103239 88.665162)
		(end 149.117459 88.656227)
		(width 0.1016)
		(layer "In2.Cu")
		(net 49)
	)
	(segment
		(start 149.15 87.836)
		(end 149.3 87.836)
		(width 0.1016)
		(layer "In2.Cu")
		(net 49)
	)
	(segment
		(start 149.082428 87.878458)
		(end 149.091363 87.864238)
		(width 0.1016)
		(layer "In2.Cu")
		(net 49)
	)
	(segment
		(start 147.8 92.3)
		(end 147.822608 92.297453)
		(width 0.1016)
		(layer "In2.Cu")
		(net 49)
	)
	(segment
		(start 149.075 89.1834)
		(end 149.075 89.1302)
		(width 0.1016)
		(layer "In2.Cu")
		(net 49)
	)
	(segment
		(start 149.082428 88.284858)
		(end 149.091363 88.270638)
		(width 0.1016)
		(layer "In2.Cu")
		(net 49)
	)
	(segment
		(start 149.346761 87.819637)
		(end 149.358637 87.807761)
		(width 0.1016)
		(layer "In2.Cu")
		(net 49)
	)
	(segment
		(start 149.075 90.7558)
		(end 149.076881 90.73911)
		(width 0.1016)
		(layer "In2.Cu")
		(net 49)
	)
	(segment
		(start 149.075 91.5686)
		(end 149.076881 91.55191)
		(width 0.1016)
		(layer "In2.Cu")
		(net 49)
	)
	(segment
		(start 149.358637 88.473838)
		(end 149.346761 88.461962)
		(width 0.1016)
		(layer "In2.Cu")
		(net 49)
	)
	(segment
		(start 149.346761 89.445237)
		(end 149.358637 89.433361)
		(width 0.1016)
		(layer "In2.Cu")
		(net 49)
	)
	(segment
		(start 148.297938 92.242483)
		(end 148.305452 92.221009)
		(width 0.1016)
		(layer "In2.Cu")
		(net 49)
	)
	(segment
		(start 149.076881 89.606489)
		(end 149.075 89.5898)
		(width 0.1016)
		(layer "In2.Cu")
		(net 49)
	)
	(segment
		(start 149.316689 88.240519)
		(end 149.332541 88.234972)
		(width 0.1016)
		(layer "In2.Cu")
		(net 49)
	)
	(segment
		(start 149.375 91.3654)
		(end 149.373119 91.34871)
		(width 0.1016)
		(layer "In2.Cu")
		(net 49)
	)
	(segment
		(start 149.367572 91.044741)
		(end 149.373119 91.028889)
		(width 0.1016)
		(layer "In2.Cu")
		(net 49)
	)
	(segment
		(start 149.076881 90.012889)
		(end 149.075 89.9962)
		(width 0.1016)
		(layer "In2.Cu")
		(net 49)
	)
	(segment
		(start 149.082428 89.504058)
		(end 149.091363 89.489838)
		(width 0.1016)
		(layer "In2.Cu")
		(net 49)
	)
	(segment
		(start 149.091363 88.417361)
		(end 149.082428 88.403141)
		(width 0.1016)
		(layer "In2.Cu")
		(net 49)
	)
	(segment
		(start 149.358637 89.693038)
		(end 149.346761 89.681162)
		(width 0.1016)
		(layer "In2.Cu")
		(net 49)
	)
	(segment
		(start 148.305452 92.221009)
		(end 148.308 92.1984)
		(width 0.1016)
		(layer "In2.Cu")
		(net 49)
	)
	(segment
		(start 149.225 87.5578)
		(end 149.225 87.377927)
		(width 0.1016)
		(layer "In2.Cu")
		(net 49)
	)
	(segment
		(start 149.346761 90.087562)
		(end 149.332541 90.078627)
		(width 0.1016)
		(layer "In2.Cu")
		(net 49)
	)
	(segment
		(start 149.15 90.2744)
		(end 149.3 90.2744)
		(width 0.1016)
		(layer "In2.Cu")
		(net 49)
	)
	(segment
		(start 149.367572 89.419141)
		(end 149.373119 89.403289)
		(width 0.1016)
		(layer "In2.Cu")
		(net 49)
	)
	(segment
		(start 149.375 88.9802)
		(end 149.375 88.927)
		(width 0.1016)
		(layer "In2.Cu")
		(net 49)
	)
	(segment
		(start 149.373119 88.590489)
		(end 149.375 88.5738)
		(width 0.1016)
		(layer "In2.Cu")
		(net 49)
	)
	(segment
		(start 149.103239 90.697162)
		(end 149.117459 90.688227)
		(width 0.1016)
		(layer "In2.Cu")
		(net 49)
	)
	(segment
		(start 149.3 89.6648)
		(end 149.15 89.6648)
		(width 0.1016)
		(layer "In2.Cu")
		(net 49)
	)
	(segment
		(start 149.332541 91.704227)
		(end 149.316689 91.69868)
		(width 0.1016)
		(layer "In2.Cu")
		(net 49)
	)
	(segment
		(start 149.373119 89.72311)
		(end 149.367572 89.707258)
		(width 0.1016)
		(layer "In2.Cu")
		(net 49)
	)
	(segment
		(start 149.316689 87.63468)
		(end 149.28331 87.630919)
		(width 0.1016)
		(layer "In2.Cu")
		(net 49)
	)
	(segment
		(start 149.091363 90.709038)
		(end 149.103239 90.697162)
		(width 0.1016)
		(layer "In2.Cu")
		(net 49)
	)
	(segment
		(start 149.375 88.5206)
		(end 149.373119 88.50391)
		(width 0.1016)
		(layer "In2.Cu")
		(net 49)
	)
	(segment
		(start 147.9016 92.1984)
		(end 147.9016 92.001399)
		(width 0.1016)
		(layer "In2.Cu")
		(net 49)
	)
	(segment
		(start 148.025808 91.902347)
		(end 148.047282 91.909861)
		(width 0.1016)
		(layer "In2.Cu")
		(net 49)
	)
	(segment
		(start 149.346761 91.713162)
		(end 149.332541 91.704227)
		(width 0.1016)
		(layer "In2.Cu")
		(net 49)
	)
	(segment
		(start 149.15 89.4616)
		(end 149.3 89.4616)
		(width 0.1016)
		(layer "In2.Cu")
		(net 49)
	)
	(segment
		(start 149.373119 90.622489)
		(end 149.375 90.6058)
		(width 0.1016)
		(layer "In2.Cu")
		(net 49)
	)
	(segment
		(start 147.879434 92.261747)
		(end 147.891538 92.242483)
		(width 0.1016)
		(layer "In2.Cu")
		(net 49)
	)
	(segment
		(start 149.3 89.4616)
		(end 149.316689 89.459719)
		(width 0.1016)
		(layer "In2.Cu")
		(net 49)
	)
	(segment
		(start 149.103239 91.680437)
		(end 149.091363 91.668561)
		(width 0.1016)
		(layer "In2.Cu")
		(net 49)
	)
	(segment
		(start 149.373119 91.028889)
		(end 149.375 91.0122)
		(width 0.1016)
		(layer "In2.Cu")
		(net 49)
	)
	(segment
		(start 149.332541 90.891427)
		(end 149.316689 90.88588)
		(width 0.1016)
		(layer "In2.Cu")
		(net 49)
	)
	(segment
		(start 149.358637 89.026961)
		(end 149.367572 89.012741)
		(width 0.1016)
		(layer "In2.Cu")
		(net 49)
	)
	(segment
		(start 149.133311 89.256519)
		(end 149.117459 89.250972)
		(width 0.1016)
		(layer "In2.Cu")
		(net 49)
	)
	(segment
		(start 149.133311 91.49548)
		(end 149.15 91.4936)
		(width 0.1016)
		(layer "In2.Cu")
		(net 49)
	)
	(segment
		(start 149.358637 89.839761)
		(end 149.367572 89.825541)
		(width 0.1016)
		(layer "In2.Cu")
		(net 49)
	)
	(segment
		(start 149.3 90.2744)
		(end 149.316689 90.272519)
		(width 0.1016)
		(layer "In2.Cu")
		(net 49)
	)
	(segment
		(start 149.091363 91.521838)
		(end 149.103239 91.509962)
		(width 0.1016)
		(layer "In2.Cu")
		(net 49)
	)
	(segment
		(start 149.373119 91.435289)
		(end 149.375 91.4186)
		(width 0.1016)
		(layer "In2.Cu")
		(net 49)
	)
	(segment
		(start 149.316689 90.88588)
		(end 149.3 90.884)
		(width 0.1016)
		(layer "In2.Cu")
		(net 49)
	)
	(segment
		(start 149.332541 89.860572)
		(end 149.346761 89.851637)
		(width 0.1016)
		(layer "In2.Cu")
		(net 49)
	)
	(segment
		(start 149.117459 90.876572)
		(end 149.103239 90.867637)
		(width 0.1016)
		(layer "In2.Cu")
		(net 49)
	)
	(segment
		(start 149.3 91.4936)
		(end 149.316689 91.491719)
		(width 0.1016)
		(layer "In2.Cu")
		(net 49)
	)
	(segment
		(start 147.844082 92.289939)
		(end 147.863346 92.277835)
		(width 0.1016)
		(layer "In2.Cu")
		(net 49)
	)
	(segment
		(start 149.082428 90.723258)
		(end 149.091363 90.709038)
		(width 0.1016)
		(layer "In2.Cu")
		(net 49)
	)
	(segment
		(start 148.318061 91.957317)
		(end 148.330165 91.938053)
		(width 0.1016)
		(layer "In2.Cu")
		(net 49)
	)
	(segment
		(start 149.3 91.2904)
		(end 149.15 91.2904)
		(width 0.1016)
		(layer "In2.Cu")
		(net 49)
	)
	(segment
		(start 149.346761 88.632437)
		(end 149.358637 88.620561)
		(width 0.1016)
		(layer "In2.Cu")
		(net 49)
	)
	(segment
		(start 149.358637 91.725038)
		(end 149.346761 91.713162)
		(width 0.1016)
		(layer "In2.Cu")
		(net 49)
	)
	(segment
		(start 149.367572 88.199941)
		(end 149.373119 88.184089)
		(width 0.1016)
		(layer "In2.Cu")
		(net 49)
	)
	(segment
		(start 149.082428 90.841541)
		(end 149.076881 90.825689)
		(width 0.1016)
		(layer "In2.Cu")
		(net 49)
	)
	(segment
		(start 149.253238 91.916362)
		(end 149.267458 91.907427)
		(width 0.1016)
		(layer "In2.Cu")
		(net 49)
	)
	(segment
		(start 149.133311 90.882119)
		(end 149.117459 90.876572)
		(width 0.1016)
		(layer "In2.Cu")
		(net 49)
	)
	(segment
		(start 149.28331 91.90188)
		(end 149.316689 91.898119)
		(width 0.1016)
		(layer "In2.Cu")
		(net 49)
	)
	(segment
		(start 149.373119 88.184089)
		(end 149.375 88.1674)
		(width 0.1016)
		(layer "In2.Cu")
		(net 49)
	)
	(segment
		(start 148.1048 92.001399)
		(end 148.1048 92.1984)
		(width 0.1016)
		(layer "In2.Cu")
		(net 49)
	)
	(segment
		(start 149.316689 91.085319)
		(end 149.332541 91.079772)
		(width 0.1016)
		(layer "In2.Cu")
		(net 49)
	)
	(segment
		(start 149.076881 89.51991)
		(end 149.082428 89.504058)
		(width 0.1016)
		(layer "In2.Cu")
		(net 49)
	)
	(segment
		(start 149.316689 90.07308)
		(end 149.3 90.0712)
		(width 0.1016)
		(layer "In2.Cu")
		(net 49)
	)
	(segment
		(start 148.453682 91.909861)
		(end 148.472946 91.921965)
		(width 0.1016)
		(layer "In2.Cu")
		(net 49)
	)
	(segment
		(start 149.15 89.868)
		(end 149.3 89.868)
		(width 0.1016)
		(layer "In2.Cu")
		(net 49)
	)
	(segment
		(start 149.358637 87.807761)
		(end 149.367572 87.793541)
		(width 0.1016)
		(layer "In2.Cu")
		(net 49)
	)
	(segment
		(start 149.103239 89.477962)
		(end 149.117459 89.469027)
		(width 0.1016)
		(layer "In2.Cu")
		(net 49)
	)
	(segment
		(start 149.3 91.6968)
		(end 149.15 91.6968)
		(width 0.1016)
		(layer "In2.Cu")
		(net 49)
	)
	(segment
		(start 148.590191 92.297453)
		(end 148.6128 92.3)
		(width 0.1016)
		(layer "In2.Cu")
		(net 49)
	)
	(segment
		(start 149.358637 88.067438)
		(end 149.346761 88.055562)
		(width 0.1016)
		(layer "In2.Cu")
		(net 49)
	)
	(segment
		(start 149.076881 91.55191)
		(end 149.082428 91.536058)
		(width 0.1016)
		(layer "In2.Cu")
		(net 49)
	)
	(segment
		(start 149.367572 87.793541)
		(end 149.373119 87.777689)
		(width 0.1016)
		(layer "In2.Cu")
		(net 49)
	)
	(segment
		(start 149.117459 90.281827)
		(end 149.133311 90.27628)
		(width 0.1016)
		(layer "In2.Cu")
		(net 49)
	)
	(segment
		(start 149.082428 88.691258)
		(end 149.091363 88.677038)
		(width 0.1016)
		(layer "In2.Cu")
		(net 49)
	)
	(segment
		(start 149.375 89.7398)
		(end 149.373119 89.72311)
		(width 0.1016)
		(layer "In2.Cu")
		(net 49)
	)
	(segment
		(start 149.367572 90.520058)
		(end 149.358637 90.505838)
		(width 0.1016)
		(layer "In2.Cu")
		(net 49)
	)
	(segment
		(start 149.3 91.0872)
		(end 149.316689 91.085319)
		(width 0.1016)
		(layer "In2.Cu")
		(net 49)
	)
	(segment
		(start 148.183791 92.297453)
		(end 148.2064 92.3)
		(width 0.1016)
		(layer "In2.Cu")
		(net 49)
	)
	(segment
		(start 149.075 90.809)
		(end 149.075 90.7558)
		(width 0.1016)
		(layer "In2.Cu")
		(net 49)
	)
	(segment
		(start 149.076881 91.14551)
		(end 149.082428 91.129658)
		(width 0.1016)
		(layer "In2.Cu")
		(net 49)
	)
	(segment
		(start 149.316689 91.491719)
		(end 149.332541 91.486172)
		(width 0.1016)
		(layer "In2.Cu")
		(net 49)
	)
	(segment
		(start 149.316689 90.272519)
		(end 149.332541 90.266972)
		(width 0.1016)
		(layer "In2.Cu")
		(net 49)
	)
	(segment
		(start 149.332541 88.453027)
		(end 149.316689 88.44748)
		(width 0.1016)
		(layer "In2.Cu")
		(net 49)
	)
	(segment
		(start 148.047282 91.909861)
		(end 148.066546 91.921965)
		(width 0.1016)
		(layer "In2.Cu")
		(net 49)
	)
	(segment
		(start 149.232427 87.590341)
		(end 149.22688 87.574489)
		(width 0.1016)
		(layer "In2.Cu")
		(net 49)
	)
	(segment
		(start 149.332541 88.859427)
		(end 149.316689 88.85388)
		(width 0.1016)
		(layer "In2.Cu")
		(net 49)
	)
	(segment
		(start 147.9016 92.001399)
		(end 147.904147 91.978791)
		(width 0.1016)
		(layer "In2.Cu")
		(net 49)
	)
	(segment
		(start 149.075 87.911)
		(end 149.076881 87.89431)
		(width 0.1016)
		(layer "In2.Cu")
		(net 49)
	)
	(segment
		(start 149.373119 87.69111)
		(end 149.367572 87.675258)
		(width 0.1016)
		(layer "In2.Cu")
		(net 49)
	)
	(segment
		(start 149.316689 90.47948)
		(end 149.3 90.4776)
		(width 0.1016)
		(layer "In2.Cu")
		(net 49)
	)
	(segment
		(start 149.076881 88.70711)
		(end 149.082428 88.691258)
		(width 0.1016)
		(layer "In2.Cu")
		(net 49)
	)
	(segment
		(start 149.133311 87.83788)
		(end 149.15 87.836)
		(width 0.1016)
		(layer "In2.Cu")
		(net 49)
	)
	(segment
		(start 149.3 90.4776)
		(end 149.15 90.4776)
		(width 0.1016)
		(layer "In2.Cu")
		(net 49)
	)
	(segment
		(start 148.2064 92.3)
		(end 148.229008 92.297453)
		(width 0.1016)
		(layer "In2.Cu")
		(net 49)
	)
	(segment
		(start 149.332541 90.673372)
		(end 149.346761 90.664437)
		(width 0.1016)
		(layer "In2.Cu")
		(net 49)
	)
	(segment
		(start 149.091363 88.677038)
		(end 149.103239 88.665162)
		(width 0.1016)
		(layer "In2.Cu")
		(net 49)
	)
	(segment
		(start 148.549453 92.277835)
		(end 148.568717 92.289939)
		(width 0.1016)
		(layer "In2.Cu")
		(net 49)
	)
	(segment
		(start 149.076881 88.30071)
		(end 149.082428 88.284858)
		(width 0.1016)
		(layer "In2.Cu")
		(net 49)
	)
	(segment
		(start 149.373119 89.31671)
		(end 149.367572 89.300858)
		(width 0.1016)
		(layer "In2.Cu")
		(net 49)
	)
	(segment
		(start 149.316689 89.866119)
		(end 149.332541 89.860572)
		(width 0.1016)
		(layer "In2.Cu")
		(net 49)
	)
	(segment
		(start 149.358637 90.099438)
		(end 149.346761 90.087562)
		(width 0.1016)
		(layer "In2.Cu")
		(net 49)
	)
	(segment
		(start 149.091363 91.115438)
		(end 149.103239 91.103562)
		(width 0.1016)
		(layer "In2.Cu")
		(net 49)
	)
	(segment
		(start 149.375 87.761)
		(end 149.375 87.7078)
		(width 0.1016)
		(layer "In2.Cu")
		(net 49)
	)
	(segment
		(start 149.117459 88.656227)
		(end 149.133311 88.65068)
		(width 0.1016)
		(layer "In2.Cu")
		(net 49)
	)
	(segment
		(start 149.375 89.793)
		(end 149.375 89.7398)
		(width 0.1016)
		(layer "In2.Cu")
		(net 49)
	)
	(segment
		(start 148.6128 92.3)
		(end 148.9 92.3)
		(width 0.1016)
		(layer "In2.Cu")
		(net 49)
	)
	(segment
		(start 149.082428 90.028741)
		(end 149.076881 90.012889)
		(width 0.1016)
		(layer "In2.Cu")
		(net 49)
	)
	(segment
		(start 148.114861 92.242483)
		(end 148.126965 92.261747)
		(width 0.1016)
		(layer "In2.Cu")
		(net 49)
	)
	(segment
		(start 149.3 88.2424)
		(end 149.316689 88.240519)
		(width 0.1016)
		(layer "In2.Cu")
		(net 49)
	)
	(segment
		(start 149.103239 91.509962)
		(end 149.117459 91.501027)
		(width 0.1016)
		(layer "In2.Cu")
		(net 49)
	)
	(segment
		(start 149.075 89.1302)
		(end 149.076881 89.11351)
		(width 0.1016)
		(layer "In2.Cu")
		(net 49)
	)
	(segment
		(start 149.28331 87.630919)
		(end 149.267458 87.625372)
		(width 0.1016)
		(layer "In2.Cu")
		(net 49)
	)
	(segment
		(start 149.075 89.9962)
		(end 149.075 89.943)
		(width 0.1016)
		(layer "In2.Cu")
		(net 49)
	)
	(segment
		(start 149.076881 90.825689)
		(end 149.075 90.809)
		(width 0.1016)
		(layer "In2.Cu")
		(net 49)
	)
	(segment
		(start 149.332541 88.234972)
		(end 149.346761 88.226037)
		(width 0.1016)
		(layer "In2.Cu")
		(net 49)
	)
	(segment
		(start 149.375 88.1674)
		(end 149.375 88.1142)
		(width 0.1016)
		(layer "In2.Cu")
		(net 49)
	)
	(segment
		(start 149.332541 91.297827)
		(end 149.316689 91.29228)
		(width 0.1016)
		(layer "In2.Cu")
		(net 49)
	)
	(segment
		(start 149.091363 91.262161)
		(end 149.082428 91.247941)
		(width 0.1016)
		(layer "In2.Cu")
		(net 49)
	)
	(segment
		(start 149.075 88.3174)
		(end 149.076881 88.30071)
		(width 0.1016)
		(layer "In2.Cu")
		(net 49)
	)
	(segment
		(start 148.5112 92.1984)
		(end 148.513747 92.221009)
		(width 0.1016)
		(layer "In2.Cu")
		(net 49)
	)
	(segment
		(start 149.346761 91.883637)
		(end 149.358637 91.871761)
		(width 0.1016)
		(layer "In2.Cu")
		(net 49)
	)
	(segment
		(start 149.133311 89.46348)
		(end 149.15 89.4616)
		(width 0.1016)
		(layer "In2.Cu")
		(net 49)
	)
	(segment
		(start 148.107347 92.221009)
		(end 148.114861 92.242483)
		(width 0.1016)
		(layer "In2.Cu")
		(net 49)
	)
	(segment
		(start 149.133311 90.475719)
		(end 149.117459 90.470172)
		(width 0.1016)
		(layer "In2.Cu")
		(net 49)
	)
	(segment
		(start 149.091363 89.896238)
		(end 149.103239 89.884362)
		(width 0.1016)
		(layer "In2.Cu")
		(net 49)
	)
	(segment
		(start 149.332541 90.485027)
		(end 149.316689 90.47948)
		(width 0.1016)
		(layer "In2.Cu")
		(net 49)
	)
	(segment
		(start 149.346761 89.038837)
		(end 149.358637 89.026961)
		(width 0.1016)
		(layer "In2.Cu")
		(net 49)
	)
	(segment
		(start 149.358637 90.505838)
		(end 149.346761 90.493962)
		(width 0.1016)
		(layer "In2.Cu")
		(net 49)
	)
	(segment
		(start 148.4096 91.899799)
		(end 148.432208 91.902347)
		(width 0.1016)
		(layer "In2.Cu")
		(net 49)
	)
	(segment
		(start 148.365517 91.909861)
		(end 148.386991 91.902347)
		(width 0.1016)
		(layer "In2.Cu")
		(net 49)
	)
	(segment
		(start 149.082428 91.654341)
		(end 149.076881 91.638489)
		(width 0.1016)
		(layer "In2.Cu")
		(net 49)
	)
	(segment
		(start 149.375 91.4186)
		(end 149.375 91.3654)
		(width 0.1016)
		(layer "In2.Cu")
		(net 49)
	)
	(segment
		(start 149.373119 90.94231)
		(end 149.367572 90.926458)
		(width 0.1016)
		(layer "In2.Cu")
		(net 49)
	)
	(segment
		(start 149.367572 91.739258)
		(end 149.358637 91.725038)
		(width 0.1016)
		(layer "In2.Cu")
		(net 49)
	)
	(segment
		(start 149.316689 90.678919)
		(end 149.332541 90.673372)
		(width 0.1016)
		(layer "In2.Cu")
		(net 49)
	)
	(segment
		(start 149.075 88.777)
		(end 149.075 88.7238)
		(width 0.1016)
		(layer "In2.Cu")
		(net 49)
	)
	(segment
		(start 149.253238 87.616437)
		(end 149.241362 87.604561)
		(width 0.1016)
		(layer "In2.Cu")
		(net 49)
	)
	(segment
		(start 149.082428 91.129658)
		(end 149.091363 91.115438)
		(width 0.1016)
		(layer "In2.Cu")
		(net 49)
	)
	(segment
		(start 149.316689 91.69868)
		(end 149.3 91.6968)
		(width 0.1016)
		(layer "In2.Cu")
		(net 49)
	)
	(segment
		(start 149.103239 89.242037)
		(end 149.091363 89.230161)
		(width 0.1016)
		(layer "In2.Cu")
		(net 49)
	)
	(segment
		(start 148.229008 92.297453)
		(end 148.250482 92.289939)
		(width 0.1016)
		(layer "In2.Cu")
		(net 49)
	)
	(segment
		(start 149.375 90.1994)
		(end 149.375 90.1462)
		(width 0.1016)
		(layer "In2.Cu")
		(net 49)
	)
	(segment
		(start 149.15 89.0552)
		(end 149.3 89.0552)
		(width 0.1016)
		(layer "In2.Cu")
		(net 49)
	)
	(segment
		(start 149.316689 88.85388)
		(end 149.3 88.852)
		(width 0.1016)
		(layer "In2.Cu")
		(net 49)
	)
	(segment
		(start 149.15 89.6648)
		(end 149.133311 89.662919)
		(width 0.1016)
		(layer "In2.Cu")
		(net 49)
	)
	(segment
		(start 149.346761 89.681162)
		(end 149.332541 89.672227)
		(width 0.1016)
		(layer "In2.Cu")
		(net 49)
	)
	(segment
		(start 147.891538 92.242483)
		(end 147.899052 92.221009)
		(width 0.1016)
		(layer "In2.Cu")
		(net 49)
	)
	(segment
		(start 149.103239 88.835637)
		(end 149.091363 88.823761)
		(width 0.1016)
		(layer "In2.Cu")
		(net 49)
	)
	(segment
		(start 149.367572 89.825541)
		(end 149.373119 89.809689)
		(width 0.1016)
		(layer "In2.Cu")
		(net 49)
	)
	(segment
		(start 149.133311 88.65068)
		(end 149.15 88.6488)
		(width 0.1016)
		(layer "In2.Cu")
		(net 49)
	)
	(segment
		(start 149.373119 90.53591)
		(end 149.367572 90.520058)
		(width 0.1016)
		(layer "In2.Cu")
		(net 49)
	)
	(segment
		(start 149.358637 90.912238)
		(end 149.346761 90.900362)
		(width 0.1016)
		(layer "In2.Cu")
		(net 49)
	)
	(segment
		(start 149.076881 89.11351)
		(end 149.082428 89.097658)
		(width 0.1016)
		(layer "In2.Cu")
		(net 49)
	)
	(segment
		(start 149.091363 88.270638)
		(end 149.103239 88.258762)
		(width 0.1016)
		(layer "In2.Cu")
		(net 49)
	)
	(segment
		(start 149.117459 90.470172)
		(end 149.103239 90.461237)
		(width 0.1016)
		(layer "In2.Cu")
		(net 49)
	)
	(segment
		(start 149.15 88.0392)
		(end 149.133311 88.037319)
		(width 0.1016)
		(layer "In2.Cu")
		(net 49)
	)
	(segment
		(start 149.15 91.2904)
		(end 149.133311 91.288519)
		(width 0.1016)
		(layer "In2.Cu")
		(net 49)
	)
	(segment
		(start 149.091363 89.230161)
		(end 149.082428 89.215941)
		(width 0.1016)
		(layer "In2.Cu")
		(net 49)
	)
	(segment
		(start 149.22688 91.95831)
		(end 149.232427 91.942458)
		(width 0.1016)
		(layer "In2.Cu")
		(net 49)
	)
	(segment
		(start 149.082428 90.435141)
		(end 149.076881 90.419289)
		(width 0.1016)
		(layer "In2.Cu")
		(net 49)
	)
	(segment
		(start 149.367572 88.894458)
		(end 149.358637 88.880238)
		(width 0.1016)
		(layer "In2.Cu")
		(net 49)
	)
	(segment
		(start 149.103239 88.258762)
		(end 149.117459 88.249827)
		(width 0.1016)
		(layer "In2.Cu")
		(net 49)
	)
	(segment
		(start 148.285834 92.261747)
		(end 148.297938 92.242483)
		(width 0.1016)
		(layer "In2.Cu")
		(net 49)
	)
	(segment
		(start 147.904147 91.978791)
		(end 147.911661 91.957317)
		(width 0.1016)
		(layer "In2.Cu")
		(net 49)
	)
	(segment
		(start 149.3 90.0712)
		(end 149.15 90.0712)
		(width 0.1016)
		(layer "In2.Cu")
		(net 49)
	)
	(segment
		(start 149.133311 88.24428)
		(end 149.15 88.2424)
		(width 0.1016)
		(layer "In2.Cu")
		(net 49)
	)
	(segment
		(start 149.082428 89.097658)
		(end 149.091363 89.083438)
		(width 0.1016)
		(layer "In2.Cu")
		(net 49)
	)
	(segment
		(start 149.15 88.4456)
		(end 149.133311 88.443719)
		(width 0.1016)
		(layer "In2.Cu")
		(net 49)
	)
	(segment
		(start 149.375 89.3334)
		(end 149.373119 89.31671)
		(width 0.1016)
		(layer "In2.Cu")
		(net 49)
	)
	(segment
		(start 149.346761 91.070837)
		(end 149.358637 91.058961)
		(width 0.1016)
		(layer "In2.Cu")
		(net 49)
	)
	(segment
		(start 149.316689 88.44748)
		(end 149.3 88.4456)
		(width 0.1016)
		(layer "In2.Cu")
		(net 49)
	)
	(segment
		(start 149.091363 88.010961)
		(end 149.082428 87.996741)
		(width 0.1016)
		(layer "In2.Cu")
		(net 49)
	)
	(segment
		(start 149.133311 88.850119)
		(end 149.117459 88.844572)
		(width 0.1016)
		(layer "In2.Cu")
		(net 49)
	)
	(segment
		(start 149.15 91.0872)
		(end 149.3 91.0872)
		(width 0.1016)
		(layer "In2.Cu")
		(net 49)
	)
	(segment
		(start 149.346761 90.258037)
		(end 149.358637 90.246161)
		(width 0.1016)
		(layer "In2.Cu")
		(net 49)
	)
	(segment
		(start 149.117459 88.249827)
		(end 149.133311 88.24428)
		(width 0.1016)
		(layer "In2.Cu")
		(net 49)
	)
	(segment
		(start 149.367572 89.300858)
		(end 149.358637 89.286638)
		(width 0.1016)
		(layer "In2.Cu")
		(net 49)
	)
	(segment
		(start 149.117459 88.438172)
		(end 149.103239 88.429237)
		(width 0.1016)
		(layer "In2.Cu")
		(net 49)
	)
	(segment
		(start 149.075 90.3494)
		(end 149.076881 90.33271)
		(width 0.1016)
		(layer "In2.Cu")
		(net 49)
	)
	(segment
		(start 149.241362 91.928238)
		(end 149.253238 91.916362)
		(width 0.1016)
		(layer "In2.Cu")
		(net 49)
	)
	(segment
		(start 149.3 88.6488)
		(end 149.316689 88.646919)
		(width 0.1016)
		(layer "In2.Cu")
		(net 49)
	)
	(segment
		(start 149.133311 90.27628)
		(end 149.15 90.2744)
		(width 0.1016)
		(layer "In2.Cu")
		(net 49)
	)
	(segment
		(start 149.316689 89.66668)
		(end 149.3 89.6648)
		(width 0.1016)
		(layer "In2.Cu")
		(net 49)
	)
	(segment
		(start 149.076881 90.419289)
		(end 149.075 90.4026)
		(width 0.1016)
		(layer "In2.Cu")
		(net 49)
	)
	(segment
		(start 149.076881 90.33271)
		(end 149.082428 90.316858)
		(width 0.1016)
		(layer "In2.Cu")
		(net 49)
	)
	(segment
		(start 147.899052 92.221009)
		(end 147.9016 92.1984)
		(width 0.1016)
		(layer "In2.Cu")
		(net 49)
	)
	(segment
		(start 149.332541 89.047772)
		(end 149.346761 89.038837)
		(width 0.1016)
		(layer "In2.Cu")
		(net 49)
	)
	(segment
		(start 149.346761 88.055562)
		(end 149.332541 88.046627)
		(width 0.1016)
		(layer "In2.Cu")
		(net 49)
	)
	(segment
		(start 149.346761 91.306762)
		(end 149.332541 91.297827)
		(width 0.1016)
		(layer "In2.Cu")
		(net 49)
	)
	(segment
		(start 149.103239 90.867637)
		(end 149.091363 90.855761)
		(width 0.1016)
		(layer "In2.Cu")
		(net 49)
	)
	(segment
		(start 149.3 88.0392)
		(end 149.15 88.0392)
		(width 0.1016)
		(layer "In2.Cu")
		(net 49)
	)
	(segment
		(start 149.133311 88.443719)
		(end 149.117459 88.438172)
		(width 0.1016)
		(layer "In2.Cu")
		(net 49)
	)
	(segment
		(start 149.332541 91.486172)
		(end 149.346761 91.477237)
		(width 0.1016)
		(layer "In2.Cu")
		(net 49)
	)
	(segment
		(start 149.367572 91.451141)
		(end 149.373119 91.435289)
		(width 0.1016)
		(layer "In2.Cu")
		(net 49)
	)
	(segment
		(start 149.3 90.6808)
		(end 149.316689 90.678919)
		(width 0.1016)
		(layer "In2.Cu")
		(net 49)
	)
	(segment
		(start 149.346761 90.900362)
		(end 149.332541 90.891427)
		(width 0.1016)
		(layer "In2.Cu")
		(net 49)
	)
	(segment
		(start 149.332541 90.266972)
		(end 149.346761 90.258037)
		(width 0.1016)
		(layer "In2.Cu")
		(net 49)
	)
	(segment
		(start 149.082428 88.403141)
		(end 149.076881 88.387289)
		(width 0.1016)
		(layer "In2.Cu")
		(net 49)
	)
	(segment
		(start 149.3 88.4456)
		(end 149.15 88.4456)
		(width 0.1016)
		(layer "In2.Cu")
		(net 49)
	)
	(segment
		(start 148.0032 91.899799)
		(end 148.025808 91.902347)
		(width 0.1016)
		(layer "In2.Cu")
		(net 49)
	)
	(segment
		(start 148.521261 92.242483)
		(end 148.533365 92.261747)
		(width 0.1016)
		(layer "In2.Cu")
		(net 49)
	)
	(segment
		(start 149.332541 91.079772)
		(end 149.346761 91.070837)
		(width 0.1016)
		(layer "In2.Cu")
		(net 49)
	)
	(segment
		(start 149.076881 88.387289)
		(end 149.075 88.3706)
		(width 0.1016)
		(layer "In2.Cu")
		(net 49)
	)
	(segment
		(start 149.091363 89.083438)
		(end 149.103239 89.071562)
		(width 0.1016)
		(layer "In2.Cu")
		(net 49)
	)
	(segment
		(start 149.117459 89.875427)
		(end 149.133311 89.86988)
		(width 0.1016)
		(layer "In2.Cu")
		(net 49)
	)
	(segment
		(start 149.316689 89.459719)
		(end 149.332541 89.454172)
		(width 0.1016)
		(layer "In2.Cu")
		(net 49)
	)
	(segment
		(start 149.075 88.7238)
		(end 149.076881 88.70711)
		(width 0.1016)
		(layer "In2.Cu")
		(net 49)
	)
	(segment
		(start 147.911661 91.957317)
		(end 147.923765 91.938053)
		(width 0.1016)
		(layer "In2.Cu")
		(net 49)
	)
	(segment
		(start 149.133311 90.68268)
		(end 149.15 90.6808)
		(width 0.1016)
		(layer "In2.Cu")
		(net 49)
	)
	(segment
		(start 149.15 88.852)
		(end 149.133311 88.850119)
		(width 0.1016)
		(layer "In2.Cu")
		(net 49)
	)
	(segment
		(start 149.091363 91.668561)
		(end 149.082428 91.654341)
		(width 0.1016)
		(layer "In2.Cu")
		(net 49)
	)
	(segment
		(start 149.15 91.4936)
		(end 149.3 91.4936)
		(width 0.1016)
		(layer "In2.Cu")
		(net 49)
	)
	(segment
		(start 149.3 87.836)
		(end 149.316689 87.834119)
		(width 0.1016)
		(layer "In2.Cu")
		(net 49)
	)
	(segment
		(start 148.330165 91.938053)
		(end 148.346253 91.921965)
		(width 0.1016)
		(layer "In2.Cu")
		(net 49)
	)
	(segment
		(start 149.15 90.4776)
		(end 149.133311 90.475719)
		(width 0.1016)
		(layer "In2.Cu")
		(net 49)
	)
	(segment
		(start 149.367572 90.638341)
		(end 149.373119 90.622489)
		(width 0.1016)
		(layer "In2.Cu")
		(net 49)
	)
	(segment
		(start 149.346761 87.649162)
		(end 149.332541 87.640227)
		(width 0.1016)
		(layer "In2.Cu")
		(net 49)
	)
	(segment
		(start 149.358637 88.880238)
		(end 149.346761 88.868362)
		(width 0.1016)
		(layer "In2.Cu")
		(net 49)
	)
	(segment
		(start 149.367572 88.081658)
		(end 149.358637 88.067438)
		(width 0.1016)
		(layer "In2.Cu")
		(net 49)
	)
	(segment
		(start 148.568717 92.289939)
		(end 148.590191 92.297453)
		(width 0.1016)
		(layer "In2.Cu")
		(net 49)
	)
	(segment
		(start 149.15 90.0712)
		(end 149.133311 90.069319)
		(width 0.1016)
		(layer "In2.Cu")
		(net 49)
	)
	(segment
		(start 147.822608 92.297453)
		(end 147.844082 92.289939)
		(width 0.1016)
		(layer "In2.Cu")
		(net 49)
	)
	(segment
		(start 149.346761 89.851637)
		(end 149.358637 89.839761)
		(width 0.1016)
		(layer "In2.Cu")
		(net 49)
	)
	(segment
		(start 149.316689 88.04108)
		(end 149.3 88.0392)
		(width 0.1016)
		(layer "In2.Cu")
		(net 49)
	)
	(segment
		(start 149.076881 87.980889)
		(end 149.075 87.9642)
		(width 0.1016)
		(layer "In2.Cu")
		(net 49)
	)
	(segment
		(start 149.103239 87.852362)
		(end 149.117459 87.843427)
		(width 0.1016)
		(layer "In2.Cu")
		(net 49)
	)
	(segment
		(start 149.117459 91.689372)
		(end 149.103239 91.680437)
		(width 0.1016)
		(layer "In2.Cu")
		(net 49)
	)
	(segment
		(start 149.358637 91.318638)
		(end 149.346761 91.306762)
		(width 0.1016)
		(layer "In2.Cu")
		(net 49)
	)
	(segment
		(start 149.316689 89.053319)
		(end 149.332541 89.047772)
		(width 0.1016)
		(layer "In2.Cu")
		(net 49)
	)
	(segment
		(start 149.076881 89.92631)
		(end 149.082428 89.910458)
		(width 0.1016)
		(layer "In2.Cu")
		(net 49)
	)
	(segment
		(start 148.094738 91.957317)
		(end 148.102252 91.978791)
		(width 0.1016)
		(layer "In2.Cu")
		(net 49)
	)
	(segment
		(start 148.533365 92.261747)
		(end 148.549453 92.277835)
		(width 0.1016)
		(layer "In2.Cu")
		(net 49)
	)
	(segment
		(start 149.373119 90.12951)
		(end 149.367572 90.113658)
		(width 0.1016)
		(layer "In2.Cu")
		(net 49)
	)
	(segment
		(start 149.091363 90.449361)
		(end 149.082428 90.435141)
		(width 0.1016)
		(layer "In2.Cu")
		(net 49)
	)
	(segment
		(start 149.133311 91.08908)
		(end 149.15 91.0872)
		(width 0.1016)
		(layer "In2.Cu")
		(net 49)
	)
	(segment
		(start 149.103239 91.274037)
		(end 149.091363 91.262161)
		(width 0.1016)
		(layer "In2.Cu")
		(net 49)
	)
	(segment
		(start 148.126965 92.261747)
		(end 148.143053 92.277835)
		(width 0.1016)
		(layer "In2.Cu")
		(net 49)
	)
	(segment
		(start 149.117459 90.063772)
		(end 149.103239 90.054837)
		(width 0.1016)
		(layer "In2.Cu")
		(net 49)
	)
	(segment
		(start 148.310547 91.978791)
		(end 148.318061 91.957317)
		(width 0.1016)
		(layer "In2.Cu")
		(net 49)
	)
	(segment
		(start 149.133311 91.694919)
		(end 149.117459 91.689372)
		(width 0.1016)
		(layer "In2.Cu")
		(net 49)
	)
	(segment
		(start 149.316689 88.646919)
		(end 149.332541 88.641372)
		(width 0.1016)
		(layer "In2.Cu")
		(net 49)
	)
	(segment
		(start 148.5112 92.001399)
		(end 148.5112 92.1984)
		(width 0.1016)
		(layer "In2.Cu")
		(net 49)
	)
	(segment
		(start 149.332541 88.641372)
		(end 149.346761 88.632437)
		(width 0.1016)
		(layer "In2.Cu")
		(net 49)
	)
	(segment
		(start 149.375 91.7718)
		(end 149.373119 91.75511)
		(width 0.1016)
		(layer "In2.Cu")
		(net 49)
	)
	(segment
		(start 149.075 90.4026)
		(end 149.075 90.3494)
		(width 0.1016)
		(layer "In2.Cu")
		(net 49)
	)
	(segment
		(start 149.373119 91.841689)
		(end 149.375 91.825)
		(width 0.1016)
		(layer "In2.Cu")
		(net 49)
	)
	(segment
		(start 149.367572 88.606341)
		(end 149.373119 88.590489)
		(width 0.1016)
		(layer "In2.Cu")
		(net 49)
	)
	(segment
		(start 149.358637 90.652561)
		(end 149.367572 90.638341)
		(width 0.1016)
		(layer "In2.Cu")
		(net 49)
	)
	(segment
		(start 149.075 91.6218)
		(end 149.075 91.5686)
		(width 0.1016)
		(layer "In2.Cu")
		(net 49)
	)
	(segment
		(start 149.082428 90.316858)
		(end 149.091363 90.302638)
		(width 0.1016)
		(layer "In2.Cu")
		(net 49)
	)
	(segment
		(start 149.103239 90.461237)
		(end 149.091363 90.449361)
		(width 0.1016)
		(layer "In2.Cu")
		(net 49)
	)
	(segment
		(start 149.375 87.7078)
		(end 149.373119 87.69111)
		(width 0.1016)
		(layer "In2.Cu")
		(net 49)
	)
	(segment
		(start 149.358637 88.214161)
		(end 149.367572 88.199941)
		(width 0.1016)
		(layer "In2.Cu")
		(net 49)
	)
	(segment
		(start 148.346253 91.921965)
		(end 148.365517 91.909861)
		(width 0.1016)
		(layer "In2.Cu")
		(net 49)
	)
	(segment
		(start 149.103239 91.103562)
		(end 149.117459 91.094627)
		(width 0.1016)
		(layer "In2.Cu")
		(net 49)
	)
	(segment
		(start 149.375 90.6058)
		(end 149.375 90.5526)
		(width 0.1016)
		(layer "In2.Cu")
		(net 49)
	)
	(segment
		(start 149.316689 91.29228)
		(end 149.3 91.2904)
		(width 0.1016)
		(layer "In2.Cu")
		(net 49)
	)
	(segment
		(start 149.375 88.5738)
		(end 149.375 88.5206)
		(width 0.1016)
		(layer "In2.Cu")
		(net 49)
	)
	(segment
		(start 149.103239 88.429237)
		(end 149.091363 88.417361)
		(width 0.1016)
		(layer "In2.Cu")
		(net 49)
	)
	(segment
		(start 149.373119 88.996889)
		(end 149.375 88.9802)
		(width 0.1016)
		(layer "In2.Cu")
		(net 49)
	)
	(segment
		(start 149.117459 87.843427)
		(end 149.133311 87.83788)
		(width 0.1016)
		(layer "In2.Cu")
		(net 49)
	)
	(segment
		(start 149.332541 89.672227)
		(end 149.316689 89.66668)
		(width 0.1016)
		(layer "In2.Cu")
		(net 49)
	)
	(segment
		(start 149.15 91.6968)
		(end 149.133311 91.694919)
		(width 0.1016)
		(layer "In2.Cu")
		(net 49)
	)
	(segment
		(start 147.959117 91.909861)
		(end 147.980591 91.902347)
		(width 0.1016)
		(layer "In2.Cu")
		(net 49)
	)
	(segment
		(start 149.091363 87.864238)
		(end 149.103239 87.852362)
		(width 0.1016)
		(layer "In2.Cu")
		(net 49)
	)
	(segment
		(start 149.076881 91.638489)
		(end 149.075 91.6218)
		(width 0.1016)
		(layer "In2.Cu")
		(net 49)
	)
	(segment
		(start 149.332541 87.640227)
		(end 149.316689 87.63468)
		(width 0.1016)
		(layer "In2.Cu")
		(net 49)
	)
	(segment
		(start 149.346761 89.274762)
		(end 149.332541 89.265827)
		(width 0.1016)
		(layer "In2.Cu")
		(net 49)
	)
	(segment
		(start 148.066546 91.921965)
		(end 148.082634 91.938053)
		(width 0.1016)
		(layer "In2.Cu")
		(net 49)
	)
	(segment
		(start 149.358637 91.058961)
		(end 149.367572 91.044741)
		(width 0.1016)
		(layer "In2.Cu")
		(net 49)
	)
	(segment
		(start 148.508652 91.978791)
		(end 148.5112 92.001399)
		(width 0.1016)
		(layer "In2.Cu")
		(net 49)
	)
	(segment
		(start 147.863346 92.277835)
		(end 147.879434 92.261747)
		(width 0.1016)
		(layer "In2.Cu")
		(net 49)
	)
	(segment
		(start 149.15 90.884)
		(end 149.133311 90.882119)
		(width 0.1016)
		(layer "In2.Cu")
		(net 49)
	)
	(segment
		(start 149.117459 89.469027)
		(end 149.133311 89.46348)
		(width 0.1016)
		(layer "In2.Cu")
		(net 49)
	)
	(segment
		(start 149.103239 89.884362)
		(end 149.117459 89.875427)
		(width 0.1016)
		(layer "In2.Cu")
		(net 49)
	)
	(segment
		(start 149.346761 90.493962)
		(end 149.332541 90.485027)
		(width 0.1016)
		(layer "In2.Cu")
		(net 49)
	)
	(segment
		(start 149.316689 87.834119)
		(end 149.332541 87.828572)
		(width 0.1016)
		(layer "In2.Cu")
		(net 49)
	)
	(segment
		(start 149.373119 88.91031)
		(end 149.367572 88.894458)
		(width 0.1016)
		(layer "In2.Cu")
		(net 49)
	)
	(segment
		(start 147.939853 91.921965)
		(end 147.959117 91.909861)
		(width 0.1016)
		(layer "In2.Cu")
		(net 49)
	)
	(segment
		(start 149.358637 91.871761)
		(end 149.367572 91.857541)
		(width 0.1016)
		(layer "In2.Cu")
		(net 49)
	)
	(segment
		(start 149.375 88.927)
		(end 149.373119 88.91031)
		(width 0.1016)
		(layer "In2.Cu")
		(net 49)
	)
	(segment
		(start 148.162317 92.289939)
		(end 148.183791 92.297453)
		(width 0.1016)
		(layer "In2.Cu")
		(net 49)
	)
	(segment
		(start 148.269746 92.277835)
		(end 148.285834 92.261747)
		(width 0.1016)
		(layer "In2.Cu")
		(net 49)
	)
	(segment
		(start 149.373119 89.403289)
		(end 149.375 89.3866)
		(width 0.1016)
		(layer "In2.Cu")
		(net 49)
	)
	(segment
		(start 149.358637 88.620561)
		(end 149.367572 88.606341)
		(width 0.1016)
		(layer "In2.Cu")
		(net 49)
	)
	(segment
		(start 149.267458 91.907427)
		(end 149.28331 91.90188)
		(width 0.1016)
		(layer "In2.Cu")
		(net 49)
	)
	(segment
		(start 149.117459 88.031772)
		(end 149.103239 88.022837)
		(width 0.1016)
		(layer "In2.Cu")
		(net 49)
	)
	(segment
		(start 147.980591 91.902347)
		(end 148.0032 91.899799)
		(width 0.1016)
		(layer "In2.Cu")
		(net 49)
	)
	(segment
		(start 148.308 92.1984)
		(end 148.308 92.001399)
		(width 0.1016)
		(layer "In2.Cu")
		(net 49)
	)
	(segment
		(start 149.373119 91.75511)
		(end 149.367572 91.739258)
		(width 0.1016)
		(layer "In2.Cu")
		(net 49)
	)
	(segment
		(start 149.091363 89.636561)
		(end 149.082428 89.622341)
		(width 0.1016)
		(layer "In2.Cu")
		(net 49)
	)
	(segment
		(start 149.232427 91.942458)
		(end 149.241362 91.928238)
		(width 0.1016)
		(layer "In2.Cu")
		(net 49)
	)
	(segment
		(start 149.091363 89.489838)
		(end 149.103239 89.477962)
		(width 0.1016)
		(layer "In2.Cu")
		(net 49)
	)
	(segment
		(start 149.358637 87.661038)
		(end 149.346761 87.649162)
		(width 0.1016)
		(layer "In2.Cu")
		(net 49)
	)
	(segment
		(start 149.332541 91.892572)
		(end 149.346761 91.883637)
		(width 0.1016)
		(layer "In2.Cu")
		(net 49)
	)
	(segment
		(start 149.358637 91.465361)
		(end 149.367572 91.451141)
		(width 0.1016)
		(layer "In2.Cu")
		(net 49)
	)
	(segment
		(start 149.373119 91.34871)
		(end 149.367572 91.332858)
		(width 0.1016)
		(layer "In2.Cu")
		(net 49)
	)
	(segment
		(start 149.346761 88.461962)
		(end 149.332541 88.453027)
		(width 0.1016)
		(layer "In2.Cu")
		(net 49)
	)
	(segment
		(start 130.725 92.1)
		(end 132.175 92.1)
		(width 0.2)
		(layer "F.Cu")
		(net 50)
	)
	(segment
		(start 134.16 86.45)
		(end 134.175 86.465)
		(width 0.2)
		(layer "F.Cu")
		(net 50)
	)
	(segment
		(start 122.27501 83.275)
		(end 121.315 83.275)
		(width 0.2)
		(layer "F.Cu")
		(net 50)
	)
	(segment
		(start 122.27501 82.625)
		(end 122.27501 81.54501)
		(width 0.2)
		(layer "F.Cu")
		(net 50)
	)
	(segment
		(start 129.015 81.145)
		(end 129.015 81.825)
		(width 0.2)
		(layer "F.Cu")
		(net 50)
	)
	(segment
		(start 126.56 93.765)
		(end 126.555 93.77)
		(width 0.2)
		(layer "F.Cu")
		(net 50)
	)
	(segment
		(start 126.555 89.235)
		(end 126.555 88.515)
		(width 0.2)
		(layer "F.Cu")
		(net 50)
	)
	(segment
		(start 121.315 83.275)
		(end 121.31 83.27)
		(width 0.2)
		(layer "F.Cu")
		(net 50)
	)
	(segment
		(start 130.725 92.1)
		(end 130.725 92.85)
		(width 0.2)
		(layer "F.Cu")
		(net 50)
	)
	(segment
		(start 132.175 92.1)
		(end 132.175 93.2)
		(width 0.2)
		(layer "F.Cu")
		(net 50)
	)
	(segment
		(start 126.56 93.07)
		(end 126.56 93.765)
		(width 0.2)
		(layer "F.Cu")
		(net 50)
	)
	(segment
		(start 134.175 85.685)
		(end 134.175 86.465)
		(width 0.2)
		(layer "F.Cu")
		(net 50)
	)
	(segment
		(start 122.27501 82.625)
		(end 121.305 82.625)
		(width 0.2)
		(layer "F.Cu")
		(net 50)
	)
	(segment
		(start 122.27501 83.275)
		(end 122.27501 82.625)
		(width 0.2)
		(layer "F.Cu")
		(net 50)
	)
	(segment
		(start 122.27501 83.925)
		(end 121.315 83.925)
		(width 0.2)
		(layer "F.Cu")
		(net 50)
	)
	(segment
		(start 122.27501 83.925)
		(end 122.27501 83.275)
		(width 0.2)
		(layer "F.Cu")
		(net 50)
	)
	(segment
		(start 137.15 85.2)
		(end 135.75 85.2)
		(width 0.2)
		(layer "F.Cu")
		(net 50)
	)
	(segment
		(start 132.775 86.45)
		(end 134.16 86.45)
		(width 0.2)
		(layer "F.Cu")
		(net 50)
	)
	(via
		(at 130.725 92.85)
		(size 0.45)
		(drill 0.15)
		(layers "F.Cu" "B.Cu")
		(net 50)
	)
	(via
		(at 121.315 83.925)
		(size 0.45)
		(drill 0.15)
		(layers "F.Cu" "B.Cu")
		(net 50)
	)
	(via
		(at 132.175 93.2)
		(size 0.45)
		(drill 0.15)
		(layers "F.Cu" "B.Cu")
		(net 50)
	)
	(via
		(at 135.75 85.2)
		(size 0.45)
		(drill 0.15)
		(layers "F.Cu" "B.Cu")
		(net 50)
	)
	(via
		(at 134.175 86.465)
		(size 0.45)
		(drill 0.15)
		(layers "F.Cu" "B.Cu")
		(net 50)
	)
	(via
		(at 129.015 81.825)
		(size 0.45)
		(drill 0.15)
		(layers "F.Cu" "B.Cu")
		(net 50)
	)
	(via
		(at 126.555 93.77)
		(size 0.45)
		(drill 0.15)
		(layers "F.Cu" "B.Cu")
		(net 50)
	)
	(via
		(at 121.31 83.27)
		(size 0.45)
		(drill 0.15)
		(layers "F.Cu" "B.Cu")
		(net 50)
	)
	(via
		(at 126.555 88.515)
		(size 0.45)
		(drill 0.15)
		(layers "F.Cu" "B.Cu")
		(net 50)
	)
	(via
		(at 121.305 82.625)
		(size 0.45)
		(drill 0.15)
		(layers "F.Cu" "B.Cu")
		(net 50)
	)
	(segment
		(start 130.675 98.7)
		(end 130.175 98.7)
		(width 0.2)
		(layer "B.Cu")
		(net 50)
	)
	(via
		(at 125.9 96.8)
		(size 0.45)
		(drill 0.15)
		(layers "F.Cu" "B.Cu")
		(net 51)
	)
	(via
		(at 137.4 90.8)
		(size 0.45)
		(drill 0.15)
		(layers "F.Cu" "B.Cu")
		(net 51)
	)
	(via
		(at 136.8 91.4)
		(size 0.45)
		(drill 0.15)
		(layers "F.Cu" "B.Cu")
		(net 51)
	)
	(via
		(at 124.7 96.8)
		(size 0.45)
		(drill 0.15)
		(layers "F.Cu" "B.Cu")
		(net 51)
	)
	(via
		(at 125.3 96.8)
		(size 0.45)
		(drill 0.15)
		(layers "F.Cu" "B.Cu")
		(net 51)
	)
	(via
		(at 137.4 88.2)
		(size 0.45)
		(drill 0.15)
		(layers "F.Cu" "B.Cu")
		(net 51)
	)
	(via
		(at 136.8 88.2)
		(size 0.45)
		(drill 0.15)
		(layers "F.Cu" "B.Cu")
		(net 51)
	)
	(via
		(at 137.4 90.2)
		(size 0.45)
		(drill 0.15)
		(layers "F.Cu" "B.Cu")
		(net 51)
	)
	(via
		(at 126.5 96.8)
		(size 0.45)
		(drill 0.15)
		(layers "F.Cu" "B.Cu")
		(net 51)
	)
	(via
		(at 136.8 90.8)
		(size 0.45)
		(drill 0.15)
		(layers "F.Cu" "B.Cu")
		(net 51)
	)
	(via
		(at 127.1 96.8)
		(size 0.45)
		(drill 0.15)
		(layers "F.Cu" "B.Cu")
		(net 51)
	)
	(via
		(at 127.7 96.8)
		(size 0.45)
		(drill 0.15)
		(layers "F.Cu" "B.Cu")
		(net 51)
	)
	(via
		(at 136.8 90.2)
		(size 0.45)
		(drill 0.15)
		(layers "F.Cu" "B.Cu")
		(net 51)
	)
	(via
		(at 137.4 91.4)
		(size 0.45)
		(drill 0.15)
		(layers "F.Cu" "B.Cu")
		(net 51)
	)
	(segment
		(start 127.975 82.625)
		(end 130.15 82.625)
		(width 0.2)
		(layer "F.Cu")
		(net 52)
	)
	(segment
		(start 130.15 82.625)
		(end 130.175 82.6)
		(width 0.2)
		(layer "F.Cu")
		(net 52)
	)
	(segment
		(start 127.975 82.625)
		(end 127.975 81.215)
		(width 0.2)
		(layer "F.Cu")
		(net 52)
	)
	(segment
		(start 127.975 81.215)
		(end 128.045 81.145)
		(width 0.2)
		(layer "F.Cu")
		(net 52)
	)
	(segment
		(start 130.175 82.6)
		(end 130.175 81.15)
		(width 0.2)
		(layer "F.Cu")
		(net 52)
	)
	(segment
		(start 142.675 98.7)
		(end 142.675 96.075)
		(width 0.145)
		(layer "B.Cu")
		(net 53)
	)
	(segment
		(start 141.6 89)
		(end 143.957053 86.642947)
		(width 0.145)
		(layer "B.Cu")
		(net 53)
	)
	(segment
		(start 142.675 96.075)
		(end 141.6 95)
		(width 0.145)
		(layer "B.Cu")
		(net 53)
	)
	(segment
		(start 141.6 95)
		(end 141.6 89)
		(width 0.145)
		(layer "B.Cu")
		(net 53)
	)
	(segment
		(start 154.6 95.6)
		(end 154 95)
		(width 0.145)
		(layer "F.Cu")
		(net 54)
	)
	(segment
		(start 151 92.4)
		(end 151.225 92.175)
		(width 0.145)
		(layer "F.Cu")
		(net 54)
	)
	(segment
		(start 154 95)
		(end 152.6 95)
		(width 0.145)
		(layer "F.Cu")
		(net 54)
	)
	(segment
		(start 154.425 97.175)
		(end 154.6 97)
		(width 0.145)
		(layer "F.Cu")
		(net 54)
	)
	(segment
		(start 150.4 92.8)
		(end 150.4 92.6)
		(width 0.145)
		(layer "F.Cu")
		(net 54)
	)
	(segment
		(start 151.225 92.175)
		(end 151.225 91.635)
		(width 0.145)
		(layer "F.Cu")
		(net 54)
	)
	(segment
		(start 150.4 92.6)
		(end 150.6 92.4)
		(width 0.145)
		(layer "F.Cu")
		(net 54)
	)
	(segment
		(start 154.425 98.7)
		(end 154.425 97.175)
		(width 0.145)
		(layer "F.Cu")
		(net 54)
	)
	(segment
		(start 154.6 97)
		(end 154.6 95.6)
		(width 0.145)
		(layer "F.Cu")
		(net 54)
	)
	(segment
		(start 152.6 95)
		(end 150.4 92.8)
		(width 0.145)
		(layer "F.Cu")
		(net 54)
	)
	(segment
		(start 150.6 92.4)
		(end 151 92.4)
		(width 0.145)
		(layer "F.Cu")
		(net 54)
	)
	(segment
		(start 157.385 93.615)
		(end 154.675 96.325)
		(width 0.145)
		(layer "B.Cu")
		(net 55)
	)
	(segment
		(start 157.385 85.6)
		(end 157.385 93.615)
		(width 0.145)
		(layer "B.Cu")
		(net 55)
	)
	(segment
		(start 154.675 96.325)
		(end 154.675 98.7)
		(width 0.145)
		(layer "B.Cu")
		(net 55)
	)
	(segment
		(start 141.2 95)
		(end 142.175 95.975)
		(width 0.145)
		(layer "B.Cu")
		(net 56)
	)
	(segment
		(start 141.2 88.6)
		(end 141.2 95)
		(width 0.145)
		(layer "B.Cu")
		(net 56)
	)
	(segment
		(start 142.057053 87.742947)
		(end 141.2 88.6)
		(width 0.145)
		(layer "B.Cu")
		(net 56)
	)
	(segment
		(start 142.175 95.975)
		(end 142.175 98.7)
		(width 0.145)
		(layer "B.Cu")
		(net 56)
	)
	(segment
		(start 142 89.4)
		(end 142.857053 88.542947)
		(width 0.145)
		(layer "B.Cu")
		(net 57)
	)
	(segment
		(start 143.175 97.09067)
		(end 143.025899 96.941569)
		(width 0.145)
		(layer "B.Cu")
		(net 57)
	)
	(segment
		(start 143.025899 96.025899)
		(end 142 95)
		(width 0.145)
		(layer "B.Cu")
		(net 57)
	)
	(segment
		(start 142 95)
		(end 142 89.4)
		(width 0.145)
		(layer "B.Cu")
		(net 57)
	)
	(segment
		(start 143.025899 96.941569)
		(end 143.025899 96.025899)
		(width 0.145)
		(layer "B.Cu")
		(net 57)
	)
	(segment
		(start 143.175 98.7)
		(end 143.175 97.09067)
		(width 0.145)
		(layer "B.Cu")
		(net 57)
	)
	(segment
		(start 151.225 82.05)
		(end 151.625 82.45)
		(width 0.145)
		(layer "F.Cu")
		(net 58)
	)
	(via
		(at 151.625 82.45)
		(size 0.45)
		(drill 0.15)
		(layers "F.Cu" "B.Cu")
		(net 58)
	)
	(segment
		(start 156.415 84.6)
		(end 156.415 85.6)
		(width 0.145)
		(layer "B.Cu")
		(net 58)
	)
	(segment
		(start 151.65 82.45)
		(end 151.625 82.45)
		(width 0.145)
		(layer "B.Cu")
		(net 58)
	)
	(segment
		(start 153.224101 84.455215)
		(end 153.224101 84.024101)
		(width 0.145)
		(layer "B.Cu")
		(net 58)
	)
	(segment
		(start 154.368886 85.6)
		(end 153.224101 84.455215)
		(width 0.145)
		(layer "B.Cu")
		(net 58)
	)
	(segment
		(start 156.415 85.6)
		(end 154.368886 85.6)
		(width 0.145)
		(layer "B.Cu")
		(net 58)
	)
	(segment
		(start 153.224101 84.024101)
		(end 151.65 82.45)
		(width 0.145)
		(layer "B.Cu")
		(net 58)
	)
	(segment
		(start 150.425 82.05)
		(end 150.025 82.45)
		(width 0.145)
		(layer "F.Cu")
		(net 59)
	)
	(via
		(at 150.025 82.45)
		(size 0.45)
		(drill 0.15)
		(layers "F.Cu" "B.Cu")
		(net 59)
	)
	(segment
		(start 149.2 83.7)
		(end 146.9 83.7)
		(width 0.145)
		(layer "B.Cu")
		(net 59)
	)
	(segment
		(start 150.025 82.45)
		(end 150.025 82.875)
		(width 0.145)
		(layer "B.Cu")
		(net 59)
	)
	(segment
		(start 146.9 83.7)
		(end 144.642947 85.957053)
		(width 0.145)
		(layer "B.Cu")
		(net 59)
	)
	(segment
		(start 150.025 82.875)
		(end 149.2 83.7)
		(width 0.145)
		(layer "B.Cu")
		(net 59)
	)
	(segment
		(start 147.665 90.665)
		(end 149.225 90.665)
		(width 0.145)
		(layer "F.Cu")
		(net 60)
	)
	(segment
		(start 147.225 88.45)
		(end 147.225 90.225)
		(width 0.145)
		(layer "F.Cu")
		(net 60)
	)
	(segment
		(start 150.195 91.635)
		(end 149.225 90.665)
		(width 0.145)
		(layer "F.Cu")
		(net 60)
	)
	(segment
		(start 147.225 90.225)
		(end 147.665 90.665)
		(width 0.145)
		(layer "F.Cu")
		(net 60)
	)
	(segment
		(start 150.225 91.635)
		(end 150.195 91.635)
		(width 0.145)
		(layer "F.Cu")
		(net 60)
	)
	(segment
		(start 157.525 86.765)
		(end 156.11 86.765)
		(width 0.145)
		(layer "F.Cu")
		(net 61)
	)
	(segment
		(start 156.11 86.765)
		(end 156.025 86.85)
		(width 0.145)
		(layer "F.Cu")
		(net 61)
	)
	(segment
		(start 147.225 82.05)
		(end 146.825 82.45)
		(width 0.145)
		(layer "F.Cu")
		(net 62)
	)
	(via
		(at 146.825 82.45)
		(size 0.45)
		(drill 0.15)
		(layers "F.Cu" "B.Cu")
		(net 62)
	)
	(segment
		(start 143.119889 85.638693)
		(end 143.16246 85.628976)
		(width 0.145)
		(layer "B.Cu")
		(net 62)
	)
	(segment
		(start 143.01918 85.719005)
		(end 143.046406 85.684865)
		(width 0.145)
		(layer "B.Cu")
		(net 62)
	)
	(segment
		(start 143.322178 85.684865)
		(end 143.580772 85.943459)
		(width 0.145)
		(layer "B.Cu")
		(net 62)
	)
	(segment
		(start 143.902714 85.741168)
		(end 143.883768 85.701826)
		(width 0.145)
		(layer "B.Cu")
		(net 62)
	)
	(segment
		(start 143.883768 85.701826)
		(end 143.856541 85.667688)
		(width 0.145)
		(layer "B.Cu")
		(net 62)
	)
	(segment
		(start 143.248697 85.638694)
		(end 143.288039 85.65764)
		(width 0.145)
		(layer "B.Cu")
		(net 62)
	)
	(segment
		(start 142.990519 85.800917)
		(end 143.000235 85.758345)
		(width 0.145)
		(layer "B.Cu")
		(net 62)
	)
	(segment
		(start 143.046406 85.960637)
		(end 143.01918 85.926497)
		(width 0.145)
		(layer "B.Cu")
		(net 62)
	)
	(segment
		(start 144.514149 85.285851)
		(end 145.2 84.6)
		(width 0.145)
		(layer "B.Cu")
		(net 62)
	)
	(segment
		(start 143.856542 85.943458)
		(end 143.883767 85.90932)
		(width 0.145)
		(layer "B.Cu")
		(net 62)
	)
	(segment
		(start 143.288039 85.65764)
		(end 143.322178 85.684865)
		(width 0.145)
		(layer "B.Cu")
		(net 62)
	)
	(segment
		(start 143.580772 85.943459)
		(end 143.614912 85.970685)
		(width 0.145)
		(layer "B.Cu")
		(net 62)
	)
	(segment
		(start 143.783064 85.98963)
		(end 143.822404 85.970685)
		(width 0.145)
		(layer "B.Cu")
		(net 62)
	)
	(segment
		(start 145.6 84.6)
		(end 146.825 83.375)
		(width 0.145)
		(layer "B.Cu")
		(net 62)
	)
	(segment
		(start 146.825 83.375)
		(end 146.825 82.45)
		(width 0.145)
		(layer "B.Cu")
		(net 62)
	)
	(segment
		(start 143.654254 85.989631)
		(end 143.696826 85.999346)
		(width 0.145)
		(layer "B.Cu")
		(net 62)
	)
	(segment
		(start 143.046406 85.684865)
		(end 143.080547 85.657639)
		(width 0.145)
		(layer "B.Cu")
		(net 62)
	)
	(segment
		(start 143.000234 85.887155)
		(end 142.990519 85.844583)
		(width 0.145)
		(layer "B.Cu")
		(net 62)
	)
	(segment
		(start 143.570722 85.167463)
		(end 143.597948 85.133323)
		(width 0.145)
		(layer "B.Cu")
		(net 62)
	)
	(segment
		(start 143.883767 85.90932)
		(end 143.902713 85.869978)
		(width 0.145)
		(layer "B.Cu")
		(net 62)
	)
	(segment
		(start 143.000235 85.758345)
		(end 143.01918 85.719005)
		(width 0.145)
		(layer "B.Cu")
		(net 62)
	)
	(segment
		(start 143.304999 86.21923)
		(end 143.046406 85.960637)
		(width 0.145)
		(layer "B.Cu")
		(net 62)
	)
	(segment
		(start 144.248368 85.447804)
		(end 144.292034 85.447804)
		(width 0.145)
		(layer "B.Cu")
		(net 62)
	)
	(segment
		(start 144.132314 85.391917)
		(end 144.166454 85.419143)
		(width 0.145)
		(layer "B.Cu")
		(net 62)
	)
	(segment
		(start 143.856543 85.943458)
		(end 143.856542 85.943458)
		(width 0.145)
		(layer "B.Cu")
		(net 62)
	)
	(segment
		(start 143.360888 86.335283)
		(end 143.351172 86.29271)
		(width 0.145)
		(layer "B.Cu")
		(net 62)
	)
	(segment
		(start 143.351171 86.42152)
		(end 143.360888 86.378949)
		(width 0.145)
		(layer "B.Cu")
		(net 62)
	)
	(segment
		(start 143.714002 85.077434)
		(end 143.757668 85.077434)
		(width 0.145)
		(layer "B.Cu")
		(net 62)
	)
	(segment
		(start 142.990519 85.844583)
		(end 142.990519 85.800917)
		(width 0.145)
		(layer "B.Cu")
		(net 62)
	)
	(segment
		(start 143.16246 85.628976)
		(end 143.206126 85.628976)
		(width 0.145)
		(layer "B.Cu")
		(net 62)
	)
	(segment
		(start 143.01918 85.926497)
		(end 143.000234 85.887155)
		(width 0.145)
		(layer "B.Cu")
		(net 62)
	)
	(segment
		(start 144.408085 85.391916)
		(end 144.514149 85.285851)
		(width 0.145)
		(layer "B.Cu")
		(net 62)
	)
	(segment
		(start 143.080547 85.657639)
		(end 143.119889 85.638693)
		(width 0.145)
		(layer "B.Cu")
		(net 62)
	)
	(segment
		(start 144.334606 85.438088)
		(end 144.373946 85.419143)
		(width 0.145)
		(layer "B.Cu")
		(net 62)
	)
	(segment
		(start 143.570722 85.374955)
		(end 143.551776 85.335613)
		(width 0.145)
		(layer "B.Cu")
		(net 62)
	)
	(segment
		(start 143.542061 85.293041)
		(end 143.542061 85.249375)
		(width 0.145)
		(layer "B.Cu")
		(net 62)
	)
	(segment
		(start 143.839581 85.106098)
		(end 143.87372 85.133323)
		(width 0.145)
		(layer "B.Cu")
		(net 62)
	)
	(segment
		(start 143.305 86.495)
		(end 143.332225 86.460862)
		(width 0.145)
		(layer "B.Cu")
		(net 62)
	)
	(segment
		(start 143.822404 85.970685)
		(end 143.856543 85.943458)
		(width 0.145)
		(layer "B.Cu")
		(net 62)
	)
	(segment
		(start 143.91243 85.827407)
		(end 143.91243 85.783741)
		(width 0.145)
		(layer "B.Cu")
		(net 62)
	)
	(segment
		(start 143.551777 85.206803)
		(end 143.570722 85.167463)
		(width 0.145)
		(layer "B.Cu")
		(net 62)
	)
	(segment
		(start 144.373946 85.419143)
		(end 144.408085 85.391916)
		(width 0.145)
		(layer "B.Cu")
		(net 62)
	)
	(segment
		(start 144.292034 85.447804)
		(end 144.334606 85.438088)
		(width 0.145)
		(layer "B.Cu")
		(net 62)
	)
	(segment
		(start 143.206126 85.628976)
		(end 143.248697 85.638694)
		(width 0.145)
		(layer "B.Cu")
		(net 62)
	)
	(segment
		(start 143.757668 85.077434)
		(end 143.800239 85.087152)
		(width 0.145)
		(layer "B.Cu")
		(net 62)
	)
	(segment
		(start 143.696826 85.999346)
		(end 143.740492 85.999346)
		(width 0.145)
		(layer "B.Cu")
		(net 62)
	)
	(segment
		(start 143.632089 85.106097)
		(end 143.671431 85.087151)
		(width 0.145)
		(layer "B.Cu")
		(net 62)
	)
	(segment
		(start 143.671431 85.087151)
		(end 143.714002 85.077434)
		(width 0.145)
		(layer "B.Cu")
		(net 62)
	)
	(segment
		(start 143.360888 86.378949)
		(end 143.360888 86.335283)
		(width 0.145)
		(layer "B.Cu")
		(net 62)
	)
	(segment
		(start 143.542061 85.249375)
		(end 143.551777 85.206803)
		(width 0.145)
		(layer "B.Cu")
		(net 62)
	)
	(segment
		(start 144.166454 85.419143)
		(end 144.205796 85.438089)
		(width 0.145)
		(layer "B.Cu")
		(net 62)
	)
	(segment
		(start 143.91243 85.783741)
		(end 143.902714 85.741168)
		(width 0.145)
		(layer "B.Cu")
		(net 62)
	)
	(segment
		(start 144.205796 85.438089)
		(end 144.248368 85.447804)
		(width 0.145)
		(layer "B.Cu")
		(net 62)
	)
	(segment
		(start 145.2 84.6)
		(end 145.6 84.6)
		(width 0.145)
		(layer "B.Cu")
		(net 62)
	)
	(segment
		(start 143.856541 85.667688)
		(end 143.597948 85.409095)
		(width 0.145)
		(layer "B.Cu")
		(net 62)
	)
	(segment
		(start 143.87372 85.133323)
		(end 144.132314 85.391917)
		(width 0.145)
		(layer "B.Cu")
		(net 62)
	)
	(segment
		(start 143.332226 86.253368)
		(end 143.304999 86.21923)
		(width 0.145)
		(layer "B.Cu")
		(net 62)
	)
	(segment
		(start 143.332225 86.460862)
		(end 143.351171 86.42152)
		(width 0.145)
		(layer "B.Cu")
		(net 62)
	)
	(segment
		(start 143.740492 85.999346)
		(end 143.783064 85.98963)
		(width 0.145)
		(layer "B.Cu")
		(net 62)
	)
	(segment
		(start 143.902713 85.869978)
		(end 143.91243 85.827407)
		(width 0.145)
		(layer "B.Cu")
		(net 62)
	)
	(segment
		(start 143.614912 85.970685)
		(end 143.654254 85.989631)
		(width 0.145)
		(layer "B.Cu")
		(net 62)
	)
	(segment
		(start 143.800239 85.087152)
		(end 143.839581 85.106098)
		(width 0.145)
		(layer "B.Cu")
		(net 62)
	)
	(segment
		(start 143.597948 85.133323)
		(end 143.632089 85.106097)
		(width 0.145)
		(layer "B.Cu")
		(net 62)
	)
	(segment
		(start 143.597948 85.409095)
		(end 143.570722 85.374955)
		(width 0.145)
		(layer "B.Cu")
		(net 62)
	)
	(segment
		(start 142.742947 87.057053)
		(end 143.305 86.495)
		(width 0.145)
		(layer "B.Cu")
		(net 62)
	)
	(segment
		(start 143.551776 85.335613)
		(end 143.542061 85.293041)
		(width 0.145)
		(layer "B.Cu")
		(net 62)
	)
	(segment
		(start 143.351172 86.29271)
		(end 143.332226 86.253368)
		(width 0.145)
		(layer "B.Cu")
		(net 62)
	)
	(segment
		(start 151.225 82.85)
		(end 150.825 83.25)
		(width 0.145)
		(layer "F.Cu")
		(net 63)
	)
	(via
		(at 150.825 83.25)
		(size 0.45)
		(drill 0.15)
		(layers "F.Cu" "B.Cu")
		(net 63)
	)
	(segment
		(start 150.024101 84.020229)
		(end 150.024101 84.675899)
		(width 0.145)
		(layer "B.Cu")
		(net 63)
	)
	(segment
		(start 149.3 85.4)
		(end 146 85.4)
		(width 0.145)
		(layer "B.Cu")
		(net 63)
	)
	(segment
		(start 150.825 83.25)
		(end 150.79433 83.25)
		(width 0.145)
		(layer "B.Cu")
		(net 63)
	)
	(segment
		(start 150.024101 84.675899)
		(end 149.3 85.4)
		(width 0.145)
		(layer "B.Cu")
		(net 63)
	)
	(segment
		(start 146 85.4)
		(end 143.542947 87.857053)
		(width 0.145)
		(layer "B.Cu")
		(net 63)
	)
	(segment
		(start 150.79433 83.25)
		(end 150.024101 84.020229)
		(width 0.145)
		(layer "B.Cu")
		(net 63)
	)
	(segment
		(start 151.225 88.45)
		(end 151.225 90.665)
		(width 0.127)
		(layer "F.Cu")
		(net 64)
	)
	(segment
		(start 156.025 82.05)
		(end 157.95 82.05)
		(width 0.145)
		(layer "F.Cu")
		(net 65)
	)
	(segment
		(start 157.95 82.05)
		(end 158.325 82.425)
		(width 0.145)
		(layer "F.Cu")
		(net 65)
	)
	(segment
		(start 158.325 82.425)
		(end 158.325 83.09)
		(width 0.145)
		(layer "F.Cu")
		(net 65)
	)
	(segment
		(start 156.025 88.45)
		(end 157.275 88.45)
		(width 0.145)
		(layer "F.Cu")
		(net 66)
	)
	(segment
		(start 157.275 88.45)
		(end 157.525 88.7)
		(width 0.145)
		(layer "F.Cu")
		(net 66)
	)
	(segment
		(start 130.675 86.45)
		(end 130.675 85.55)
		(width 0.2)
		(layer "F.Cu")
		(net 69)
	)
	(segment
		(start 131.725 84.5)
		(end 132.875 84.5)
		(width 0.2)
		(layer "F.Cu")
		(net 69)
	)
	(segment
		(start 130.675 85.55)
		(end 131.725 84.5)
		(width 0.2)
		(layer "F.Cu")
		(net 69)
	)
	(zone
		(net 51)
		(net_name "1V1_SYS")
		(layer "F.Cu")
		(hatch edge 0.508)
		(connect_pads yes
			(clearance 0.15)
		)
		(min_thickness 0.254)
		(filled_areas_thickness no)
		(fill yes
			(thermal_gap 0.508)
			(thermal_bridge_width 0.508)
		)
		(polygon
			(pts
				(xy 128.1 99.95) (xy 124.25 100) (xy 124.25 96.5) (xy 128.1 96.5)
			)
		)
	)
	(zone
		(net 51)
		(net_name "1V1_SYS")
		(layer "F.Cu")
		(hatch edge 0.508)
		(connect_pads yes
			(clearance 0.15)
		)
		(min_thickness 0.254)
		(filled_areas_thickness no)
		(fill yes
			(thermal_gap 0.508)
			(thermal_bridge_width 0.508)
		)
		(polygon
			(pts
				(xy 137.8 91.7) (xy 136.5 91.7) (xy 136.5 86.5) (xy 137.8 86.5)
			)
		)
	)
	(zone
		(net 2)
		(net_name "VDDQ")
		(layer "F.Cu")
		(hatch edge 0.508)
		(connect_pads yes
			(clearance 0.15)
		)
		(min_thickness 0.254)
		(filled_areas_thickness no)
		(fill yes
			(thermal_gap 0.508)
			(thermal_bridge_width 0.508)
		)
		(polygon
			(pts
				(xy 141 89.85) (xy 138.6 89.85) (xy 138.6 88.55) (xy 141 88.55)
			)
		)
	)
	(zone
		(net 18)
		(net_name "VDD")
		(layer "F.Cu")
		(hatch edge 0.508)
		(connect_pads yes
			(clearance 0.15)
		)
		(min_thickness 0.254)
		(filled_areas_thickness no)
		(fill yes
			(thermal_gap 0.508)
			(thermal_bridge_width 0.508)
		)
		(polygon
			(pts
				(xy 141 87.85) (xy 138.6 87.85) (xy 138.6 86.55) (xy 141 86.55)
			)
		)
	)
	(zone
		(net 0)
		(net_name "")
		(layer "F.Mask")
		(hatch edge 0.508)
		(connect_pads
			(clearance 0.508)
		)
		(min_thickness 0.254)
		(filled_areas_thickness no)
		(fill yes
			(thermal_gap 0.508)
			(thermal_bridge_width 0.508)
		)
		(polygon
			(pts
				(xy 136.85 97.25) (xy 139.5 97.25) (xy 139.5 100.15) (xy 136.85 100.15)
			)
		)
	)
	(zone
		(net 50)
		(net_name "1V8_SYS")
		(layer "B.Cu")
		(hatch edge 0.508)
		(connect_pads yes
			(clearance 0.15)
		)
		(min_thickness 0.254)
		(filled_areas_thickness no)
		(fill yes
			(thermal_gap 0.508)
			(thermal_bridge_width 0.508)
			(smoothing fillet)
			(radius 0.5)
		)
		(polygon
			(pts
				(xy 132.175 95.315) (xy 132.175 99.95) (xy 130.125 99.95) (xy 130.125 95.32) (xy 121.03 95.33) (xy 120.975 80.45)
				(xy 136.2 80.4675) (xy 136.2 95.3325)
			)
		)
	)
	(zone
		(net 0)
		(net_name "")
		(layer "B.Mask")
		(hatch edge 0.508)
		(connect_pads
			(clearance 0.508)
		)
		(min_thickness 0.254)
		(filled_areas_thickness no)
		(fill yes
			(thermal_gap 0.508)
			(thermal_bridge_width 0.508)
		)
		(polygon
			(pts
				(xy 137.05 97.25) (xy 139.7 97.25) (xy 139.7 100.15) (xy 137.05 100.15)
			)
		)
	)
	(zone
		(net 2)
		(net_name "VDDQ")
		(layer "In1.Cu")
		(hatch edge 0.508)
		(connect_pads
			(clearance 0.15)
		)
		(min_thickness 0.254)
		(filled_areas_thickness no)
		(fill yes
			(thermal_gap 0.508)
			(thermal_bridge_width 0.508)
		)
		(polygon
			(pts
				(xy 170 100) (xy 139 100) (xy 139 70) (xy 170 70)
			)
		)
	)
	(zone
		(net 0)
		(net_name "")
		(layer "B.SilkS")
		(hatch edge 0.508)
		(connect_pads yes
			(clearance 0.125)
		)
		(min_thickness 0.125)
		(filled_areas_thickness no)
		(fill yes
			(thermal_gap 0.15)
			(thermal_bridge_width 0.151)
		)
		(polygon
			(pts
				(xy 106.24 76.85) (xy 118.97946 76.85) (xy 118.97946 72.95) (xy 106.24 72.95)
			)
		)
	)
	(zone
		(net 1)
		(net_name "GND")
		(layer "In3.Cu")
		(hatch edge 0.508)
		(connect_pads
			(clearance 0.15)
		)
		(min_thickness 0.254)
		(filled_areas_thickness no)
		(fill yes
			(thermal_gap 0.508)
			(thermal_bridge_width 0.508)
		)
		(polygon
			(pts
				(xy 169.975 99.95) (xy 99.975 99.95) (xy 99.975 69.95) (xy 169.975 69.95)
			)
		)
	)
	(zone
		(net 51)
		(net_name "1V1_SYS")
		(layer "In4.Cu")
		(hatch edge 0.508)
		(connect_pads yes
			(clearance 0.15)
		)
		(min_thickness 0.254)
		(filled_areas_thickness no)
		(fill yes
			(thermal_gap 0.508)
			(thermal_bridge_width 0.508)
		)
		(polygon
			(pts
				(xy 137.8 100) (xy 124.2 100) (xy 124.25 96.5) (xy 124.25 87.9) (xy 136.5 87.9) (xy 137.8 87.9)
			)
		)
	)
	(zone
		(net 18)
		(net_name "VDD")
		(layer "In4.Cu")
		(hatch edge 0.508)
		(connect_pads
			(clearance 0.15)
		)
		(min_thickness 0.254)
		(filled_areas_thickness no)
		(fill yes
			(thermal_gap 0.508)
			(thermal_bridge_width 0.508)
		)
		(polygon
			(pts
				(xy 170 100) (xy 139 100) (xy 139 70) (xy 170 70)
			)
		)
	)
)
